G04 ================== begin FILE IDENTIFICATION RECORD ==================*
G04 Layout Name:  15126-1b.brd*
G04 Film Name:    SE_REF_L12*
G04 File Format:  Gerber RS274X*
G04 File Origin:  Cadence Allegro 16.6-2015-S079*
G04 Origin Date:  Fri Feb 10 17:23:37 2017*
G04 *
G04 Layer:  BOARD GEOMETRY/PANEL_OUTLINE*
G04 Layer:  BOARD GEOMETRY/SE_REF_L12_TBL*
G04 Layer:  BOARD GEOMETRY/SE_REF_L12_L12*
G04 *
G04 Offset:    (0.00 0.00)*
G04 Mirror:    No*
G04 Mode:      Positive*
G04 Rotation:  0*
G04 FullContactRelief:  No*
G04 UndefLineWidth:     6.00*
G04 ================== end FILE IDENTIFICATION RECORD ====================*
%FSLAX35Y35*MOIN*%
%IR0*IPPOS*OFA0.00000B0.00000*MIA0B0*SFA1.00000B1.00000*%
%ADD10C,.02*%
%ADD11C,.006*%
%ADD12C,.0035*%
%ADD13C,.00352*%
%ADD14C,.0056*%
G75*
%LPD*%
G75*
G54D10*
G01X2026678Y631398D02*
Y527448D01*
G01D02*
X2796678D01*
G01X2026678Y562098D02*
X2796678D01*
G01X2026678Y596748D02*
X2796678D01*
G01X2026678Y631398D02*
X2796678D01*
G01X2201678D02*
Y527448D01*
G01X2481678Y631398D02*
Y527448D01*
G01X2586678Y631398D02*
Y527448D01*
G01X2796678Y631398D02*
Y527448D01*
G54D11*
G01X-17372Y-95792D02*
Y-113292D01*
G01X-22394Y-95792D02*
X-12350D01*
G01X-3584Y-113292D02*
Y-95792D01*
G01Y-104250D02*
X-2492Y-102792D01*
X-1400Y-101917D01*
X346Y-101626D01*
X1656Y-101917D01*
X3185Y-103084D01*
X3840Y-104834D01*
Y-113292D01*
G01X17628Y-101626D02*
Y-113292D01*
G01Y-96959D02*
X17191Y-96667D01*
Y-96084D01*
X17628Y-95792D01*
X18065Y-96084D01*
Y-96667D01*
X17628Y-96959D01*
G01X31853Y-111251D02*
X32945Y-112417D01*
X34473Y-113292D01*
X35783D01*
X37093Y-112709D01*
X37966Y-111834D01*
X38403Y-110668D01*
X38185Y-108917D01*
X37311Y-108042D01*
X33381Y-106292D01*
X32508Y-104250D01*
X32945Y-102792D01*
X33818Y-101917D01*
X35128Y-101626D01*
X36438Y-101917D01*
X37748Y-102792D01*
G01X67071Y-117667D02*
X68600Y-118834D01*
X70346Y-119125D01*
X71874Y-118834D01*
X73185Y-117376D01*
X74058Y-115334D01*
Y-101626D01*
G01Y-103959D02*
X73185Y-102792D01*
X71874Y-101917D01*
X70346Y-101626D01*
X68600Y-102209D01*
X67508Y-103375D01*
X66634Y-105417D01*
X66198Y-107459D01*
X66416Y-109209D01*
X67290Y-111251D01*
X68600Y-112709D01*
X70346Y-113292D01*
X71656Y-113000D01*
X73185Y-111834D01*
X74058Y-110668D01*
G01X84353Y-105417D02*
X91340D01*
X90685Y-103375D01*
X89593Y-102209D01*
X88065Y-101626D01*
X86536Y-101917D01*
X85226Y-102792D01*
X84353Y-104834D01*
X83916Y-106584D01*
Y-108334D01*
X84353Y-110084D01*
X85445Y-111834D01*
X86755Y-113000D01*
X88283Y-113292D01*
X89811Y-112709D01*
X91340Y-110959D01*
G01X102071Y-113292D02*
Y-101626D01*
G01Y-103959D02*
X103163Y-102792D01*
X104255Y-101917D01*
X105783Y-101626D01*
X106874Y-101917D01*
X108185Y-102792D01*
G01X118698Y-113292D02*
Y-95792D01*
G01Y-104542D02*
X119790Y-102792D01*
X121100Y-101917D01*
X122410Y-101626D01*
X124374Y-102209D01*
X125685Y-103375D01*
X126558Y-105417D01*
Y-107750D01*
X126121Y-110084D01*
X125248Y-111834D01*
X123720Y-113000D01*
X122410Y-113292D01*
X121100Y-113000D01*
X119790Y-112126D01*
X118698Y-110668D01*
G01X136853Y-105417D02*
X143840D01*
X143185Y-103375D01*
X142093Y-102209D01*
X140565Y-101626D01*
X139036Y-101917D01*
X137726Y-102792D01*
X136853Y-104834D01*
X136416Y-106584D01*
Y-108334D01*
X136853Y-110084D01*
X137945Y-111834D01*
X139255Y-113000D01*
X140783Y-113292D01*
X142311Y-112709D01*
X143840Y-110959D01*
G01X154571Y-113292D02*
Y-101626D01*
G01Y-103959D02*
X155663Y-102792D01*
X156755Y-101917D01*
X158283Y-101626D01*
X159374Y-101917D01*
X160685Y-102792D01*
G01X192628Y-101626D02*
Y-113292D01*
G01Y-96959D02*
X192191Y-96667D01*
Y-96084D01*
X192628Y-95792D01*
X193065Y-96084D01*
Y-96667D01*
X192628Y-96959D01*
G01X206853Y-111251D02*
X207945Y-112417D01*
X209473Y-113292D01*
X210783D01*
X212093Y-112709D01*
X212966Y-111834D01*
X213403Y-110668D01*
X213185Y-108917D01*
X212311Y-108042D01*
X208381Y-106292D01*
X207508Y-104250D01*
X207945Y-102792D01*
X208818Y-101917D01*
X210128Y-101626D01*
X211438Y-101917D01*
X212748Y-102792D01*
G01X241634Y-117667D02*
X243163Y-118834D01*
X244473Y-119125D01*
X246220Y-118542D01*
X247530Y-117084D01*
X248185Y-114458D01*
Y-101626D01*
G01Y-96959D02*
X247748Y-96667D01*
Y-96084D01*
X248185Y-95792D01*
X248621Y-96084D01*
Y-96667D01*
X248185Y-96959D01*
G01X258916Y-101626D02*
Y-109792D01*
X259790Y-111834D01*
X261100Y-113000D01*
X262628Y-113292D01*
X264156Y-113000D01*
X265466Y-111834D01*
X266340Y-109792D01*
G01Y-113292D02*
Y-101626D01*
G01X276853Y-111251D02*
X277945Y-112417D01*
X279473Y-113292D01*
X280783D01*
X282093Y-112709D01*
X282966Y-111834D01*
X283403Y-110668D01*
X283185Y-108917D01*
X282311Y-108042D01*
X278381Y-106292D01*
X277508Y-104250D01*
X277945Y-102792D01*
X278818Y-101917D01*
X280128Y-101626D01*
X281438Y-101917D01*
X282748Y-102792D01*
G01X297628Y-95792D02*
Y-113292D01*
G01X294571Y-101626D02*
X300685D01*
G01X331318Y-113292D02*
Y-98417D01*
X331755Y-96959D01*
X332628Y-96084D01*
X333938Y-95792D01*
X335248Y-96375D01*
X335903Y-97834D01*
G01X333283Y-102792D02*
X328916D01*
G01X350128Y-113292D02*
X348818Y-113000D01*
X347508Y-111834D01*
X346634Y-109792D01*
X346198Y-107459D01*
X346634Y-105125D01*
X347508Y-103084D01*
X348818Y-101917D01*
X350128Y-101626D01*
X351438Y-101917D01*
X352748Y-103084D01*
X353621Y-105125D01*
X353840Y-107459D01*
X353621Y-109792D01*
X352748Y-111834D01*
X351438Y-113000D01*
X350128Y-113292D01*
G01X364571D02*
Y-101626D01*
G01Y-103959D02*
X365663Y-102792D01*
X366755Y-101917D01*
X368283Y-101626D01*
X369374Y-101917D01*
X370685Y-102792D01*
G01X398043Y-118542D02*
X399353Y-119125D01*
X401100Y-118542D01*
X402191Y-117376D01*
X403065Y-115917D01*
X404374Y-111251D01*
X407213Y-101626D01*
G01X400226D02*
X404374Y-111251D01*
G01X420128Y-113292D02*
X418818Y-113000D01*
X417508Y-111834D01*
X416634Y-109792D01*
X416198Y-107459D01*
X416634Y-105125D01*
X417508Y-103084D01*
X418818Y-101917D01*
X420128Y-101626D01*
X421438Y-101917D01*
X422748Y-103084D01*
X423621Y-105125D01*
X423840Y-107459D01*
X423621Y-109792D01*
X422748Y-111834D01*
X421438Y-113000D01*
X420128Y-113292D01*
G01X433916Y-101626D02*
Y-109792D01*
X434790Y-111834D01*
X436100Y-113000D01*
X437628Y-113292D01*
X439156Y-113000D01*
X440466Y-111834D01*
X441340Y-109792D01*
G01Y-113292D02*
Y-101626D01*
G01X452071Y-113292D02*
Y-101626D01*
G01Y-103959D02*
X453163Y-102792D01*
X454255Y-101917D01*
X455783Y-101626D01*
X456874Y-101917D01*
X458185Y-102792D01*
G01X487071Y-113292D02*
Y-101626D01*
G01Y-103959D02*
X488163Y-102792D01*
X489255Y-101917D01*
X490783Y-101626D01*
X491874Y-101917D01*
X493185Y-102792D01*
G01X504353Y-105417D02*
X511340D01*
X510685Y-103375D01*
X509593Y-102209D01*
X508065Y-101626D01*
X506536Y-101917D01*
X505226Y-102792D01*
X504353Y-104834D01*
X503916Y-106584D01*
Y-108334D01*
X504353Y-110084D01*
X505445Y-111834D01*
X506755Y-113000D01*
X508283Y-113292D01*
X509811Y-112709D01*
X511340Y-110959D01*
G01X523818Y-113292D02*
Y-98417D01*
X524255Y-96959D01*
X525128Y-96084D01*
X526438Y-95792D01*
X527748Y-96375D01*
X528403Y-97834D01*
G01X525783Y-102792D02*
X521416D01*
G01X539353Y-105417D02*
X546340D01*
X545685Y-103375D01*
X544593Y-102209D01*
X543065Y-101626D01*
X541536Y-101917D01*
X540226Y-102792D01*
X539353Y-104834D01*
X538916Y-106584D01*
Y-108334D01*
X539353Y-110084D01*
X540445Y-111834D01*
X541755Y-113000D01*
X543283Y-113292D01*
X544811Y-112709D01*
X546340Y-110959D01*
G01X557071Y-113292D02*
Y-101626D01*
G01Y-103959D02*
X558163Y-102792D01*
X559255Y-101917D01*
X560783Y-101626D01*
X561874Y-101917D01*
X563185Y-102792D01*
G01X574353Y-105417D02*
X581340D01*
X580685Y-103375D01*
X579593Y-102209D01*
X578065Y-101626D01*
X576536Y-101917D01*
X575226Y-102792D01*
X574353Y-104834D01*
X573916Y-106584D01*
Y-108334D01*
X574353Y-110084D01*
X575445Y-111834D01*
X576755Y-113000D01*
X578283Y-113292D01*
X579811Y-112709D01*
X581340Y-110959D01*
G01X591416Y-113292D02*
Y-101626D01*
G01Y-104542D02*
X592290Y-103084D01*
X593600Y-101917D01*
X595346Y-101626D01*
X596874Y-101917D01*
X598185Y-103084D01*
X598840Y-105125D01*
Y-113292D01*
G01X616121Y-103084D02*
X614593Y-101917D01*
X613283Y-101626D01*
X611536Y-102209D01*
X610226Y-103375D01*
X609353Y-105417D01*
X609134Y-107459D01*
X609353Y-109501D01*
X610226Y-111251D01*
X611536Y-112709D01*
X613283Y-113292D01*
X614811Y-112709D01*
X616121Y-111542D01*
G01X626853Y-105417D02*
X633840D01*
X633185Y-103375D01*
X632093Y-102209D01*
X630565Y-101626D01*
X629036Y-101917D01*
X627726Y-102792D01*
X626853Y-104834D01*
X626416Y-106584D01*
Y-108334D01*
X626853Y-110084D01*
X627945Y-111834D01*
X629255Y-113000D01*
X630783Y-113292D01*
X632311Y-112709D01*
X633840Y-110959D01*
G01X665128Y-95792D02*
Y-113292D01*
G01X662071Y-101626D02*
X668185D01*
G01X682628Y-113292D02*
X681318Y-113000D01*
X680008Y-111834D01*
X679134Y-109792D01*
X678698Y-107459D01*
X679134Y-105125D01*
X680008Y-103084D01*
X681318Y-101917D01*
X682628Y-101626D01*
X683938Y-101917D01*
X685248Y-103084D01*
X686121Y-105125D01*
X686340Y-107459D01*
X686121Y-109792D01*
X685248Y-111834D01*
X683938Y-113000D01*
X682628Y-113292D01*
G01X716318D02*
Y-98417D01*
X716755Y-96959D01*
X717628Y-96084D01*
X718938Y-95792D01*
X720248Y-96375D01*
X720903Y-97834D01*
G01X718283Y-102792D02*
X713916D01*
G01X735128Y-101626D02*
Y-113292D01*
G01Y-96959D02*
X734691Y-96667D01*
Y-96084D01*
X735128Y-95792D01*
X735565Y-96084D01*
Y-96667D01*
X735128Y-96959D01*
G01X748916Y-113292D02*
Y-101626D01*
G01Y-104542D02*
X749790Y-103084D01*
X751100Y-101917D01*
X752846Y-101626D01*
X754374Y-101917D01*
X755685Y-103084D01*
X756340Y-105125D01*
Y-113292D01*
G01X774058Y-95792D02*
Y-113292D01*
G01Y-110668D02*
X773185Y-112126D01*
X771874Y-113000D01*
X770346Y-113292D01*
X768600Y-112709D01*
X767290Y-111251D01*
X766416Y-109501D01*
X766198Y-107459D01*
X766416Y-105417D01*
X767290Y-103667D01*
X768600Y-102209D01*
X770346Y-101626D01*
X771874Y-101917D01*
X772966Y-102501D01*
X774058Y-103667D01*
G01X805128Y-95792D02*
Y-113292D01*
G01X802071Y-101626D02*
X808185D01*
G01X818916Y-113292D02*
Y-95792D01*
G01Y-104250D02*
X820008Y-102792D01*
X821100Y-101917D01*
X822846Y-101626D01*
X824156Y-101917D01*
X825685Y-103084D01*
X826340Y-104834D01*
Y-113292D01*
G01X836853Y-105417D02*
X843840D01*
X843185Y-103375D01*
X842093Y-102209D01*
X840565Y-101626D01*
X839036Y-101917D01*
X837726Y-102792D01*
X836853Y-104834D01*
X836416Y-106584D01*
Y-108334D01*
X836853Y-110084D01*
X837945Y-111834D01*
X839255Y-113000D01*
X840783Y-113292D01*
X842311Y-112709D01*
X843840Y-110959D01*
G01X870543D02*
X872290Y-112417D01*
X874255Y-113292D01*
X876001D01*
X877748Y-112417D01*
X879058Y-110959D01*
X879713Y-108917D01*
X879276Y-106876D01*
X878185Y-105125D01*
X876220Y-103959D01*
X873600Y-103375D01*
X872071Y-102209D01*
X871416Y-100167D01*
X871853Y-98125D01*
X872945Y-96667D01*
X874473Y-95792D01*
X876001D01*
X877530Y-96375D01*
X878840Y-97834D01*
G01X896995Y-113292D02*
X888261D01*
Y-95792D01*
X896995D01*
G01X893501Y-104250D02*
X888261D01*
G01X927628Y-101626D02*
Y-113292D01*
G01Y-96959D02*
X927191Y-96667D01*
Y-96084D01*
X927628Y-95792D01*
X928065Y-96084D01*
Y-96667D01*
X927628Y-96959D01*
G01X938578Y-113292D02*
Y-101626D01*
G01Y-104834D02*
X939233Y-103375D01*
X940325Y-102209D01*
X941853Y-101626D01*
X943381Y-102209D01*
X944473Y-103375D01*
X945128Y-104834D01*
Y-113292D01*
G01Y-104834D02*
X945783Y-103375D01*
X946874Y-102209D01*
X948403Y-101626D01*
X949931Y-102209D01*
X951023Y-103375D01*
X951678Y-105125D01*
Y-113292D01*
G01X958698Y-119125D02*
Y-101626D01*
G01Y-104250D02*
X959790Y-102792D01*
X960881Y-101917D01*
X962628Y-101626D01*
X964156Y-101917D01*
X965685Y-103375D01*
X966340Y-105417D01*
X966558Y-107459D01*
X966340Y-109501D01*
X965685Y-111542D01*
X964374Y-112709D01*
X962628Y-113292D01*
X961100Y-113000D01*
X959571Y-112126D01*
X958698Y-110959D01*
G01X976853Y-105417D02*
X983840D01*
X983185Y-103375D01*
X982093Y-102209D01*
X980565Y-101626D01*
X979036Y-101917D01*
X977726Y-102792D01*
X976853Y-104834D01*
X976416Y-106584D01*
Y-108334D01*
X976853Y-110084D01*
X977945Y-111834D01*
X979255Y-113000D01*
X980783Y-113292D01*
X982311Y-112709D01*
X983840Y-110959D01*
G01X1001558Y-95792D02*
Y-113292D01*
G01Y-110668D02*
X1000685Y-112126D01*
X999374Y-113000D01*
X997846Y-113292D01*
X996100Y-112709D01*
X994790Y-111251D01*
X993916Y-109501D01*
X993698Y-107459D01*
X993916Y-105417D01*
X994790Y-103667D01*
X996100Y-102209D01*
X997846Y-101626D01*
X999374Y-101917D01*
X1000466Y-102501D01*
X1001558Y-103667D01*
G01X1019058Y-113292D02*
Y-101626D01*
G01Y-103667D02*
X1018185Y-102501D01*
X1016874Y-101917D01*
X1015346Y-101626D01*
X1013818Y-102209D01*
X1012508Y-103375D01*
X1011634Y-105125D01*
X1011198Y-107459D01*
X1011634Y-109792D01*
X1012508Y-111542D01*
X1013818Y-112709D01*
X1015346Y-113292D01*
X1016874Y-113000D01*
X1018185Y-112126D01*
X1019058Y-110959D01*
G01X1028916Y-113292D02*
Y-101626D01*
G01Y-104542D02*
X1029790Y-103084D01*
X1031100Y-101917D01*
X1032846Y-101626D01*
X1034374Y-101917D01*
X1035685Y-103084D01*
X1036340Y-105125D01*
Y-113292D01*
G01X1053621Y-103084D02*
X1052093Y-101917D01*
X1050783Y-101626D01*
X1049036Y-102209D01*
X1047726Y-103375D01*
X1046853Y-105417D01*
X1046634Y-107459D01*
X1046853Y-109501D01*
X1047726Y-111251D01*
X1049036Y-112709D01*
X1050783Y-113292D01*
X1052311Y-112709D01*
X1053621Y-111542D01*
G01X1064353Y-105417D02*
X1071340D01*
X1070685Y-103375D01*
X1069593Y-102209D01*
X1068065Y-101626D01*
X1066536Y-101917D01*
X1065226Y-102792D01*
X1064353Y-104834D01*
X1063916Y-106584D01*
Y-108334D01*
X1064353Y-110084D01*
X1065445Y-111834D01*
X1066755Y-113000D01*
X1068283Y-113292D01*
X1069811Y-112709D01*
X1071340Y-110959D01*
G01X1102628Y-95792D02*
Y-113292D01*
G01X1099571Y-101626D02*
X1105685D01*
G01X1117071Y-113292D02*
Y-101626D01*
G01Y-103959D02*
X1118163Y-102792D01*
X1119255Y-101917D01*
X1120783Y-101626D01*
X1121874Y-101917D01*
X1123185Y-102792D01*
G01X1141558Y-113292D02*
Y-101626D01*
G01Y-103667D02*
X1140685Y-102501D01*
X1139374Y-101917D01*
X1137846Y-101626D01*
X1136318Y-102209D01*
X1135008Y-103375D01*
X1134134Y-105125D01*
X1133698Y-107459D01*
X1134134Y-109792D01*
X1135008Y-111542D01*
X1136318Y-112709D01*
X1137846Y-113292D01*
X1139374Y-113000D01*
X1140685Y-112126D01*
X1141558Y-110959D01*
G01X1158621Y-103084D02*
X1157093Y-101917D01*
X1155783Y-101626D01*
X1154036Y-102209D01*
X1152726Y-103375D01*
X1151853Y-105417D01*
X1151634Y-107459D01*
X1151853Y-109501D01*
X1152726Y-111251D01*
X1154036Y-112709D01*
X1155783Y-113292D01*
X1157311Y-112709D01*
X1158621Y-111542D01*
G01X1169353Y-105417D02*
X1176340D01*
X1175685Y-103375D01*
X1174593Y-102209D01*
X1173065Y-101626D01*
X1171536Y-101917D01*
X1170226Y-102792D01*
X1169353Y-104834D01*
X1168916Y-106584D01*
Y-108334D01*
X1169353Y-110084D01*
X1170445Y-111834D01*
X1171755Y-113000D01*
X1173283Y-113292D01*
X1174811Y-112709D01*
X1176340Y-110959D01*
G01X1186853Y-111251D02*
X1187945Y-112417D01*
X1189473Y-113292D01*
X1190783D01*
X1192093Y-112709D01*
X1192966Y-111834D01*
X1193403Y-110668D01*
X1193185Y-108917D01*
X1192311Y-108042D01*
X1188381Y-106292D01*
X1187508Y-104250D01*
X1187945Y-102792D01*
X1188818Y-101917D01*
X1190128Y-101626D01*
X1191438Y-101917D01*
X1192748Y-102792D01*
G01X1225128Y-101626D02*
Y-113292D01*
G01Y-96959D02*
X1224691Y-96667D01*
Y-96084D01*
X1225128Y-95792D01*
X1225565Y-96084D01*
Y-96667D01*
X1225128Y-96959D01*
G01X1238916Y-113292D02*
Y-101626D01*
G01Y-104542D02*
X1239790Y-103084D01*
X1241100Y-101917D01*
X1242846Y-101626D01*
X1244374Y-101917D01*
X1245685Y-103084D01*
X1246340Y-105125D01*
Y-113292D01*
G01X1277628D02*
Y-95792D01*
G01X1299058Y-113292D02*
Y-101626D01*
G01Y-103667D02*
X1298185Y-102501D01*
X1296874Y-101917D01*
X1295346Y-101626D01*
X1293818Y-102209D01*
X1292508Y-103375D01*
X1291634Y-105125D01*
X1291198Y-107459D01*
X1291634Y-109792D01*
X1292508Y-111542D01*
X1293818Y-112709D01*
X1295346Y-113292D01*
X1296874Y-113000D01*
X1298185Y-112126D01*
X1299058Y-110959D01*
G01X1308043Y-118542D02*
X1309353Y-119125D01*
X1311100Y-118542D01*
X1312191Y-117376D01*
X1313065Y-115917D01*
X1314374Y-111251D01*
X1317213Y-101626D01*
G01X1310226D02*
X1314374Y-111251D01*
G01X1326853Y-105417D02*
X1333840D01*
X1333185Y-103375D01*
X1332093Y-102209D01*
X1330565Y-101626D01*
X1329036Y-101917D01*
X1327726Y-102792D01*
X1326853Y-104834D01*
X1326416Y-106584D01*
Y-108334D01*
X1326853Y-110084D01*
X1327945Y-111834D01*
X1329255Y-113000D01*
X1330783Y-113292D01*
X1332311Y-112709D01*
X1333840Y-110959D01*
G01X1344571Y-113292D02*
Y-101626D01*
G01Y-103959D02*
X1345663Y-102792D01*
X1346755Y-101917D01*
X1348283Y-101626D01*
X1349374Y-101917D01*
X1350685Y-102792D01*
G01X1378261Y-95792D02*
Y-113292D01*
X1386995D01*
G01X1400128D02*
Y-95792D01*
X1397508Y-99292D01*
G01Y-113292D02*
X1402748D01*
G01X1413480Y-98709D02*
X1414790Y-96959D01*
X1416318Y-96084D01*
X1418065Y-95792D01*
X1420248Y-96375D01*
X1421776Y-97834D01*
X1422213Y-99583D01*
X1421995Y-101334D01*
X1421121Y-102792D01*
X1416755Y-105709D01*
X1414790Y-107750D01*
X1413480Y-110668D01*
X1413043Y-113292D01*
X1422213D01*
G01X1435128Y-113875D02*
X1434691Y-113584D01*
Y-113000D01*
X1435128Y-112709D01*
X1435565Y-113000D01*
Y-113584D01*
X1435128Y-113875D01*
G01X2083125Y539822D02*
X2084434Y538364D01*
X2085963Y537490D01*
X2087928Y537198D01*
X2089893Y537781D01*
X2091421Y538948D01*
X2092513Y540989D01*
X2092731Y543323D01*
X2092295Y545656D01*
X2091203Y547115D01*
X2089674Y548281D01*
X2088146Y548573D01*
X2086618Y548281D01*
X2084653Y547115D01*
X2085308Y554698D01*
X2091203D01*
G01X2105428D02*
X2103681Y554115D01*
X2102371Y552656D01*
X2101498Y550907D01*
X2100843Y548573D01*
X2100625Y545948D01*
X2100843Y543323D01*
X2101498Y540989D01*
X2102371Y539239D01*
X2103681Y537781D01*
X2105428Y537198D01*
X2107174Y537781D01*
X2108485Y539239D01*
X2109358Y540989D01*
X2110013Y543323D01*
X2110231Y545948D01*
X2110013Y548573D01*
X2109358Y550907D01*
X2108485Y552656D01*
X2107174Y554115D01*
X2105428Y554698D01*
G01X2122928Y536615D02*
X2122491Y536906D01*
Y537490D01*
X2122928Y537781D01*
X2123365Y537490D01*
Y536906D01*
X2122928Y536615D01*
G01X2140428Y554698D02*
X2138681Y554115D01*
X2137371Y552656D01*
X2136498Y550907D01*
X2135843Y548573D01*
X2135625Y545948D01*
X2135843Y543323D01*
X2136498Y540989D01*
X2137371Y539239D01*
X2138681Y537781D01*
X2140428Y537198D01*
X2142174Y537781D01*
X2143485Y539239D01*
X2144358Y540989D01*
X2145013Y543323D01*
X2145231Y545948D01*
X2145013Y548573D01*
X2144358Y550907D01*
X2143485Y552656D01*
X2142174Y554115D01*
X2140428Y554698D01*
G01X2090548Y571848D02*
Y589348D01*
X2082469Y576806D01*
X2093387D01*
G01X2105428Y589348D02*
X2103681Y588765D01*
X2102371Y587306D01*
X2101498Y585557D01*
X2100843Y583223D01*
X2100625Y580598D01*
X2100843Y577973D01*
X2101498Y575639D01*
X2102371Y573889D01*
X2103681Y572431D01*
X2105428Y571848D01*
X2107174Y572431D01*
X2108485Y573889D01*
X2109358Y575639D01*
X2110013Y577973D01*
X2110231Y580598D01*
X2110013Y583223D01*
X2109358Y585557D01*
X2108485Y587306D01*
X2107174Y588765D01*
X2105428Y589348D01*
G01X2122928Y571265D02*
X2122491Y571556D01*
Y572140D01*
X2122928Y572431D01*
X2123365Y572140D01*
Y571556D01*
X2122928Y571265D01*
G01X2140428Y589348D02*
X2138681Y588765D01*
X2137371Y587306D01*
X2136498Y585557D01*
X2135843Y583223D01*
X2135625Y580598D01*
X2135843Y577973D01*
X2136498Y575639D01*
X2137371Y573889D01*
X2138681Y572431D01*
X2140428Y571848D01*
X2142174Y572431D01*
X2143485Y573889D01*
X2144358Y575639D01*
X2145013Y577973D01*
X2145231Y580598D01*
X2145013Y583223D01*
X2144358Y585557D01*
X2143485Y587306D01*
X2142174Y588765D01*
X2140428Y589348D01*
G01X2050308Y623998D02*
X2055548D01*
G01X2052928D02*
Y606498D01*
G01X2050308D02*
X2055548D01*
G01X2064751D02*
Y623998D01*
X2070428Y609415D01*
X2076105Y623998D01*
Y606498D01*
G01X2083561D02*
Y623998D01*
X2088801D01*
X2090548Y623123D01*
X2091858Y621081D01*
X2092295Y618748D01*
X2091858Y616415D01*
X2090766Y614665D01*
X2088801Y613789D01*
X2083561D01*
G01X2104336Y600665D02*
X2102153Y603581D01*
X2101061Y606498D01*
Y618164D01*
X2102153Y621081D01*
X2104336Y623998D01*
G01X2122928Y606498D02*
X2121181Y606790D01*
X2119653Y607956D01*
X2118343Y609706D01*
X2117469Y611748D01*
X2117033Y614081D01*
Y616415D01*
X2117469Y618748D01*
X2118343Y620790D01*
X2119653Y622539D01*
X2121181Y623706D01*
X2122928Y623998D01*
X2124674Y623706D01*
X2126203Y622539D01*
X2127513Y620790D01*
X2128387Y618748D01*
X2128823Y616415D01*
Y614081D01*
X2128387Y611748D01*
X2127513Y609706D01*
X2126203Y607956D01*
X2124674Y606790D01*
X2122928Y606498D01*
G01X2136716D02*
Y623998D01*
G01Y615540D02*
X2137808Y616998D01*
X2138900Y617873D01*
X2140646Y618164D01*
X2141956Y617873D01*
X2143485Y616706D01*
X2144140Y614956D01*
Y606498D01*
G01X2151378D02*
Y618164D01*
G01Y614956D02*
X2152033Y616415D01*
X2153125Y617581D01*
X2154653Y618164D01*
X2156181Y617581D01*
X2157273Y616415D01*
X2157928Y614956D01*
Y606498D01*
G01Y614956D02*
X2158583Y616415D01*
X2159674Y617581D01*
X2161203Y618164D01*
X2162731Y617581D01*
X2163823Y616415D01*
X2164478Y614665D01*
Y606498D01*
G01X2176520Y600665D02*
X2178703Y603581D01*
X2179795Y606498D01*
Y618164D01*
X2178703Y621081D01*
X2176520Y623998D01*
G01X2028643Y643481D02*
X2030390Y642023D01*
X2032355Y641148D01*
X2034101D01*
X2035848Y642023D01*
X2037158Y643481D01*
X2037813Y645523D01*
X2037376Y647564D01*
X2036285Y649315D01*
X2034320Y650481D01*
X2031700Y651065D01*
X2030171Y652231D01*
X2029516Y654273D01*
X2029953Y656315D01*
X2031045Y657773D01*
X2032573Y658648D01*
X2034101D01*
X2035630Y658065D01*
X2036940Y656606D01*
G01X2055095Y641148D02*
X2046361D01*
Y658648D01*
X2055095D01*
G01X2051601Y650190D02*
X2046361D01*
G01X2083108Y658648D02*
X2088348D01*
G01X2085728D02*
Y641148D01*
G01X2083108D02*
X2088348D01*
G01X2097551D02*
Y658648D01*
X2103228Y644065D01*
X2108905Y658648D01*
Y641148D01*
G01X2116361D02*
Y658648D01*
X2121601D01*
X2123348Y657773D01*
X2124658Y655731D01*
X2125095Y653398D01*
X2124658Y651065D01*
X2123566Y649315D01*
X2121601Y648439D01*
X2116361D01*
G01X2142595Y641148D02*
X2133861D01*
Y658648D01*
X2142595D01*
G01X2139101Y650190D02*
X2133861D01*
G01X2150925Y641148D02*
Y658648D01*
X2155291D01*
X2157038Y657773D01*
X2158348Y656606D01*
X2159440Y654857D01*
X2160313Y652814D01*
X2160531Y649898D01*
X2160313Y646981D01*
X2159440Y644939D01*
X2158348Y643189D01*
X2157038Y642023D01*
X2155291Y641148D01*
X2150925D01*
G01X2167769D02*
X2173228Y658648D01*
X2178687Y641148D01*
G01X2176721Y647273D02*
X2169734D01*
G01X2185706Y641148D02*
Y658648D01*
X2195750Y641148D01*
Y658648D01*
G01X2213031Y657189D02*
X2211721Y658065D01*
X2210193Y658648D01*
X2208446D01*
X2206481Y657773D01*
X2204953Y656315D01*
X2203861Y654564D01*
X2202988Y651648D01*
X2202769Y649023D01*
X2203206Y646398D01*
X2203861Y644648D01*
X2205171Y642898D01*
X2206700Y641731D01*
X2208228Y641148D01*
X2209756D01*
X2211285Y641731D01*
X2212595Y642606D01*
X2213687Y643772D01*
G01X2230095Y641148D02*
X2221361D01*
Y658648D01*
X2230095D01*
G01X2226601Y650190D02*
X2221361D01*
G01X2260728Y658648D02*
Y641148D01*
G01X2255706Y658648D02*
X2265750D01*
G01X2272769Y641148D02*
X2278228Y658648D01*
X2283687Y641148D01*
G01X2281721Y647273D02*
X2274734D01*
G01X2297474Y650481D02*
X2298348Y651356D01*
X2299003Y652814D01*
X2299440Y654857D01*
X2299003Y656606D01*
X2298130Y657773D01*
X2296601Y658648D01*
X2290706D01*
Y641148D01*
X2297911D01*
X2299440Y642314D01*
X2300313Y644065D01*
X2300750Y646106D01*
X2300313Y648148D01*
X2299003Y649898D01*
X2297474Y650481D01*
X2290706D01*
G01X2308861Y658648D02*
Y641148D01*
X2317595D01*
G01X2335095D02*
X2326361D01*
Y658648D01*
X2335095D01*
G01X2331601Y650190D02*
X2326361D01*
G01X2348228Y640565D02*
X2347791Y640856D01*
Y641440D01*
X2348228Y641731D01*
X2348665Y641440D01*
Y640856D01*
X2348228Y640565D01*
G01Y648439D02*
X2347791Y648731D01*
Y649315D01*
X2348228Y649606D01*
X2348665Y649315D01*
Y648731D01*
X2348228Y648439D01*
G01X2378861Y658648D02*
Y641148D01*
X2387595D01*
G01X2400728D02*
Y658648D01*
X2398108Y655148D01*
G01Y641148D02*
X2403348D01*
G01X2414080Y655731D02*
X2415390Y657481D01*
X2416918Y658356D01*
X2418665Y658648D01*
X2420848Y658065D01*
X2422376Y656606D01*
X2422813Y654857D01*
X2422595Y653106D01*
X2421721Y651648D01*
X2417355Y648731D01*
X2415390Y646690D01*
X2414080Y643772D01*
X2413643Y641148D01*
X2422813D01*
G01X2247628Y623998D02*
X2250684Y606498D01*
X2254178Y623998D01*
X2257671Y606498D01*
X2260728Y623998D01*
G01X2269058D02*
X2274298D01*
G01X2271678D02*
Y606498D01*
G01X2269058D02*
X2274298D01*
G01X2284375D02*
Y623998D01*
X2288741D01*
X2290488Y623123D01*
X2291798Y621956D01*
X2292890Y620207D01*
X2293763Y618164D01*
X2293981Y615248D01*
X2293763Y612331D01*
X2292890Y610289D01*
X2291798Y608539D01*
X2290488Y607373D01*
X2288741Y606498D01*
X2284375D01*
G01X2306678Y623998D02*
Y606498D01*
G01X2301656Y623998D02*
X2311700D01*
G01X2319593Y606498D02*
Y623998D01*
G01X2328763D02*
Y606498D01*
G01Y615248D02*
X2319593D01*
G01X2340586Y600665D02*
X2338403Y603581D01*
X2337311Y606498D01*
Y618164D01*
X2338403Y621081D01*
X2340586Y623998D01*
G01X2352628Y606498D02*
Y618164D01*
G01Y614956D02*
X2353283Y616415D01*
X2354375Y617581D01*
X2355903Y618164D01*
X2357431Y617581D01*
X2358523Y616415D01*
X2359178Y614956D01*
Y606498D01*
G01Y614956D02*
X2359833Y616415D01*
X2360924Y617581D01*
X2362453Y618164D01*
X2363981Y617581D01*
X2365073Y616415D01*
X2365728Y614665D01*
Y606498D01*
G01X2376678Y618164D02*
Y606498D01*
G01Y622831D02*
X2376241Y623123D01*
Y623706D01*
X2376678Y623998D01*
X2377115Y623706D01*
Y623123D01*
X2376678Y622831D01*
G01X2394178Y606498D02*
Y623998D01*
G01X2408403Y608539D02*
X2409495Y607373D01*
X2411023Y606498D01*
X2412333D01*
X2413643Y607081D01*
X2414516Y607956D01*
X2414953Y609122D01*
X2414735Y610873D01*
X2413861Y611748D01*
X2409931Y613498D01*
X2409058Y615540D01*
X2409495Y616998D01*
X2410368Y617873D01*
X2411678Y618164D01*
X2412988Y617873D01*
X2414298Y616998D01*
G01X2430270Y600665D02*
X2432453Y603581D01*
X2433545Y606498D01*
Y618164D01*
X2432453Y621081D01*
X2430270Y623998D01*
G01X2310625Y540698D02*
X2311934Y538656D01*
X2313681Y537490D01*
X2315646Y537198D01*
X2317393Y537490D01*
X2319140Y538948D01*
X2320231Y540698D01*
X2320450Y542448D01*
X2320013Y544489D01*
X2318485Y545948D01*
X2316956Y546531D01*
X2314991D01*
G01X2316956D02*
X2318266Y547406D01*
X2319358Y548864D01*
X2319795Y550614D01*
X2319358Y552365D01*
X2318266Y553823D01*
X2316301Y554698D01*
X2314336Y554406D01*
X2312371Y553239D01*
G01X2332928Y536615D02*
X2332491Y536906D01*
Y537490D01*
X2332928Y537781D01*
X2333365Y537490D01*
Y536906D01*
X2332928Y536615D01*
G01X2345625Y539822D02*
X2346934Y538364D01*
X2348463Y537490D01*
X2350428Y537198D01*
X2352393Y537781D01*
X2353921Y538948D01*
X2355013Y540989D01*
X2355231Y543323D01*
X2354795Y545656D01*
X2353703Y547115D01*
X2352174Y548281D01*
X2350646Y548573D01*
X2349118Y548281D01*
X2347153Y547115D01*
X2347808Y554698D01*
X2353703D01*
G01X2363780Y551781D02*
X2365090Y553531D01*
X2366618Y554406D01*
X2368365Y554698D01*
X2370548Y554115D01*
X2372076Y552656D01*
X2372513Y550907D01*
X2372295Y549156D01*
X2371421Y547698D01*
X2367055Y544781D01*
X2365090Y542740D01*
X2363780Y539822D01*
X2363343Y537198D01*
X2372513D01*
G01X2319375Y574472D02*
X2320684Y573014D01*
X2322213Y572140D01*
X2324178Y571848D01*
X2326143Y572431D01*
X2327671Y573598D01*
X2328763Y575639D01*
X2328981Y577973D01*
X2328545Y580306D01*
X2327453Y581765D01*
X2325924Y582931D01*
X2324396Y583223D01*
X2322868Y582931D01*
X2320903Y581765D01*
X2321558Y589348D01*
X2327453D01*
G01X2341678Y571265D02*
X2341241Y571556D01*
Y572140D01*
X2341678Y572431D01*
X2342115Y572140D01*
Y571556D01*
X2341678Y571265D01*
G01X2355030Y579139D02*
X2356558Y581181D01*
X2357868Y582348D01*
X2359615Y582931D01*
X2361143Y582348D01*
X2362235Y581181D01*
X2363108Y579431D01*
X2363326Y577390D01*
X2363108Y575639D01*
X2362235Y573889D01*
X2360924Y572431D01*
X2359396Y571848D01*
X2357650Y572431D01*
X2356121Y574181D01*
X2355248Y576806D01*
X2355030Y579723D01*
X2355466Y583514D01*
X2356121Y585557D01*
X2357213Y587598D01*
X2358741Y589056D01*
X2360270Y589348D01*
X2361798Y588765D01*
X2362890Y587306D01*
G01X2507928Y623998D02*
Y606498D01*
G01X2502906Y623998D02*
X2512950D01*
G01X2525428Y606498D02*
Y614373D01*
X2521061Y623998D01*
G01X2529795D02*
X2525428Y614373D01*
G01X2538561Y606498D02*
Y623998D01*
X2543801D01*
X2545548Y623123D01*
X2546858Y621081D01*
X2547295Y618748D01*
X2546858Y616415D01*
X2545766Y614665D01*
X2543801Y613789D01*
X2538561D01*
G01X2564795Y606498D02*
X2556061D01*
Y623998D01*
X2564795D01*
G01X2561301Y615540D02*
X2556061D01*
G01X2520843Y539531D02*
X2522590Y538073D01*
X2524555Y537198D01*
X2526301D01*
X2528048Y538073D01*
X2529358Y539531D01*
X2530013Y541573D01*
X2529576Y543614D01*
X2528485Y545365D01*
X2526520Y546531D01*
X2523900Y547115D01*
X2522371Y548281D01*
X2521716Y550323D01*
X2522153Y552365D01*
X2523245Y553823D01*
X2524773Y554698D01*
X2526301D01*
X2527830Y554115D01*
X2529140Y552656D01*
G01X2547295Y537198D02*
X2538561D01*
Y554698D01*
X2547295D01*
G01X2543801Y546240D02*
X2538561D01*
G01X2520843Y574181D02*
X2522590Y572723D01*
X2524555Y571848D01*
X2526301D01*
X2528048Y572723D01*
X2529358Y574181D01*
X2530013Y576223D01*
X2529576Y578264D01*
X2528485Y580015D01*
X2526520Y581181D01*
X2523900Y581765D01*
X2522371Y582931D01*
X2521716Y584973D01*
X2522153Y587015D01*
X2523245Y588473D01*
X2524773Y589348D01*
X2526301D01*
X2527830Y588765D01*
X2529140Y587306D01*
G01X2547295Y571848D02*
X2538561D01*
Y589348D01*
X2547295D01*
G01X2543801Y580890D02*
X2538561D01*
G01X2634811Y554698D02*
Y537198D01*
X2643545D01*
G01X2656678D02*
Y554698D01*
X2654058Y551198D01*
G01Y537198D02*
X2659298D01*
G01X2674178D02*
Y554698D01*
X2671558Y551198D01*
G01Y537198D02*
X2676798D01*
G01X2687748Y536615D02*
X2695608Y554698D01*
G01X2704811D02*
Y537198D01*
X2713545D01*
G01X2726678D02*
Y554698D01*
X2724058Y551198D01*
G01Y537198D02*
X2729298D01*
G01X2739375Y540698D02*
X2740684Y538656D01*
X2742431Y537490D01*
X2744396Y537198D01*
X2746143Y537490D01*
X2747890Y538948D01*
X2748981Y540698D01*
X2749200Y542448D01*
X2748763Y544489D01*
X2747235Y545948D01*
X2745706Y546531D01*
X2743741D01*
G01X2745706D02*
X2747016Y547406D01*
X2748108Y548864D01*
X2748545Y550614D01*
X2748108Y552365D01*
X2747016Y553823D01*
X2745051Y554698D01*
X2743086Y554406D01*
X2741121Y553239D01*
G01X2634811Y589348D02*
Y571848D01*
X2643545D01*
G01X2656678D02*
Y589348D01*
X2654058Y585848D01*
G01Y571848D02*
X2659298D01*
G01X2674178D02*
Y589348D01*
X2671558Y585848D01*
G01Y571848D02*
X2676798D01*
G01X2687748Y571265D02*
X2695608Y589348D01*
G01X2704811D02*
Y571848D01*
X2713545D01*
G01X2726678D02*
Y589348D01*
X2724058Y585848D01*
G01Y571848D02*
X2729298D01*
G01X2739375Y575348D02*
X2740684Y573306D01*
X2742431Y572140D01*
X2744396Y571848D01*
X2746143Y572140D01*
X2747890Y573598D01*
X2748981Y575348D01*
X2749200Y577098D01*
X2748763Y579139D01*
X2747235Y580598D01*
X2745706Y581181D01*
X2743741D01*
G01X2745706D02*
X2747016Y582056D01*
X2748108Y583514D01*
X2748545Y585264D01*
X2748108Y587015D01*
X2747016Y588473D01*
X2745051Y589348D01*
X2743086Y589056D01*
X2741121Y587889D01*
G01X2608561Y606498D02*
Y623998D01*
X2614020D01*
X2615766Y623123D01*
X2616858Y621956D01*
X2617295Y619623D01*
X2616858Y617289D01*
X2615548Y615831D01*
X2614020Y614956D01*
X2608561D01*
G01X2614020D02*
X2617295Y606498D01*
G01X2627153Y614373D02*
X2634140D01*
X2633485Y616415D01*
X2632393Y617581D01*
X2630865Y618164D01*
X2629336Y617873D01*
X2628026Y616998D01*
X2627153Y614956D01*
X2626716Y613206D01*
Y611456D01*
X2627153Y609706D01*
X2628245Y607956D01*
X2629555Y606790D01*
X2631083Y606498D01*
X2632611Y607081D01*
X2634140Y608831D01*
G01X2646618Y606498D02*
Y621373D01*
X2647055Y622831D01*
X2647928Y623706D01*
X2649238Y623998D01*
X2650548Y623415D01*
X2651203Y621956D01*
G01X2648583Y616998D02*
X2644216D01*
G01X2665428Y605915D02*
X2664991Y606206D01*
Y606790D01*
X2665428Y607081D01*
X2665865Y606790D01*
Y606206D01*
X2665428Y605915D01*
G01X2696061Y606498D02*
Y623998D01*
X2701301D01*
X2703048Y623123D01*
X2704358Y621081D01*
X2704795Y618748D01*
X2704358Y616415D01*
X2703266Y614665D01*
X2701301Y613789D01*
X2696061D01*
G01X2717928Y606498D02*
Y623998D01*
G01X2739358Y606498D02*
Y618164D01*
G01Y616123D02*
X2738485Y617289D01*
X2737174Y617873D01*
X2735646Y618164D01*
X2734118Y617581D01*
X2732808Y616415D01*
X2731934Y614665D01*
X2731498Y612331D01*
X2731934Y609998D01*
X2732808Y608248D01*
X2734118Y607081D01*
X2735646Y606498D01*
X2737174Y606790D01*
X2738485Y607664D01*
X2739358Y608831D01*
G01X2749216Y606498D02*
Y618164D01*
G01Y615248D02*
X2750090Y616706D01*
X2751400Y617873D01*
X2753146Y618164D01*
X2754674Y617873D01*
X2755985Y616706D01*
X2756640Y614665D01*
Y606498D01*
G01X2767153Y614373D02*
X2774140D01*
X2773485Y616415D01*
X2772393Y617581D01*
X2770865Y618164D01*
X2769336Y617873D01*
X2768026Y616998D01*
X2767153Y614956D01*
X2766716Y613206D01*
Y611456D01*
X2767153Y609706D01*
X2768245Y607956D01*
X2769555Y606790D01*
X2771083Y606498D01*
X2772611Y607081D01*
X2774140Y608831D01*
G01X2888228Y548864D02*
Y537198D01*
G01Y553531D02*
X2887791Y553823D01*
Y554406D01*
X2888228Y554698D01*
X2888665Y554406D01*
Y553823D01*
X2888228Y553531D01*
G01X2902016Y537198D02*
Y548864D01*
G01Y545948D02*
X2902890Y547406D01*
X2904200Y548573D01*
X2905946Y548864D01*
X2907474Y548573D01*
X2908785Y547406D01*
X2909440Y545365D01*
Y537198D01*
G01X2919953Y539239D02*
X2921045Y538073D01*
X2922573Y537198D01*
X2923883D01*
X2925193Y537781D01*
X2926066Y538656D01*
X2926503Y539822D01*
X2926285Y541573D01*
X2925411Y542448D01*
X2921481Y544198D01*
X2920608Y546240D01*
X2921045Y547698D01*
X2921918Y548573D01*
X2923228Y548864D01*
X2924538Y548573D01*
X2925848Y547698D01*
G01X2940728Y548864D02*
Y537198D01*
G01Y553531D02*
X2940291Y553823D01*
Y554406D01*
X2940728Y554698D01*
X2941165Y554406D01*
Y553823D01*
X2940728Y553531D01*
G01X2962158Y554698D02*
Y537198D01*
G01Y539822D02*
X2961285Y538364D01*
X2959974Y537490D01*
X2958446Y537198D01*
X2956700Y537781D01*
X2955390Y539239D01*
X2954516Y540989D01*
X2954298Y543031D01*
X2954516Y545073D01*
X2955390Y546823D01*
X2956700Y548281D01*
X2958446Y548864D01*
X2959974Y548573D01*
X2961066Y547989D01*
X2962158Y546823D01*
G01X2972453Y545073D02*
X2979440D01*
X2978785Y547115D01*
X2977693Y548281D01*
X2976165Y548864D01*
X2974636Y548573D01*
X2973326Y547698D01*
X2972453Y545656D01*
X2972016Y543906D01*
Y542156D01*
X2972453Y540406D01*
X2973545Y538656D01*
X2974855Y537490D01*
X2976383Y537198D01*
X2977911Y537781D01*
X2979440Y539531D01*
G01X3006798Y537198D02*
Y554698D01*
G01Y545948D02*
X3007890Y547698D01*
X3009200Y548573D01*
X3010510Y548864D01*
X3012474Y548281D01*
X3013785Y547115D01*
X3014658Y545073D01*
Y542740D01*
X3014221Y540406D01*
X3013348Y538656D01*
X3011820Y537490D01*
X3010510Y537198D01*
X3009200Y537490D01*
X3007890Y538364D01*
X3006798Y539822D01*
G01X3028228Y537198D02*
X3026918Y537490D01*
X3025608Y538656D01*
X3024734Y540698D01*
X3024298Y543031D01*
X3024734Y545365D01*
X3025608Y547406D01*
X3026918Y548573D01*
X3028228Y548864D01*
X3029538Y548573D01*
X3030848Y547406D01*
X3031721Y545365D01*
X3031940Y543031D01*
X3031721Y540698D01*
X3030848Y538656D01*
X3029538Y537490D01*
X3028228Y537198D01*
G01X3049658D02*
Y548864D01*
G01Y546823D02*
X3048785Y547989D01*
X3047474Y548573D01*
X3045946Y548864D01*
X3044418Y548281D01*
X3043108Y547115D01*
X3042234Y545365D01*
X3041798Y543031D01*
X3042234Y540698D01*
X3043108Y538948D01*
X3044418Y537781D01*
X3045946Y537198D01*
X3047474Y537490D01*
X3048785Y538364D01*
X3049658Y539531D01*
G01X3060171Y537198D02*
Y548864D01*
G01Y546531D02*
X3061263Y547698D01*
X3062355Y548573D01*
X3063883Y548864D01*
X3064974Y548573D01*
X3066285Y547698D01*
G01X3084658Y554698D02*
Y537198D01*
G01Y539822D02*
X3083785Y538364D01*
X3082474Y537490D01*
X3080946Y537198D01*
X3079200Y537781D01*
X3077890Y539239D01*
X3077016Y540989D01*
X3076798Y543031D01*
X3077016Y545073D01*
X3077890Y546823D01*
X3079200Y548281D01*
X3080946Y548864D01*
X3082474Y548573D01*
X3083566Y547989D01*
X3084658Y546823D01*
G01X3115728Y537198D02*
X3114418Y537490D01*
X3113108Y538656D01*
X3112234Y540698D01*
X3111798Y543031D01*
X3112234Y545365D01*
X3113108Y547406D01*
X3114418Y548573D01*
X3115728Y548864D01*
X3117038Y548573D01*
X3118348Y547406D01*
X3119221Y545365D01*
X3119440Y543031D01*
X3119221Y540698D01*
X3118348Y538656D01*
X3117038Y537490D01*
X3115728Y537198D01*
G01X3129516Y548864D02*
Y540698D01*
X3130390Y538656D01*
X3131700Y537490D01*
X3133228Y537198D01*
X3134756Y537490D01*
X3136066Y538656D01*
X3136940Y540698D01*
G01Y537198D02*
Y548864D01*
G01X3150728Y554698D02*
Y537198D01*
G01X3147671Y548864D02*
X3153785D01*
G01X3168228Y537198D02*
Y554698D01*
G01X3185728Y548864D02*
Y537198D01*
G01Y553531D02*
X3185291Y553823D01*
Y554406D01*
X3185728Y554698D01*
X3186165Y554406D01*
Y553823D01*
X3185728Y553531D01*
G01X3199516Y537198D02*
Y548864D01*
G01Y545948D02*
X3200390Y547406D01*
X3201700Y548573D01*
X3203446Y548864D01*
X3204974Y548573D01*
X3206285Y547406D01*
X3206940Y545365D01*
Y537198D01*
G01X3217453Y545073D02*
X3224440D01*
X3223785Y547115D01*
X3222693Y548281D01*
X3221165Y548864D01*
X3219636Y548573D01*
X3218326Y547698D01*
X3217453Y545656D01*
X3217016Y543906D01*
Y542156D01*
X3217453Y540406D01*
X3218545Y538656D01*
X3219855Y537490D01*
X3221383Y537198D01*
X3222911Y537781D01*
X3224440Y539531D01*
G01X3238228Y536615D02*
X3237791Y536906D01*
Y537490D01*
X3238228Y537781D01*
X3238665Y537490D01*
Y536906D01*
X3238228Y536615D01*
G01X2888228Y583514D02*
Y571848D01*
G01Y588181D02*
X2887791Y588473D01*
Y589056D01*
X2888228Y589348D01*
X2888665Y589056D01*
Y588473D01*
X2888228Y588181D01*
G01X2902453Y573889D02*
X2903545Y572723D01*
X2905073Y571848D01*
X2906383D01*
X2907693Y572431D01*
X2908566Y573306D01*
X2909003Y574472D01*
X2908785Y576223D01*
X2907911Y577098D01*
X2903981Y578848D01*
X2903108Y580890D01*
X2903545Y582348D01*
X2904418Y583223D01*
X2905728Y583514D01*
X2907038Y583223D01*
X2908348Y582348D01*
G01X2935706Y571848D02*
Y589348D01*
X2945750Y571848D01*
Y589348D01*
G01X2958228Y571848D02*
X2956481Y572140D01*
X2954953Y573306D01*
X2953643Y575056D01*
X2952769Y577098D01*
X2952333Y579431D01*
Y581765D01*
X2952769Y584098D01*
X2953643Y586140D01*
X2954953Y587889D01*
X2956481Y589056D01*
X2958228Y589348D01*
X2959974Y589056D01*
X2961503Y587889D01*
X2962813Y586140D01*
X2963687Y584098D01*
X2964123Y581765D01*
Y579431D01*
X2963687Y577098D01*
X2962813Y575056D01*
X2961503Y573306D01*
X2959974Y572140D01*
X2958228Y571848D01*
G01X2975728Y589348D02*
Y571848D01*
G01X2970706Y589348D02*
X2980750D01*
G01X3007016Y583514D02*
Y575348D01*
X3007890Y573306D01*
X3009200Y572140D01*
X3010728Y571848D01*
X3012256Y572140D01*
X3013566Y573306D01*
X3014440Y575348D01*
G01Y571848D02*
Y583514D01*
G01X3024953Y573889D02*
X3026045Y572723D01*
X3027573Y571848D01*
X3028883D01*
X3030193Y572431D01*
X3031066Y573306D01*
X3031503Y574472D01*
X3031285Y576223D01*
X3030411Y577098D01*
X3026481Y578848D01*
X3025608Y580890D01*
X3026045Y582348D01*
X3026918Y583223D01*
X3028228Y583514D01*
X3029538Y583223D01*
X3030848Y582348D01*
G01X3042453Y579723D02*
X3049440D01*
X3048785Y581765D01*
X3047693Y582931D01*
X3046165Y583514D01*
X3044636Y583223D01*
X3043326Y582348D01*
X3042453Y580306D01*
X3042016Y578556D01*
Y576806D01*
X3042453Y575056D01*
X3043545Y573306D01*
X3044855Y572140D01*
X3046383Y571848D01*
X3047911Y572431D01*
X3049440Y574181D01*
G01X3067158Y589348D02*
Y571848D01*
G01Y574472D02*
X3066285Y573014D01*
X3064974Y572140D01*
X3063446Y571848D01*
X3061700Y572431D01*
X3060390Y573889D01*
X3059516Y575639D01*
X3059298Y577681D01*
X3059516Y579723D01*
X3060390Y581473D01*
X3061700Y582931D01*
X3063446Y583514D01*
X3064974Y583223D01*
X3066066Y582639D01*
X3067158Y581473D01*
G01X3098228Y583514D02*
Y571848D01*
G01Y588181D02*
X3097791Y588473D01*
Y589056D01*
X3098228Y589348D01*
X3098665Y589056D01*
Y588473D01*
X3098228Y588181D01*
G01X3112016Y571848D02*
Y583514D01*
G01Y580598D02*
X3112890Y582056D01*
X3114200Y583223D01*
X3115946Y583514D01*
X3117474Y583223D01*
X3118785Y582056D01*
X3119440Y580015D01*
Y571848D01*
G01X3150728Y589348D02*
Y571848D01*
G01X3147671Y583514D02*
X3153785D01*
G01X3164516Y571848D02*
Y589348D01*
G01Y580890D02*
X3165608Y582348D01*
X3166700Y583223D01*
X3168446Y583514D01*
X3169756Y583223D01*
X3171285Y582056D01*
X3171940Y580306D01*
Y571848D01*
G01X3185728Y583514D02*
Y571848D01*
G01Y588181D02*
X3185291Y588473D01*
Y589056D01*
X3185728Y589348D01*
X3186165Y589056D01*
Y588473D01*
X3185728Y588181D01*
G01X3199953Y573889D02*
X3201045Y572723D01*
X3202573Y571848D01*
X3203883D01*
X3205193Y572431D01*
X3206066Y573306D01*
X3206503Y574472D01*
X3206285Y576223D01*
X3205411Y577098D01*
X3201481Y578848D01*
X3200608Y580890D01*
X3201045Y582348D01*
X3201918Y583223D01*
X3203228Y583514D01*
X3204538Y583223D01*
X3205848Y582348D01*
G01X3238228Y571848D02*
Y589348D01*
G01X3259658Y571848D02*
Y583514D01*
G01Y581473D02*
X3258785Y582639D01*
X3257474Y583223D01*
X3255946Y583514D01*
X3254418Y582931D01*
X3253108Y581765D01*
X3252234Y580015D01*
X3251798Y577681D01*
X3252234Y575348D01*
X3253108Y573598D01*
X3254418Y572431D01*
X3255946Y571848D01*
X3257474Y572140D01*
X3258785Y573014D01*
X3259658Y574181D01*
G01X3268643Y566598D02*
X3269953Y566015D01*
X3271700Y566598D01*
X3272791Y567764D01*
X3273665Y569223D01*
X3274974Y573889D01*
X3277813Y583514D01*
G01X3270826D02*
X3274974Y573889D01*
G01X3287453Y579723D02*
X3294440D01*
X3293785Y581765D01*
X3292693Y582931D01*
X3291165Y583514D01*
X3289636Y583223D01*
X3288326Y582348D01*
X3287453Y580306D01*
X3287016Y578556D01*
Y576806D01*
X3287453Y575056D01*
X3288545Y573306D01*
X3289855Y572140D01*
X3291383Y571848D01*
X3292911Y572431D01*
X3294440Y574181D01*
G01X3305171Y571848D02*
Y583514D01*
G01Y581181D02*
X3306263Y582348D01*
X3307355Y583223D01*
X3308883Y583514D01*
X3309974Y583223D01*
X3311285Y582348D01*
G01X2813425Y605915D02*
X2823031Y618748D01*
G01X2818228Y621081D02*
Y603581D01*
G01X2823031Y605915D02*
X2813425Y618748D01*
G01X2811678Y612331D02*
X2824778D01*
G01X2850390D02*
X2856066D01*
G01X2883425Y606498D02*
Y623998D01*
X2887791D01*
X2889538Y623123D01*
X2890848Y621956D01*
X2891940Y620207D01*
X2892813Y618164D01*
X2893031Y615248D01*
X2892813Y612331D01*
X2891940Y610289D01*
X2890848Y608539D01*
X2889538Y607373D01*
X2887791Y606498D01*
X2883425D01*
G01X2902453Y614373D02*
X2909440D01*
X2908785Y616415D01*
X2907693Y617581D01*
X2906165Y618164D01*
X2904636Y617873D01*
X2903326Y616998D01*
X2902453Y614956D01*
X2902016Y613206D01*
Y611456D01*
X2902453Y609706D01*
X2903545Y607956D01*
X2904855Y606790D01*
X2906383Y606498D01*
X2907911Y607081D01*
X2909440Y608831D01*
G01X2919516Y606498D02*
Y618164D01*
G01Y615248D02*
X2920390Y616706D01*
X2921700Y617873D01*
X2923446Y618164D01*
X2924974Y617873D01*
X2926285Y616706D01*
X2926940Y614665D01*
Y606498D01*
G01X2940728D02*
X2939418Y606790D01*
X2938108Y607956D01*
X2937234Y609998D01*
X2936798Y612331D01*
X2937234Y614665D01*
X2938108Y616706D01*
X2939418Y617873D01*
X2940728Y618164D01*
X2942038Y617873D01*
X2943348Y616706D01*
X2944221Y614665D01*
X2944440Y612331D01*
X2944221Y609998D01*
X2943348Y607956D01*
X2942038Y606790D01*
X2940728Y606498D01*
G01X2958228Y623998D02*
Y606498D01*
G01X2955171Y618164D02*
X2961285D01*
G01X2972453Y614373D02*
X2979440D01*
X2978785Y616415D01*
X2977693Y617581D01*
X2976165Y618164D01*
X2974636Y617873D01*
X2973326Y616998D01*
X2972453Y614956D01*
X2972016Y613206D01*
Y611456D01*
X2972453Y609706D01*
X2973545Y607956D01*
X2974855Y606790D01*
X2976383Y606498D01*
X2977911Y607081D01*
X2979440Y608831D01*
G01X2989953Y608539D02*
X2991045Y607373D01*
X2992573Y606498D01*
X2993883D01*
X2995193Y607081D01*
X2996066Y607956D01*
X2996503Y609122D01*
X2996285Y610873D01*
X2995411Y611748D01*
X2991481Y613498D01*
X2990608Y615540D01*
X2991045Y616998D01*
X2991918Y617873D01*
X2993228Y618164D01*
X2994538Y617873D01*
X2995848Y616998D01*
G01X3028228Y623998D02*
Y606498D01*
G01X3025171Y618164D02*
X3031285D01*
G01X3042016Y606498D02*
Y623998D01*
G01Y615540D02*
X3043108Y616998D01*
X3044200Y617873D01*
X3045946Y618164D01*
X3047256Y617873D01*
X3048785Y616706D01*
X3049440Y614956D01*
Y606498D01*
G01X3067158D02*
Y618164D01*
G01Y616123D02*
X3066285Y617289D01*
X3064974Y617873D01*
X3063446Y618164D01*
X3061918Y617581D01*
X3060608Y616415D01*
X3059734Y614665D01*
X3059298Y612331D01*
X3059734Y609998D01*
X3060608Y608248D01*
X3061918Y607081D01*
X3063446Y606498D01*
X3064974Y606790D01*
X3066285Y607664D01*
X3067158Y608831D01*
G01X3080728Y623998D02*
Y606498D01*
G01X3077671Y618164D02*
X3083785D01*
G01X3109178Y623998D02*
X3112234Y606498D01*
X3115728Y623998D01*
X3119221Y606498D01*
X3122278Y623998D01*
G01X3130608D02*
X3135848D01*
G01X3133228D02*
Y606498D01*
G01X3130608D02*
X3135848D01*
G01X3145925D02*
Y623998D01*
X3150291D01*
X3152038Y623123D01*
X3153348Y621956D01*
X3154440Y620207D01*
X3155313Y618164D01*
X3155531Y615248D01*
X3155313Y612331D01*
X3154440Y610289D01*
X3153348Y608539D01*
X3152038Y607373D01*
X3150291Y606498D01*
X3145925D01*
G01X3168228Y623998D02*
Y606498D01*
G01X3163206Y623998D02*
X3173250D01*
G01X3181143Y606498D02*
Y623998D01*
G01X3190313D02*
Y606498D01*
G01Y615248D02*
X3181143D01*
G01X-7874Y-31496D02*
X-19685D01*
G01X-7874D02*
X-19685D01*
G01D02*
G03X-23622Y-35433I0J-3937D01*
G01D02*
Y-59055D01*
G01Y-35433D02*
Y-59055D01*
G01X-19685Y-31496D02*
G03X-23622Y-35433I0J-3937D01*
G01Y-59055D02*
G03X-19685Y-62992I3937J0D01*
G01D02*
X1972441D01*
G01X-19685D02*
X1972441D01*
G01X-23622Y-59055D02*
G03X-19685Y-62992I3937J0D01*
G01Y-23622D02*
X1972441D01*
G01X-19685D02*
X1972441D01*
G01X-19685D02*
X1972441D01*
G01X-19685D02*
X1972441D01*
G01X-23622Y622441D02*
Y-19685D01*
G01Y622441D02*
Y-19685D01*
G01Y622441D02*
Y-19685D01*
G01Y622441D02*
Y-19685D01*
G01D02*
G03X-19685Y-23622I3937J0D01*
G01X-23622Y-19685D02*
G03X-19685Y-23622I3937J0D01*
G01X-23622Y-19685D02*
G03X-19685Y-23622I3937J0D01*
G01X-23622Y-19685D02*
G03X-19685Y-23622I3937J0D01*
G01X1972441Y626378D02*
X-19685D01*
G01X1972441D02*
X-19685D01*
G01X1972441D02*
X-19685D01*
G01X1972441D02*
X-19685D01*
G01D02*
G03X-23622Y622441I0J-3937D01*
G01X-19685Y626378D02*
G03X-23622Y622441I0J-3937D01*
G01X-19685Y626378D02*
G03X-23622Y622441I0J-3937D01*
G01X-19685Y626378D02*
G03X-23622Y622441I0J-3937D01*
G01X-19685Y634252D02*
X-7874D01*
G01X-19685D02*
X-7874D01*
G01X-23622Y661811D02*
Y638189D01*
G01Y661811D02*
Y638189D01*
G01D02*
G03X-19685Y634252I3937J0D01*
G01X-23622Y638189D02*
G03X-19685Y634252I3937J0D01*
G01X1972441Y665748D02*
X-19685D01*
G01X1972441D02*
X-19685D01*
G01D02*
G03X-23622Y661811I0J-3937D01*
G01X-19685Y665748D02*
G03X-23622Y661811I0J-3937D01*
G01X-7874Y-31496D02*
G03Y-23622I0J3937D01*
G01Y-31496D02*
G03Y-23622I0J3937D01*
G01X22835D02*
G03Y-31496I0J-3937D01*
G01X137795D02*
X22835D01*
G01X137795D02*
X22835D01*
G01Y-23622D02*
G03Y-31496I0J-3937D01*
G01X0Y616535D02*
G03Y604724I0J-5905D01*
G01Y616535D02*
G03Y604724I0J-5905D01*
G01Y616535D02*
X2646D01*
G01X2644D02*
X0D01*
G01Y604724D02*
X2644D01*
G01X2646D02*
X0D01*
G01X2646D02*
X0D01*
G01D02*
X2644D01*
G01Y616535D02*
X0D01*
G01D02*
X2646D01*
G01X0D02*
G03Y604724I0J-5905D01*
G01Y616535D02*
G03Y604724I0J-5905D01*
G01X2646Y616535D02*
G03X7595Y618285I0J7874D01*
G01X2644Y616535D02*
G03X7593Y618285I0J7874D01*
G01X2644Y616535D02*
G03X7593Y618285I0J7874D01*
G01X7595Y602975D02*
G03X2646Y604724I-4948J-6125D01*
G01X7593Y602975D02*
G03X2644Y604724I-4948J-6125D01*
G01X7593Y602975D02*
G03X2644Y604724I-4948J-6125D01*
G01X7593Y602975D02*
G03X2644Y604724I-4948J-6125D01*
G01X7593Y602975D02*
G03X2644Y604724I-4948J-6125D01*
G01X7595Y602975D02*
G03X2646Y604724I-4948J-6125D01*
G01X2644Y616535D02*
G03X7593Y618285I0J7874D01*
G01X2644Y616535D02*
G03X7593Y618285I0J7874D01*
G01X2646Y616535D02*
G03X7595Y618285I0J7874D01*
G01Y602975D02*
G03Y618285I6186J7655D01*
G01X7593Y602975D02*
G03Y618285I6187J7655D01*
G01Y602975D02*
G03Y618285I6187J7655D01*
G01Y602975D02*
G03Y618285I6187J7655D01*
G01Y602975D02*
G03Y618285I6187J7655D01*
G01X7595Y602975D02*
G03Y618285I6186J7655D01*
G01X-7874Y626378D02*
G03Y634252I0J3937D01*
G01Y626378D02*
G03Y634252I0J3937D01*
G01X22835D02*
G03Y626378I0J-3937D01*
G01Y634252D02*
X137795D01*
G01X22835D02*
X137795D01*
G01X22835D02*
G03Y626378I0J-3937D01*
G01X168504Y-23622D02*
G03Y-31496I0J-3937D01*
G01X137795D02*
G03Y-23622I0J3937D01*
G01X341732Y-31496D02*
X168504D01*
G01X341732D02*
X168504D01*
G01X137795D02*
G03Y-23622I0J3937D01*
G01X168504D02*
G03Y-31496I0J-3937D01*
G01Y634252D02*
G03Y626378I0J-3937D01*
G01X137795D02*
G03Y634252I0J3937D01*
G01X168504D02*
X341732D01*
G01X168504D02*
X341732D01*
G01X137795Y626378D02*
G03Y634252I0J3937D01*
G01X168504D02*
G03Y626378I0J-3937D01*
G01X341732Y-31496D02*
G03Y-23622I0J3937D01*
G01Y-31496D02*
G03Y-23622I0J3937D01*
G01Y626378D02*
G03Y634252I0J3937D01*
G01Y626378D02*
G03Y634252I0J3937D01*
G01X372441Y-23622D02*
G03Y-31496I0J-3937D01*
G01X529921D02*
X372441D01*
G01X529921D02*
X372441D01*
G01Y-23622D02*
G03Y-31496I0J-3937D01*
G01Y634252D02*
G03Y626378I0J-3937D01*
G01Y634252D02*
X529921D01*
G01X372441D02*
X529921D01*
G01X372441D02*
G03Y626378I0J-3937D01*
G01X529921Y-31496D02*
G03Y-23622I0J3937D01*
G01Y-31496D02*
G03Y-23622I0J3937D01*
G01Y626378D02*
G03Y634252I0J3937D01*
G01Y626378D02*
G03Y634252I0J3937D01*
G01X560630Y-23622D02*
G03Y-31496I0J-3937D01*
G01X788976D02*
X560630D01*
G01X788976D02*
X560630D01*
G01Y-23622D02*
G03Y-31496I0J-3937D01*
G01Y634252D02*
G03Y626378I0J-3937D01*
G01Y634252D02*
X788976D01*
G01X560630D02*
X788976D01*
G01X560630D02*
G03Y626378I0J-3937D01*
G01X684760Y-15529D02*
G03Y-219I6187J7655D01*
G01X684759Y-15529D02*
G03X679809Y-13780I-4948J-6125D01*
G01X679811Y-1969D02*
G03X684760Y-219I0J7874D01*
G01X677165Y-1969D02*
X679811D01*
G01X677165D02*
G03Y-13780I0J-5906D01*
G01D02*
X679809D01*
G01X684760Y602975D02*
G03Y618285I6187J7655D01*
G01X684759Y602975D02*
G03Y618285I6186J7655D01*
G01Y602975D02*
G03Y618285I6186J7655D01*
G01Y602975D02*
G03Y618285I6186J7655D01*
G01Y602975D02*
G03Y618285I6186J7655D01*
G01X684760Y602975D02*
G03Y618285I6187J7655D01*
G01X679811Y616535D02*
G03X684760Y618285I0J7874D01*
G01X679809Y616535D02*
G03X684759Y618285I0J7874D01*
G01X679809Y616535D02*
G03X684759Y618285I0J7874D01*
G01X684760Y602975D02*
G03X679811Y604724I-4948J-6125D01*
G01X684759Y602975D02*
G03X679809Y604724I-4948J-6125D01*
G01X684759Y602975D02*
G03X679809Y604724I-4948J-6125D01*
G01X684759Y602975D02*
G03X679809Y604724I-4948J-6125D01*
G01X684759Y602975D02*
G03X679809Y604724I-4948J-6125D01*
G01X684760Y602975D02*
G03X679811Y604724I-4948J-6125D01*
G01X679809Y616535D02*
G03X684759Y618285I0J7874D01*
G01X679809Y616535D02*
G03X684759Y618285I0J7874D01*
G01X679811Y616535D02*
G03X684760Y618285I0J7874D01*
G01X677165Y616535D02*
X679811D01*
G01X677165D02*
G03Y604724I0J-5905D01*
G01D02*
X679809D01*
G01X788976Y-31496D02*
G03Y-23622I0J3937D01*
G01Y-31496D02*
G03Y-23622I0J3937D01*
G01X819685D02*
G03Y-31496I0J-3937D01*
G01X975591D02*
X819685D01*
G01X975591D02*
X819685D01*
G01Y-23622D02*
G03Y-31496I0J-3937D01*
G01X788976Y626378D02*
G03Y634252I0J3937D01*
G01Y626378D02*
G03Y634252I0J3937D01*
G01X819685D02*
G03Y626378I0J-3937D01*
G01Y634252D02*
X975591D01*
G01X819685D02*
X975591D01*
G01X819685D02*
G03Y626378I0J-3937D01*
G01X975591Y-31496D02*
G03Y-23622I0J3937D01*
G01Y-31496D02*
G03Y-23622I0J3937D01*
G01X1006299D02*
G03Y-31496I0J-3937D01*
G01X1162205D02*
X1006299D01*
G01X1162205D02*
X1006299D01*
G01Y-23622D02*
G03Y-31496I0J-3937D01*
G01Y634252D02*
X1162205D01*
G01X1006299D02*
X1162205D01*
G01X975591Y626378D02*
G03Y634252I0J3937D01*
G01Y626378D02*
G03Y634252I0J3937D01*
G01X1006299D02*
G03Y626378I0J-3937D01*
G01Y634252D02*
G03Y626378I0J-3937D01*
G01X1162205Y-31496D02*
G03Y-23622I0J3937D01*
G01Y-31496D02*
G03Y-23622I0J3937D01*
G01X1192913D02*
G03Y-31496I0J-3937D01*
G01X1398425D02*
X1192913D01*
G01X1398425D02*
X1192913D01*
G01Y-23622D02*
G03Y-31496I0J-3937D01*
G01Y634252D02*
X1394488D01*
G01X1192913D02*
X1394488D01*
G01X1162205Y626378D02*
G03Y634252I0J3937D01*
G01Y626378D02*
G03Y634252I0J3937D01*
G01X1192913D02*
G03Y626378I0J-3937D01*
G01Y634252D02*
G03Y626378I0J-3937D01*
G01X1398425Y-31496D02*
G03Y-23622I0J3937D01*
G01Y-31496D02*
G03Y-23622I0J3937D01*
G01X1405512Y-1968D02*
G03Y-13779I0J-5906D01*
G01Y-1968D02*
G03Y-13779I0J-5906D01*
G01Y-1968D02*
G03Y-13779I0J-5906D01*
G01Y-1968D02*
G03Y-13779I0J-5906D01*
G01X1394488Y626378D02*
G03Y634252I0J3937D01*
G01Y626378D02*
G03Y634252I0J3937D01*
G01X1405512Y616535D02*
G03Y604724I0J-5905D01*
G01Y616535D02*
G03Y604724I0J-5905D01*
G01Y616535D02*
G03Y604724I0J-5905D01*
G01Y616535D02*
G03Y604724I0J-5905D01*
G01X1429134Y-23622D02*
G03Y-31496I0J-3937D01*
G01X1851181D02*
X1429134D01*
G01X1851181D02*
X1429134D01*
G01Y-23622D02*
G03Y-31496I0J-3937D01*
G01X1413107Y-15529D02*
G03Y-218I6186J7655D01*
G01X1413105Y-15529D02*
G03Y-218I6186J7655D01*
G01Y-15529D02*
G03Y-218I6186J7655D01*
G01Y-15529D02*
G03Y-218I6186J7655D01*
G01Y-15529D02*
G03Y-218I6186J7655D01*
G01X1413107Y-15529D02*
G03Y-218I6186J7655D01*
G01X1408157Y-1968D02*
G03X1413107Y-218I1J7874D01*
G01X1408156Y-1968D02*
G03X1413105Y-218I0J7874D01*
G01X1408156Y-1968D02*
G03X1413105Y-218I0J7874D01*
G01X1408156Y-1968D02*
G03X1413105Y-218I0J7874D01*
G01X1408156Y-1968D02*
G03X1413105Y-218I0J7874D01*
G01X1408157Y-1968D02*
G03X1413107Y-218I1J7874D01*
G01Y-15529D02*
G03X1408157Y-13779I-4949J-6124D01*
G01X1413105Y-15529D02*
G03X1408156Y-13779I-4949J-6124D01*
G01X1413105Y-15529D02*
G03X1408156Y-13779I-4949J-6124D01*
G01X1413105Y-15529D02*
G03X1408156Y-13779I-4949J-6124D01*
G01X1413105Y-15529D02*
G03X1408156Y-13779I-4949J-6124D01*
G01X1413107Y-15529D02*
G03X1408157Y-13779I-4949J-6124D01*
G01X1405512D02*
X1408156D01*
G01X1408157D02*
X1405512D01*
G01X1408157D02*
X1405512D01*
G01D02*
X1408156D01*
G01X1405512Y-1968D02*
X1408157D01*
G01X1408156D02*
X1405512D01*
G01X1408156D02*
X1405512D01*
G01D02*
X1408157D01*
G01X1425197Y634252D02*
X1851181D01*
G01X1425197D02*
X1851181D01*
G01X1425197D02*
G03Y626378I0J-3937D01*
G01Y634252D02*
G03Y626378I0J-3937D01*
G01X1408157Y616535D02*
G03X1413107Y618285I1J7874D01*
G01X1408156Y616535D02*
G03X1413105Y618285I0J7874D01*
G01X1408156Y616535D02*
G03X1413105Y618285I0J7874D01*
G01X1413107Y602975D02*
G03Y618285I6186J7655D01*
G01X1413105Y602975D02*
G03Y618285I6187J7655D01*
G01Y602975D02*
G03Y618285I6187J7655D01*
G01X1413107Y602975D02*
G03X1408157Y604724I-4948J-6125D01*
G01X1413105Y602975D02*
G03X1408156Y604724I-4948J-6125D01*
G01X1413105Y602975D02*
G03X1408156Y604724I-4948J-6125D01*
G01X1413105Y602975D02*
G03X1408156Y604724I-4948J-6125D01*
G01X1413105Y602975D02*
G03X1408156Y604724I-4948J-6125D01*
G01X1413107Y602975D02*
G03X1408157Y604724I-4948J-6125D01*
G01X1413105Y602975D02*
G03Y618285I6187J7655D01*
G01Y602975D02*
G03Y618285I6187J7655D01*
G01X1413107Y602975D02*
G03Y618285I6186J7655D01*
G01X1408156Y616535D02*
G03X1413105Y618285I0J7874D01*
G01X1408156Y616535D02*
G03X1413105Y618285I0J7874D01*
G01X1408157Y616535D02*
G03X1413107Y618285I1J7874D01*
G01X1405512Y616535D02*
X1408157D01*
G01X1408156D02*
X1405512D01*
G01Y604724D02*
X1408156D01*
G01X1408157D02*
X1405512D01*
G01X1408157D02*
X1405512D01*
G01D02*
X1408156D01*
G01Y616535D02*
X1405512D01*
G01D02*
X1408157D01*
G01X1685866Y267244D02*
X1883780D01*
G01X1685866D02*
X1883780D01*
G01X1685866D02*
X1883780D01*
G01X1685866D02*
X1883780D01*
G01X1681929Y271181D02*
G03X1685866Y267244I3937J0D01*
G01X1681929Y271181D02*
G03X1685866Y267244I3937J0D01*
G01X1681929Y271181D02*
G03X1685866Y267244I3937J0D01*
G01X1681929Y271181D02*
G03X1685866Y267244I3937J0D01*
G01X1681929Y428661D02*
Y271181D01*
G01Y428661D02*
Y271181D01*
G01Y428661D02*
Y271181D01*
G01Y428661D02*
Y271181D01*
G01X1685866Y432598D02*
G03X1681929Y428661I0J-3937D01*
G01X1685866Y432598D02*
G03X1681929Y428661I0J-3937D01*
G01X1972441Y432598D02*
X1685866D01*
G01X1972441D02*
X1685866D01*
G01X1972441D02*
X1685866D01*
G01X1972441D02*
X1685866D01*
G01D02*
G03X1681929Y428661I0J-3937D01*
G01X1685866Y432598D02*
G03X1681929Y428661I0J-3937D01*
G01X1851181Y-31496D02*
G03Y-23622I0J3937D01*
G01Y-31496D02*
G03Y-23622I0J3937D01*
G01X1881890D02*
G03Y-31496I0J-3937D01*
G01X1972441D02*
X1881890D01*
G01X1972441D02*
X1881890D01*
G01Y-23622D02*
G03Y-31496I0J-3937D01*
G01X1861926Y-15529D02*
G03X1856976Y-13780I-4948J-6125D01*
G01X1861924Y-15529D02*
G03X1856975Y-13780I-4948J-6125D01*
G01X1861924Y-15529D02*
G03X1856975Y-13780I-4948J-6125D01*
G01X1861924Y-15529D02*
G03X1856975Y-13780I-4948J-6125D01*
G01X1861924Y-15529D02*
G03X1856975Y-13780I-4948J-6125D01*
G01X1861926Y-15529D02*
G03X1856976Y-13780I-4948J-6125D01*
G01Y-1969D02*
G03X1861926Y-219I0J7874D01*
G01X1856975Y-1969D02*
G03X1861924Y-219I0J7874D01*
G01X1856975Y-1969D02*
G03X1861924Y-219I0J7874D01*
G01X1861926Y-15529D02*
G03Y-219I6186J7655D01*
G01X1861924Y-15529D02*
G03Y-219I6186J7655D01*
G01Y-15529D02*
G03Y-219I6186J7655D01*
G01Y-15529D02*
G03Y-219I6186J7655D01*
G01Y-15529D02*
G03Y-219I6186J7655D01*
G01X1861926Y-15529D02*
G03Y-219I6186J7655D01*
G01X1856975Y-1969D02*
G03X1861924Y-219I0J7874D01*
G01X1856975Y-1969D02*
G03X1861924Y-219I0J7874D01*
G01X1856976Y-1969D02*
G03X1861926Y-219I0J7874D01*
G01X1854331Y-1969D02*
G03Y-13780I0J-5906D01*
G01Y-1969D02*
G03Y-13780I0J-5906D01*
G01D02*
X1856975D01*
G01X1856976D02*
X1854331D01*
G01X1856976D02*
X1854331D01*
G01D02*
X1856975D01*
G01X1854331Y-1969D02*
G03Y-13780I0J-5906D01*
G01Y-1969D02*
G03Y-13780I0J-5906D01*
G01Y-1969D02*
X1856976D01*
G01X1856975D02*
X1854331D01*
G01X1856975D02*
X1854331D01*
G01D02*
X1856976D01*
G01X1891654Y246772D02*
X1972441D01*
G01X1891654D02*
X1972441D01*
G01X1891654D02*
X1972441D01*
G01X1891654D02*
X1972441D01*
G01X1887717Y250709D02*
G03X1891654Y246772I3937J0D01*
G01X1887717Y250709D02*
G03X1891654Y246772I3937J0D01*
G01X1887717Y263307D02*
Y250709D01*
G01Y263307D02*
Y250709D01*
G01Y263307D02*
Y250709D01*
G01Y263307D02*
Y250709D01*
G01D02*
G03X1891654Y246772I3937J0D01*
G01X1887717Y250709D02*
G03X1891654Y246772I3937J0D01*
G01X1887717Y263307D02*
G03X1883780Y267244I-3937J0D01*
G01X1887717Y263307D02*
G03X1883780Y267244I-3937J0D01*
G01X1887717Y263307D02*
G03X1883780Y267244I-3937J0D01*
G01X1887717Y263307D02*
G03X1883780Y267244I-3937J0D01*
G01X1881890Y634252D02*
G03Y626378I0J-3937D01*
G01Y634252D02*
X1972441D01*
G01X1881890D02*
X1972441D01*
G01X1881890D02*
G03Y626378I0J-3937D01*
G01X1851181D02*
G03Y634252I0J3937D01*
G01Y626378D02*
G03Y634252I0J3937D01*
G01X1856976Y616535D02*
G03X1861926Y618285I0J7874D01*
G01X1856975Y616535D02*
G03X1861924Y618285I0J7874D01*
G01X1856975Y616535D02*
G03X1861924Y618285I0J7874D01*
G01X1861926Y602975D02*
G03Y618285I6186J7655D01*
G01X1861924Y602975D02*
G03Y618285I6186J7655D01*
G01Y602975D02*
G03Y618285I6186J7655D01*
G01Y602975D02*
G03Y618285I6186J7655D01*
G01Y602975D02*
G03Y618285I6186J7655D01*
G01X1861926Y602975D02*
G03Y618285I6186J7655D01*
G01X1856975Y616535D02*
G03X1861924Y618285I0J7874D01*
G01X1856975Y616535D02*
G03X1861924Y618285I0J7874D01*
G01X1856976Y616535D02*
G03X1861926Y618285I0J7874D01*
G01Y602975D02*
G03X1856976Y604724I-4948J-6125D01*
G01X1861924Y602975D02*
G03X1856975Y604724I-4948J-6125D01*
G01X1861924Y602975D02*
G03X1856975Y604724I-4948J-6125D01*
G01X1861924Y602975D02*
G03X1856975Y604724I-4948J-6125D01*
G01X1861924Y602975D02*
G03X1856975Y604724I-4948J-6125D01*
G01X1861926Y602975D02*
G03X1856976Y604724I-4948J-6125D01*
G01X1854331Y616535D02*
G03Y604724I0J-5905D01*
G01Y616535D02*
G03Y604724I0J-5905D01*
G01D02*
X1856975D01*
G01X1856976D02*
X1854331D01*
G01X1856976D02*
X1854331D01*
G01D02*
X1856975D01*
G01X1854331Y616535D02*
G03Y604724I0J-5905D01*
G01Y616535D02*
G03Y604724I0J-5905D01*
G01Y616535D02*
X1856976D01*
G01X1856975D02*
X1854331D01*
G01X1856975D02*
X1854331D01*
G01D02*
X1856976D01*
G01X1972441Y-11811D02*
X1906890D01*
G01X1904921Y-9843D02*
G03X1906890Y-11811I1969J1D01*
G01X1904921Y53150D02*
Y-9843D01*
G01X1972441Y-11811D02*
X1906890D01*
G01X1904921Y-9843D02*
G03X1906890Y-11811I1969J1D01*
G01X1904921Y53150D02*
Y-9843D01*
G01X1923071Y53150D02*
Y-9843D01*
G01X1940787Y-3937D02*
X1972441D01*
G01X1940787D02*
G03X1938819Y-5906I0J-1968D01*
G01Y-9843D02*
Y-5906D01*
G01Y-9843D02*
G03X1940787Y-11811I1968J0D01*
G01X1921102D02*
G03X1923071Y-9843I0J1969D01*
G01X1906890Y55118D02*
G03X1904921Y53150I0J-1969D01*
G01X1972441Y55118D02*
X1906890D01*
G01X1972441D02*
X1906890D01*
G01X1972441D02*
X1906890D01*
G01X1972441D02*
X1906890D01*
G01D02*
G03X1904921Y53150I0J-1969D01*
G01X1923071D02*
G03X1921102Y55118I-1969J-1D01*
G01X1940787D02*
G03X1938819Y53150I0J-1968D01*
G01Y49213D02*
Y53150D01*
G01Y49213D02*
G03X1940787Y47244I1968J-1D01*
G01X1972441D02*
X1940787D01*
G01X1976378Y-35433D02*
G03X1972441Y-31496I-3937J0D01*
G01X1976378Y-59055D02*
Y-35433D01*
G01Y-59055D02*
Y-35433D01*
G01D02*
G03X1972441Y-31496I-3937J0D01*
G01Y-62992D02*
G03X1976378Y-59055I0J3937D01*
G01X1972441Y-62992D02*
G03X1976378Y-59055I0J3937D01*
G01X1972441Y-23622D02*
G03X1976378Y-19685I0J3937D01*
G01X1972441Y-23622D02*
G03X1976378Y-19685I0J3937D01*
G01X1972441Y-23622D02*
G03X1976378Y-19685I0J3937D01*
G01X1972441Y-23622D02*
G03X1976378Y-19685I0J3937D01*
G01D02*
Y-15748D01*
G01Y-19685D02*
Y-15748D01*
G01Y-19685D02*
Y-15748D01*
G01Y-19685D02*
Y-15748D01*
G01D02*
G03X1972441Y-11811I-3937J0D01*
G01X1976378Y-15748D02*
G03X1972441Y-11811I-3937J0D01*
G01X1976378Y-15748D02*
G03X1972441Y-11811I-3937J0D01*
G01X1976378Y-15748D02*
G03X1972441Y-11811I-3937J0D01*
G01X1976378Y0D02*
Y43307D01*
G01X1972441Y-3937D02*
G03X1976378Y0I0J3937D01*
G01X1972441Y55118D02*
G03X1976378Y59055I0J3937D01*
G01X1972441Y55118D02*
G03X1976378Y59055I0J3937D01*
G01X1972441Y55118D02*
G03X1976378Y59055I0J3937D01*
G01X1972441Y55118D02*
G03X1976378Y59055I0J3937D01*
G01D02*
Y242835D01*
G01Y59055D02*
Y242835D01*
G01Y59055D02*
Y242835D01*
G01Y59055D02*
Y242835D01*
G01Y43307D02*
G03X1972441Y47244I-3937J0D01*
G01X1976378Y242835D02*
G03X1972441Y246772I-3937J0D01*
G01X1976378Y242835D02*
G03X1972441Y246772I-3937J0D01*
G01X1976378Y242835D02*
G03X1972441Y246772I-3937J0D01*
G01X1976378Y242835D02*
G03X1972441Y246772I-3937J0D01*
G01Y432598D02*
G03X1976378Y436535I0J3937D01*
G01X1972441Y432598D02*
G03X1976378Y436535I0J3937D01*
G01X1972441Y432598D02*
G03X1976378Y436535I0J3937D01*
G01X1972441Y432598D02*
G03X1976378Y436535I0J3937D01*
G01D02*
Y622441D01*
G01Y436535D02*
Y622441D01*
G01Y436535D02*
Y622441D01*
G01Y436535D02*
Y622441D01*
G01D02*
G03X1972441Y626378I-3937J0D01*
G01X1976378Y622441D02*
G03X1972441Y626378I-3937J0D01*
G01X1976378Y622441D02*
G03X1972441Y626378I-3937J0D01*
G01X1976378Y622441D02*
G03X1972441Y626378I-3937J0D01*
G01Y634252D02*
G03X1976378Y638189I0J3937D01*
G01X1972441Y634252D02*
G03X1976378Y638189I0J3937D01*
G01D02*
Y661811D01*
G01Y638189D02*
Y661811D01*
G01D02*
G03X1972441Y665748I-3937J0D01*
G01X1976378Y661811D02*
G03X1972441Y665748I-3937J0D01*
G54D12*
G01X-21327Y177898D02*
X-11679Y168250D01*
G01X-21327Y333872D02*
Y177898D01*
G01X-19776Y261965D02*
Y246665D01*
G01Y333229D02*
Y264124D01*
G01X-4249Y350950D02*
X-21327Y333872D01*
G01X46011Y17874D02*
X52779Y11106D01*
G01X46011Y81914D02*
Y17874D01*
G01X53368Y89271D02*
X46011Y81914D01*
G01X41757Y153332D02*
X53368Y141721D01*
G01X41757Y163244D02*
Y153332D01*
G01X36751Y168250D02*
X41757Y163244D01*
G01X-11679Y168250D02*
X36751D01*
G01X30984Y350950D02*
X-4249D01*
G01X36883Y356849D02*
X30984Y350950D01*
G01X36883Y411914D02*
Y356849D01*
G01X32260Y416537D02*
X36883Y411914D01*
G01X32260Y427637D02*
Y416537D01*
G01X47746Y443123D02*
X32260Y427637D01*
G01X40512Y467244D02*
X47746Y460010D01*
G01X71257Y-21647D02*
X406158D01*
G01X68931Y-19321D02*
X71257Y-21647D01*
G01X68931Y-12254D02*
Y-19321D01*
G01X65085Y-8408D02*
X68931Y-12254D01*
G01X61537Y-8408D02*
X65085D01*
G01X54951Y-1822D02*
X61537Y-8408D01*
G01X54951Y1149D02*
Y-1822D01*
G01X52779Y3321D02*
X54951Y1149D01*
G01X52779Y11106D02*
Y3321D01*
G01X53368Y141721D02*
Y89271D01*
G01X47746Y460010D02*
Y443123D01*
G01X263756Y210761D02*
X262828Y209833D01*
G01X264786Y210761D02*
X263756D01*
G01X272509Y218484D02*
X264786Y210761D01*
G01X284818Y217285D02*
G03X286124Y218072I-59J1575D01*
G01X284689Y217285D02*
X284818D01*
G01X282744Y216122D02*
G02X284689Y217285I2015J-1162D01*
G01X281423Y215334D02*
G03X282744Y216122I-44J1575D01*
G01X281294Y215334D02*
X281423D01*
G01X279364Y214172D02*
G02X281294Y215334I2015J-1163D01*
G01X278058Y213385D02*
G03X279364Y214172I-59J1575D01*
G01X277929Y213385D02*
X278058D01*
G01X275984Y209897D02*
G02X277929Y213385I2015J1163D01*
G01X274690Y207535D02*
G03X275984Y209897I-71J1574D01*
G01X274549Y207535D02*
X274690D01*
G01X272604Y204047D02*
G02X274549Y207535I2015J1163D01*
G01X272623Y204013D02*
X272604Y204047D01*
G01X271320Y201686D02*
G03X272623Y204013I-81J1574D01*
G01X270543Y201686D02*
X271320D01*
G01X268688Y199831D02*
X270543Y201686D01*
G01X264478Y211511D02*
X272201Y219234D01*
G01X263650Y211511D02*
X264478D01*
G01X262828Y212333D02*
X263650Y211511D01*
G01X289677Y189470D02*
X288531D01*
G01X290575Y190368D02*
X289677Y189470D01*
G01X290575Y196345D02*
Y190368D01*
G01X289504Y198196D02*
X290575Y196345D01*
G01X289469Y200462D02*
G03X289504Y198196I2050J-1102D01*
G01Y200522D02*
X289469Y200462D01*
G01X289523Y200556D02*
X289504Y200522D01*
G01Y202097D02*
G02X289523Y200556I-1365J-787D01*
G01X291434Y205585D02*
G03X289504Y202097I85J-2325D01*
G01X291590Y205585D02*
X291434D01*
G01X292884Y206372D02*
G02X291590Y205585I-1365J787D01*
G01X294829Y207535D02*
G03X292884Y206372I70J-2325D01*
G01X263550Y216611D02*
X262828Y217333D01*
G01X265306Y216611D02*
X263550D01*
G01X271829Y223134D02*
X265306Y216611D01*
G01X269148Y205141D02*
X268948Y204941D01*
G01X269148Y206241D02*
Y205141D01*
G01X269658Y206751D02*
X269148Y206241D01*
G01X269658Y207563D02*
Y206751D01*
G01X269692Y207623D02*
X269658Y207563D01*
G01X269874Y207946D02*
X269692Y207623D01*
G01X271195Y208734D02*
G03X269874Y207946I44J-1575D01*
G01X271324Y208734D02*
X271195D01*
G01X273254Y212222D02*
G02X271324Y208734I-2015J-1163D01*
G01X274575Y214584D02*
G03X273254Y212222I44J-1575D01*
G01X274689Y214584D02*
X274575D01*
G01X276634Y215747D02*
G02X274689Y214584I-2015J1162D01*
G01X277955Y216535D02*
G03X276634Y215747I44J-1575D01*
G01X278084Y216535D02*
X277955D01*
G01X280014Y217697D02*
G02X278084Y216535I-2015J1163D01*
G01X281320Y218484D02*
G03X280014Y217697I59J-1575D01*
G01X284962Y190551D02*
Y189437D01*
G01X287085Y192674D02*
X284962Y190551D01*
G01X287085Y199360D02*
Y192674D01*
G01X286774Y200522D02*
G02X287085Y199360I-2015J-1162D01*
G01X286755Y200556D02*
X286774Y200522D01*
G01Y202097D02*
G03X286755Y200556I1365J-787D01*
G01X286774Y204423D02*
G02Y202097I-2015J-1163D01*
G01X288068Y206784D02*
G03X286774Y204423I71J-1574D01*
G01X288224Y206784D02*
X288068D01*
G01X290154Y207946D02*
G02X288224Y206784I-2015J1163D01*
G01X291475Y208734D02*
G03X290154Y207946I44J-1575D01*
G01X291570Y208734D02*
X291475D01*
G01X293534Y209897D02*
G02X291570Y208734I-2015J1163D01*
G01X290312Y189037D02*
Y186920D01*
G01X291325Y190050D02*
X290312Y189037D01*
G01X291325Y196547D02*
Y190050D01*
G01X290154Y198572D02*
X291325Y196547D01*
G01X290135Y200113D02*
G03X290154Y198572I1384J-754D01*
G01Y200147D02*
X290135Y200113D01*
G01X290179Y200189D02*
X290154Y200147D01*
G01Y202472D02*
G02X290179Y200189I-2015J-1164D01*
G01X291448Y204834D02*
G03X290154Y202472I71J-1574D01*
G01X291589Y204834D02*
X291448D01*
G01X293534Y205997D02*
G02X291589Y204834I-2015J1162D01*
G01X278058Y217285D02*
G03X279364Y218072I-59J1575D01*
G01X277929Y217285D02*
X278058D01*
G01X275984Y216122D02*
G02X277929Y217285I2015J-1162D01*
G01X274663Y215334D02*
G03X275984Y216122I-44J1575D01*
G01X274534Y215334D02*
X274663D01*
G01X272604Y211846D02*
G02X274534Y215334I2015J1163D01*
G01X271283Y209484D02*
G03X272604Y211846I-44J1575D01*
G01X271154Y209484D02*
X271283D01*
G01X269224Y208322D02*
G02X271154Y209484I2015J-1163D01*
G01X269092Y208093D02*
X269224Y208322D01*
G01X268724Y207455D02*
X269092Y208093D01*
G01X268079Y206810D02*
X268724Y207455D01*
G01X267080Y206810D02*
X268079D01*
G01X284647Y191440D02*
X283489D01*
G01X286336Y193129D02*
X284647Y191440D01*
G01X286336Y199358D02*
Y193129D01*
G01X286334Y199360D02*
X286336Y199358D01*
G01X286124Y200147D02*
G02X286334Y199360I-1365J-786D01*
G01X286099Y200189D02*
X286124Y200147D01*
G01Y202472D02*
G03X286099Y200189I2015J-1164D01*
G01X286143Y204013D02*
G02X286124Y202472I-1384J-754D01*
G01Y204047D02*
X286143Y204013D01*
G01X288069Y207535D02*
G03X286124Y204047I70J-2325D01*
G01X288210Y207535D02*
X288069D01*
G01X289504Y208322D02*
G02X288210Y207535I-1365J787D01*
G01X291468Y209485D02*
G03X289504Y208322I51J-2326D01*
G01X291578Y209485D02*
X291468D01*
G01X292884Y210272D02*
G02X291578Y209485I-1365J788D01*
G01X294814Y211434D02*
G03X292884Y210272I85J-2325D01*
G01X272498Y199492D02*
X270337Y197331D01*
G01X272498Y200787D02*
Y199492D01*
G01X273254Y202097D02*
X272498Y200787D01*
G01X273254Y204423D02*
G02Y202097I-2015J-1163D01*
G01X274548Y206784D02*
G03X273254Y204423I71J-1574D01*
G01X274704Y206784D02*
X274548D01*
G01X276634Y210272D02*
G02X274704Y206784I-2015J-1163D01*
G01X277955Y212635D02*
G03X276634Y210272I44J-1575D01*
G01X278084Y212635D02*
X277955D01*
G01X280014Y213797D02*
G02X278084Y212635I-2015J1163D01*
G01X281320Y214584D02*
G03X280014Y213797I59J-1575D01*
G01X281449Y214584D02*
X281320D01*
G01X283394Y215747D02*
G02X281449Y214584I-2015J1162D01*
G01X284715Y216535D02*
G03X283394Y215747I44J-1575D01*
G01X284844Y216535D02*
X284715D01*
G01X286774Y217697D02*
G02X284844Y216535I-2015J1163D01*
G01X288080Y218484D02*
G03X286774Y217697I59J-1575D01*
G01X263856Y215861D02*
X262828Y214833D01*
G01X265617Y215861D02*
X263856D01*
G01X272140Y222384D02*
X265617Y215861D01*
G01X292168Y247735D02*
X293923Y246872D01*
G01X291475Y247735D02*
X292168D01*
G01X290154Y246947D02*
G02X291475Y247735I1365J-787D01*
G01X288209Y245784D02*
G03X290154Y246947I-70J2325D01*
G01X288080Y245784D02*
X288209D01*
G01X286774Y244997D02*
G02X288080Y245784I1365J-788D01*
G01X284844Y243835D02*
G03X286774Y244997I-85J2325D01*
G01X284715Y243835D02*
X284844D01*
G01X283394Y243047D02*
G02X284715Y243835I1365J-787D01*
G01X281449Y241884D02*
G03X283394Y243047I-70J2325D01*
G01X281320Y241884D02*
X281449D01*
G01X280014Y241097D02*
G02X281320Y241884I1365J-788D01*
G01X278084Y239935D02*
G03X280014Y241097I-85J2325D01*
G01X277955Y239935D02*
X278084D01*
G01X276634Y239147D02*
G02X277955Y239935I1365J-787D01*
G01X274689Y237984D02*
G03X276634Y239147I-70J2325D01*
G01X274549Y237984D02*
X274689D01*
G01X272604Y239147D02*
G03X274549Y237984I2015J1162D01*
G01X269874Y239147D02*
G02X272604I1365J-787D01*
G01X269376Y238284D02*
X269874Y239147D01*
G01X266433Y235341D02*
X269376Y238284D01*
G01X258347Y235341D02*
X266433D01*
G01X257448Y234442D02*
X258347Y235341D01*
G01X292884Y254747D02*
G03X294829Y253584I2015J1162D01*
G01X290154Y254747D02*
G02X292884I1365J-787D01*
G01X288209Y253584D02*
G03X290154Y254747I-70J2325D01*
G01X288080Y253584D02*
X288209D01*
G01X286774Y252797D02*
G02X288080Y253584I1365J-788D01*
G01X284844Y251635D02*
G03X286774Y252797I-85J2325D01*
G01X284715Y251635D02*
X284844D01*
G01X283394Y250847D02*
G02X284715Y251635I1365J-787D01*
G01X281449Y249684D02*
G03X283394Y250847I-70J2325D01*
G01X281320Y249684D02*
X281449D01*
G01X280014Y248897D02*
G02X281320Y249684I1365J-788D01*
G01X278084Y247735D02*
G03X280014Y248897I-85J2325D01*
G01X277955Y247735D02*
X278084D01*
G01X276634Y246947D02*
G02X277955Y247735I1365J-787D01*
G01X274689Y245784D02*
G03X276634Y246947I-70J2325D01*
G01X274549Y245784D02*
X274689D01*
G01X272604Y246947D02*
G03X274549Y245784I2015J1162D01*
G01X269874Y246947D02*
G02X272604I1365J-787D01*
G01X267929Y245784D02*
G03X269874Y246947I-70J2325D01*
G01X267789Y245784D02*
X267929D01*
G01X265844Y246947D02*
G03X267789Y245784I2015J1162D01*
G01X264523Y247735D02*
G02X265844Y246947I-44J-1575D01*
G01X259527Y247735D02*
X264523D01*
G01X257772Y245980D02*
X259527Y247735D01*
G01X291661Y256285D02*
X294899Y255909D01*
G01X291449Y256285D02*
X291661D01*
G01X289504Y255122D02*
G02X291449Y256285I2015J-1162D01*
G01X288183Y254334D02*
G03X289504Y255122I-44J1575D01*
G01X288054Y254334D02*
X288183D01*
G01X286124Y253172D02*
G02X288054Y254334I2015J-1163D01*
G01X284818Y252385D02*
G03X286124Y253172I-59J1575D01*
G01X284689Y252385D02*
X284818D01*
G01X282744Y251222D02*
G02X284689Y252385I2015J-1162D01*
G01X281423Y250434D02*
G03X282744Y251222I-44J1575D01*
G01X281294Y250434D02*
X281423D01*
G01X279364Y249272D02*
G02X281294Y250434I2015J-1163D01*
G01X278058Y248485D02*
G03X279364Y249272I-59J1575D01*
G01X277929Y248485D02*
X278058D01*
G01X275984Y247322D02*
G02X277929Y248485I2015J-1162D01*
G01X273254Y247322D02*
G03X275984I1365J787D01*
G01X271309Y248485D02*
G02X273254Y247322I-70J-2325D01*
G01X271169Y248485D02*
X271309D01*
G01X269224Y247322D02*
G02X271169Y248485I2015J-1162D01*
G01X266494Y247322D02*
G03X269224I1365J787D01*
G01X264549Y248485D02*
G02X266494Y247322I-70J-2325D01*
G01X258506Y248485D02*
X264549D01*
G01X274689Y218484D02*
X272509D01*
G01X276634Y219647D02*
G02X274689Y218484I-2015J1162D01*
G01X277955Y220435D02*
G03X276634Y219647I44J-1575D01*
G01X278084Y220435D02*
X277955D01*
G01X280014Y221597D02*
G02X278084Y220435I-2015J1163D01*
G01X281320Y222384D02*
G03X280014Y221597I59J-1575D01*
G01X281449Y222384D02*
X281320D01*
G01X283394Y223547D02*
G02X281449Y222384I-2015J1162D01*
G01X284715Y224335D02*
G03X283394Y223547I44J-1575D01*
G01X284844Y224335D02*
X284715D01*
G01X286774Y225497D02*
G02X284844Y224335I-2015J1163D01*
G01X288080Y226284D02*
G03X286774Y225497I59J-1575D01*
G01X288190Y226284D02*
X288080D01*
G01X290154Y227447D02*
G02X288190Y226284I-2015J1163D01*
G01X291448Y228234D02*
G03X290154Y227447I71J-1574D01*
G01X291589Y228234D02*
X291448D01*
G01X293534Y229397D02*
G02X291589Y228234I-2015J1162D01*
G01X292884Y266447D02*
G03X294829Y265284I2015J1162D01*
G01X290154Y266447D02*
G02X292884I1365J-787D01*
G01X288209Y265284D02*
G03X290154Y266447I-70J2325D01*
G01X288080Y265284D02*
X288209D01*
G01X286774Y264497D02*
G02X288080Y265284I1365J-788D01*
G01X284844Y263335D02*
G03X286774Y264497I-85J2325D01*
G01X284715Y263335D02*
X284844D01*
G01X283394Y262547D02*
G02X284715Y263335I1365J-787D01*
G01X281449Y261384D02*
G03X283394Y262547I-70J2325D01*
G01X281320Y261384D02*
X281449D01*
G01X280014Y260597D02*
G02X281320Y261384I1365J-788D01*
G01X278084Y259435D02*
G03X280014Y260597I-85J2325D01*
G01X277955Y259435D02*
X278084D01*
G01X276634Y258647D02*
G02X277955Y259435I1365J-787D01*
G01X274689Y257484D02*
G03X276634Y258647I-70J2325D01*
G01X274549Y257484D02*
X274689D01*
G01X272604Y258647D02*
G03X274549Y257484I2015J1162D01*
G01X269874Y258647D02*
G02X272604I1365J-787D01*
G01X267929Y257484D02*
G03X269874Y258647I-70J2325D01*
G01X267789Y257484D02*
X267929D01*
G01X265844Y258647D02*
G03X267789Y257484I2015J1162D01*
G01X264523Y259435D02*
G02X265844Y258647I-44J-1575D01*
G01X262323Y259435D02*
X264523D01*
G01X262018Y259130D02*
X262323Y259435D01*
G01X260086Y259130D02*
X262018D01*
G01X292884Y221972D02*
G02X294814Y223134I2015J-1163D01*
G01X291578Y221185D02*
G03X292884Y221972I-59J1575D01*
G01X291449Y221185D02*
X291578D01*
G01X289504Y220022D02*
G02X291449Y221185I2015J-1162D01*
G01X288183Y219234D02*
G03X289504Y220022I-44J1575D01*
G01X288054Y219234D02*
X288183D01*
G01X286124Y218072D02*
G02X288054Y219234I2015J-1163D01*
G01X292950Y229888D02*
X294899Y232509D01*
G01X292884Y229772D02*
X292950Y229888D01*
G01X291590Y228985D02*
G03X292884Y229772I-71J1574D01*
G01X291434Y228985D02*
X291590D01*
G01X289504Y227823D02*
G02X291434Y228985I2015J-1163D01*
G01X288183Y227035D02*
G03X289504Y227823I-44J1575D01*
G01X288088Y227035D02*
X288183D01*
G01X286124Y225872D02*
G02X288088Y227035I2015J-1163D01*
G01X284818Y225085D02*
G03X286124Y225872I-59J1575D01*
G01X284689Y225085D02*
X284818D01*
G01X282744Y223922D02*
G02X284689Y225085I2015J-1162D01*
G01X281423Y223134D02*
G03X282744Y223922I-44J1575D01*
G01X281294Y223134D02*
X281423D01*
G01X279364Y221972D02*
G02X281294Y223134I2015J-1163D01*
G01X278058Y221185D02*
G03X279364Y221972I-59J1575D01*
G01X277929Y221185D02*
X278058D01*
G01X275984Y220022D02*
G02X277929Y221185I2015J-1162D01*
G01X274663Y219234D02*
G03X275984Y220022I-44J1575D01*
G01X272201Y219234D02*
X274663D01*
G01Y223134D02*
X271829D01*
G01X275984Y223922D02*
G02X274663Y223134I-1365J787D01*
G01X277929Y225085D02*
G03X275984Y223922I70J-2325D01*
G01X278058Y225085D02*
X277929D01*
G01X279364Y225872D02*
G02X278058Y225085I-1365J788D01*
G01X281328Y227035D02*
G03X279364Y225872I51J-2326D01*
G01X281423Y227035D02*
X281328D01*
G01X282744Y227823D02*
G02X281423Y227035I-1365J787D01*
G01X284674Y228985D02*
G03X282744Y227823I85J-2325D01*
G01X284830Y228985D02*
X284674D01*
G01X286124Y229772D02*
G02X284830Y228985I-1365J787D01*
G01X288069Y230935D02*
G03X286124Y229772I70J-2325D01*
G01X288210Y230935D02*
X288069D01*
G01X289504Y231722D02*
G02X288210Y230935I-1365J787D01*
G01X291468Y232885D02*
G03X289504Y231722I51J-2326D01*
G01X291578Y232885D02*
X291468D01*
G01X292884Y233672D02*
G02X291578Y232885I-1365J788D01*
G01X292950Y233788D02*
X292884Y233672D01*
G01X294899Y236409D02*
X292950Y233788D01*
G01X281449Y218484D02*
X281320D01*
G01X283394Y219647D02*
G02X281449Y218484I-2015J1162D01*
G01X284715Y220435D02*
G03X283394Y219647I44J-1575D01*
G01X284844Y220435D02*
X284715D01*
G01X286774Y221597D02*
G02X284844Y220435I-2015J1163D01*
G01X288080Y222384D02*
G03X286774Y221597I59J-1575D01*
G01X288209Y222384D02*
X288080D01*
G01X290154Y223547D02*
G02X288209Y222384I-2015J1162D01*
G01X291475Y224335D02*
G03X290154Y223547I44J-1575D01*
G01X291604Y224335D02*
X291475D01*
G01X293534Y225497D02*
G02X291604Y224335I-2015J1163D01*
G01X291589Y267985D02*
G02X293534Y266822I-70J-2325D01*
G01X291449Y267985D02*
X291589D01*
G01X289504Y266822D02*
G02X291449Y267985I2015J-1162D01*
G01X288183Y266034D02*
G03X289504Y266822I-44J1575D01*
G01X288054Y266034D02*
X288183D01*
G01X286124Y264872D02*
G02X288054Y266034I2015J-1163D01*
G01X284818Y264085D02*
G03X286124Y264872I-59J1575D01*
G01X284689Y264085D02*
X284818D01*
G01X282744Y262922D02*
G02X284689Y264085I2015J-1162D01*
G01X281423Y262134D02*
G03X282744Y262922I-44J1575D01*
G01X281294Y262134D02*
X281423D01*
G01X279364Y260972D02*
G02X281294Y262134I2015J-1163D01*
G01X278058Y260185D02*
G03X279364Y260972I-59J1575D01*
G01X277929Y260185D02*
X278058D01*
G01X275984Y259022D02*
G02X277929Y260185I2015J-1162D01*
G01X273254Y259022D02*
G03X275984I1365J787D01*
G01X271309Y260185D02*
G02X273254Y259022I-70J-2325D01*
G01X271169Y260185D02*
X271309D01*
G01X269224Y259022D02*
G02X271169Y260185I2015J-1162D01*
G01X266494Y259022D02*
G03X269224I1365J787D01*
G01X264549Y260185D02*
G02X266494Y259022I-70J-2325D01*
G01X262568Y260185D02*
X264549D01*
G01X261123Y261630D02*
X262568Y260185D01*
G01X260369Y261630D02*
X261123D01*
G01X292168Y248485D02*
X293959Y249374D01*
G01X291449Y248485D02*
X292168D01*
G01X289504Y247322D02*
G02X291449Y248485I2015J-1162D01*
G01X288183Y246534D02*
G03X289504Y247322I-44J1575D01*
G01X288054Y246534D02*
X288183D01*
G01X286124Y245372D02*
G02X288054Y246534I2015J-1163D01*
G01X284818Y244585D02*
G03X286124Y245372I-59J1575D01*
G01X284689Y244585D02*
X284818D01*
G01X282744Y243422D02*
G02X284689Y244585I2015J-1162D01*
G01X281423Y242634D02*
G03X282744Y243422I-44J1575D01*
G01X281294Y242634D02*
X281423D01*
G01X279364Y241472D02*
G02X281294Y242634I2015J-1163D01*
G01X278058Y240685D02*
G03X279364Y241472I-59J1575D01*
G01X277929Y240685D02*
X278058D01*
G01X275984Y239522D02*
G02X277929Y240685I2015J-1162D01*
G01X273254Y239522D02*
G03X275984I1365J787D01*
G01X271309Y240685D02*
G02X273254Y239522I-70J-2325D01*
G01X271169Y240685D02*
X271309D01*
G01X269224Y239522D02*
G02X271169Y240685I2015J-1162D01*
G01X268886Y238936D02*
X269224Y239522D01*
G01X266039Y236089D02*
X268886Y238936D01*
G01X258103Y236089D02*
X266039D01*
G01X257250Y236942D02*
X258103Y236089D01*
G01X292884Y270347D02*
G03X294829Y269184I2015J1162D01*
G01X290154Y270347D02*
G02X292884I1365J-787D01*
G01X288209Y269184D02*
G03X290154Y270347I-70J2325D01*
G01X288080Y269184D02*
X288209D01*
G01X286774Y268397D02*
G02X288080Y269184I1365J-788D01*
G01X284844Y267235D02*
G03X286774Y268397I-85J2325D01*
G01X284715Y267235D02*
X284844D01*
G01X283394Y266447D02*
G02X284715Y267235I1365J-787D01*
G01X281449Y265284D02*
G03X283394Y266447I-70J2325D01*
G01X281320Y265284D02*
X281449D01*
G01X280014Y264497D02*
G02X281320Y265284I1365J-788D01*
G01X278084Y263335D02*
G03X280014Y264497I-85J2325D01*
G01X277955Y263335D02*
X278084D01*
G01X276634Y262547D02*
G02X277955Y263335I1365J-787D01*
G01X274689Y261384D02*
G03X276634Y262547I-70J2325D01*
G01X274549Y261384D02*
X274689D01*
G01X272604Y262547D02*
G03X274549Y261384I2015J1162D01*
G01X269874Y262547D02*
G02X272604I1365J-787D01*
G01X267929Y261384D02*
G03X269874Y262547I-70J2325D01*
G01X267789Y261384D02*
X267929D01*
G01X265844Y262547D02*
G03X267789Y261384I2015J1162D01*
G01X264523Y263335D02*
G02X265844Y262547I-44J-1575D01*
G01X262201Y263335D02*
X264523D01*
G01X261406Y264130D02*
X262201Y263335D01*
G01X260368Y264130D02*
X261406D01*
G01X292884Y225872D02*
G02X294848Y227035I2015J-1163D01*
G01X291578Y225085D02*
G03X292884Y225872I-59J1575D01*
G01X291449Y225085D02*
X291578D01*
G01X289504Y223922D02*
G02X291449Y225085I2015J-1162D01*
G01X288183Y223134D02*
G03X289504Y223922I-44J1575D01*
G01X288054Y223134D02*
X288183D01*
G01X286124Y221972D02*
G02X288054Y223134I2015J-1163D01*
G01X284818Y221185D02*
G03X286124Y221972I-59J1575D01*
G01X284689Y221185D02*
X284818D01*
G01X282744Y220022D02*
G02X284689Y221185I2015J-1162D01*
G01X281423Y219234D02*
G03X282744Y220022I-44J1575D01*
G01X281294Y219234D02*
X281423D01*
G01X279364Y218072D02*
G02X281294Y219234I2015J-1163D01*
G01X292000Y251635D02*
X293960Y250744D01*
G01X291475Y251635D02*
X292000D01*
G01X290154Y250847D02*
G02X291475Y251635I1365J-787D01*
G01X288209Y249684D02*
G03X290154Y250847I-70J2325D01*
G01X288080Y249684D02*
X288209D01*
G01X286774Y248897D02*
G02X288080Y249684I1365J-788D01*
G01X284844Y247735D02*
G03X286774Y248897I-85J2325D01*
G01X284715Y247735D02*
X284844D01*
G01X283394Y246947D02*
G02X284715Y247735I1365J-787D01*
G01X281449Y245784D02*
G03X283394Y246947I-70J2325D01*
G01X281320Y245784D02*
X281449D01*
G01X280014Y244997D02*
G02X281320Y245784I1365J-788D01*
G01X278084Y243835D02*
G03X280014Y244997I-85J2325D01*
G01X277955Y243835D02*
X278084D01*
G01X276634Y243047D02*
G02X277955Y243835I1365J-787D01*
G01X274689Y241884D02*
G03X276634Y243047I-70J2325D01*
G01X274549Y241884D02*
X274689D01*
G01X272604Y243047D02*
G03X274549Y241884I2015J1162D01*
G01X269874Y243047D02*
G02X272604I1365J-787D01*
G01X267929Y241884D02*
G03X269874Y243047I-70J2325D01*
G01X267061Y241884D02*
X267929D01*
G01X265687Y243058D02*
G03X267061Y241884I2172J1151D01*
G01X264834Y243835D02*
G02X265687Y243058I-655J-1575D01*
G01X263427Y243835D02*
X264834D01*
G01X261476Y241884D02*
X263427Y243835D01*
G01X259991Y241884D02*
X261476D01*
G01X259087Y240980D02*
X259991Y241884D01*
G01X292268Y243835D02*
X293809Y243071D01*
G01X291475Y243835D02*
X292268D01*
G01X290154Y243047D02*
G02X291475Y243835I1365J-787D01*
G01X288209Y241884D02*
G03X290154Y243047I-70J2325D01*
G01X288080Y241884D02*
X288209D01*
G01X286774Y241097D02*
G02X288080Y241884I1365J-788D01*
G01X284844Y239935D02*
G03X286774Y241097I-85J2325D01*
G01X284715Y239935D02*
X284844D01*
G01X283394Y239147D02*
G02X284715Y239935I1365J-787D01*
G01X281449Y237984D02*
G03X283394Y239147I-70J2325D01*
G01X281320Y237984D02*
X281449D01*
G01X280014Y237197D02*
G02X281320Y237984I1365J-788D01*
G01X278084Y236035D02*
G03X280014Y237197I-85J2325D01*
G01X277955Y236035D02*
X278084D01*
G01X276634Y235247D02*
G02X277955Y236035I1365J-787D01*
G01X274689Y234084D02*
G03X276634Y235247I-70J2325D01*
G01X270734Y234084D02*
X274689D01*
G01X266621Y229971D02*
X270734Y234084D01*
G01X258057Y229971D02*
X266621D01*
G01X257128Y229042D02*
X258057Y229971D01*
G01X261205Y266630D02*
X259321D01*
G01X262368Y265467D02*
X261205Y266630D01*
G01X262368Y265060D02*
Y265467D01*
G01X263343Y264085D02*
X262368Y265060D01*
G01X264549Y264085D02*
X263343D01*
G01X266494Y262922D02*
G03X264549Y264085I-2015J-1162D01*
G01X269224Y262922D02*
G02X266494I-1365J787D01*
G01X271169Y264085D02*
G03X269224Y262922I70J-2325D01*
G01X271309Y264085D02*
X271169D01*
G01X273254Y262922D02*
G03X271309Y264085I-2015J-1162D01*
G01X275984Y262922D02*
G02X273254I-1365J787D01*
G01X277929Y264085D02*
G03X275984Y262922I70J-2325D01*
G01X278058Y264085D02*
X277929D01*
G01X279364Y264872D02*
G02X278058Y264085I-1365J788D01*
G01X281294Y266034D02*
G03X279364Y264872I85J-2325D01*
G01X281423Y266034D02*
X281294D01*
G01X282744Y266822D02*
G02X281423Y266034I-1365J787D01*
G01X284689Y267985D02*
G03X282744Y266822I70J-2325D01*
G01X284818Y267985D02*
X284689D01*
G01X286124Y268772D02*
G02X284818Y267985I-1365J788D01*
G01X288054Y269934D02*
G03X286124Y268772I85J-2325D01*
G01X288183Y269934D02*
X288054D01*
G01X289504Y270722D02*
G02X288183Y269934I-1365J787D01*
G01X291449Y271885D02*
G03X289504Y270722I70J-2325D01*
G01X291589Y271885D02*
X291449D01*
G01X293534Y270722D02*
G03X291589Y271885I-2015J-1162D01*
G01X288209Y218484D02*
X288080D01*
G01X290154Y219647D02*
G02X288209Y218484I-2015J1162D01*
G01X291475Y220435D02*
G03X290154Y219647I44J-1575D01*
G01X291604Y220435D02*
X291475D01*
G01X293534Y221597D02*
G02X291604Y220435I-2015J1163D01*
G01X292062Y252385D02*
X294858Y252060D01*
G01X291449Y252385D02*
X292062D01*
G01X289504Y251222D02*
G02X291449Y252385I2015J-1162D01*
G01X288183Y250434D02*
G03X289504Y251222I-44J1575D01*
G01X288054Y250434D02*
X288183D01*
G01X286124Y249272D02*
G02X288054Y250434I2015J-1163D01*
G01X284818Y248485D02*
G03X286124Y249272I-59J1575D01*
G01X284689Y248485D02*
X284818D01*
G01X282744Y247322D02*
G02X284689Y248485I2015J-1162D01*
G01X281423Y246534D02*
G03X282744Y247322I-44J1575D01*
G01X281294Y246534D02*
X281423D01*
G01X279364Y245372D02*
G02X281294Y246534I2015J-1163D01*
G01X278058Y244585D02*
G03X279364Y245372I-59J1575D01*
G01X277929Y244585D02*
X278058D01*
G01X275984Y243422D02*
G02X277929Y244585I2015J-1162D01*
G01X273254Y243422D02*
G03X275984I1365J787D01*
G01X271309Y244585D02*
G02X273254Y243422I-70J-2325D01*
G01X271169Y244585D02*
X271309D01*
G01X269224Y243422D02*
G02X271169Y244585I2015J-1162D01*
G01X267903Y242634D02*
G03X269224Y243422I-44J1575D01*
G01X267204Y242634D02*
X267903D01*
G01X266351Y243411D02*
G03X267204Y242634I1508J798D01*
G01X264977Y244585D02*
G02X266351Y243411I-798J-2325D01*
G01X263116Y244585D02*
X264977D01*
G01X262897Y244366D02*
X263116Y244585D01*
G01X262897Y244364D02*
Y244366D01*
G01X262898Y244364D02*
X262897D01*
G01X261166Y242632D02*
X262898Y244364D01*
G01X260803Y242632D02*
X261166D01*
G01X260800Y242635D02*
X260803Y242632D01*
G01X259854Y242635D02*
X260800D01*
G01X259009Y243480D02*
X259854Y242635D01*
G01X292168Y244585D02*
X293959Y245474D01*
G01X291449Y244585D02*
X292168D01*
G01X289504Y243422D02*
G02X291449Y244585I2015J-1162D01*
G01X288183Y242634D02*
G03X289504Y243422I-44J1575D01*
G01X288054Y242634D02*
X288183D01*
G01X286124Y241472D02*
G02X288054Y242634I2015J-1163D01*
G01X284818Y240685D02*
G03X286124Y241472I-59J1575D01*
G01X284689Y240685D02*
X284818D01*
G01X282744Y239522D02*
G02X284689Y240685I2015J-1162D01*
G01X281423Y238734D02*
G03X282744Y239522I-44J1575D01*
G01X281294Y238734D02*
X281423D01*
G01X279364Y237572D02*
G02X281294Y238734I2015J-1163D01*
G01X278058Y236785D02*
G03X279364Y237572I-59J1575D01*
G01X277929Y236785D02*
X278058D01*
G01X275984Y235622D02*
G02X277929Y236785I2015J-1162D01*
G01X274663Y234834D02*
G03X275984Y235622I-44J1575D01*
G01X270423Y234834D02*
X274663D01*
G01X266310Y230721D02*
X270423Y234834D01*
G01X257949Y230721D02*
X266310D01*
G01X257128Y231542D02*
X257949Y230721D01*
G01X274689Y222384D02*
X272140D01*
G01X276634Y223547D02*
G02X274689Y222384I-2015J1162D01*
G01X277955Y224335D02*
G03X276634Y223547I44J-1575D01*
G01X278084Y224335D02*
X277955D01*
G01X280014Y225497D02*
G02X278084Y224335I-2015J1163D01*
G01X281320Y226284D02*
G03X280014Y225497I59J-1575D01*
G01X281430Y226284D02*
X281320D01*
G01X283394Y227447D02*
G02X281430Y226284I-2015J1163D01*
G01X284688Y228234D02*
G03X283394Y227447I71J-1574D01*
G01X284829Y228234D02*
X284688D01*
G01X286774Y229397D02*
G02X284829Y228234I-2015J1162D01*
G01X288068Y230184D02*
G03X286774Y229397I71J-1574D01*
G01X288224Y230184D02*
X288068D01*
G01X290154Y231346D02*
G02X288224Y230184I-2015J1163D01*
G01X291475Y232134D02*
G03X290154Y231346I44J-1575D01*
G01X291570Y232134D02*
X291475D01*
G01X293534Y233297D02*
G02X291570Y232134I-2015J1163D01*
G01X264051Y334287D02*
X263808Y334324D01*
G01X265576Y334287D02*
X264051D01*
G01X266773Y335484D02*
X265576Y334287D01*
G01X267918Y335484D02*
X266773D01*
G01X269224Y334697D02*
G03X267918Y335484I-1365J-788D01*
G01X271154Y333535D02*
G02X269224Y334697I85J2325D01*
G01X271283Y333535D02*
X271154D01*
G01X272604Y332747D02*
G03X271283Y333535I-1365J-787D01*
G01X274549Y331584D02*
G02X272604Y332747I70J2325D01*
G01X274678Y331584D02*
X274549D01*
G01X275984Y330797D02*
G03X274678Y331584I-1365J-788D01*
G01X277914Y329635D02*
G02X275984Y330797I85J2325D01*
G01X278043Y329635D02*
X277914D01*
G01X279364Y328847D02*
G03X278043Y329635I-1365J-787D01*
G01X281309Y327684D02*
G02X279364Y328847I70J2325D01*
G01X281450Y327684D02*
X281309D01*
G01X282744Y326897D02*
G03X281450Y327684I-1365J-787D01*
G01X284674Y325735D02*
G02X282744Y326897I85J2325D01*
G01X284803Y325735D02*
X284674D01*
G01X286124Y324947D02*
G03X284803Y325735I-1365J-787D01*
G01X288088Y323784D02*
G02X286124Y324947I51J2326D01*
G01X288198Y323784D02*
X288088D01*
G01X289504Y322997D02*
G03X288198Y323784I-1365J-788D01*
G01X291434Y321835D02*
G02X289504Y322997I85J2325D01*
G01X291604Y321835D02*
X291434D01*
G01X293534Y322997D02*
G02X291604Y321835I-2015J1163D01*
G01Y306235D02*
G03X293534Y307397I-85J2325D01*
G01X291434Y306235D02*
X291604D01*
G01X289504Y307397D02*
G03X291434Y306235I2015J1163D01*
G01X288198Y308184D02*
G02X289504Y307397I-59J-1575D01*
G01X288069Y308184D02*
X288198D01*
G01X286124Y309347D02*
G03X288069Y308184I2015J1162D01*
G01X284803Y310135D02*
G02X286124Y309347I-44J-1575D01*
G01X284674Y310135D02*
X284803D01*
G01X282744Y311297D02*
G03X284674Y310135I2015J1163D01*
G01X281438Y312084D02*
G02X282744Y311297I-59J-1575D01*
G01X281309Y312084D02*
X281438D01*
G01X279364Y313247D02*
G03X281309Y312084I2015J1162D01*
G01X278043Y314035D02*
G02X279364Y313247I-44J-1575D01*
G01X277914Y314035D02*
X278043D01*
G01X275984Y315197D02*
G03X277914Y314035I2015J1163D01*
G01X274678Y315984D02*
G02X275984Y315197I-59J-1575D01*
G01X273683Y315984D02*
X274678D01*
G01X272455Y317045D02*
G03X273683Y315984I2164J1264D01*
G01X271570Y317798D02*
G02X272455Y317045I-631J-1638D01*
G01X270981Y317841D02*
X271570Y317798D01*
G01X270241Y317841D02*
X270981D01*
G01X268300Y315900D02*
X270241Y317841D01*
G01X266200Y315900D02*
X268300D01*
G01X264900Y317200D02*
X266200Y315900D01*
G01X291604Y317935D02*
G03X293534Y319097I-85J2325D01*
G01X291434Y317935D02*
X291604D01*
G01X289504Y319097D02*
G03X291434Y317935I2015J1163D01*
G01X288198Y319884D02*
G02X289504Y319097I-59J-1575D01*
G01X288069Y319884D02*
X288198D01*
G01X286124Y321047D02*
G03X288069Y319884I2015J1162D01*
G01X284803Y321835D02*
G02X286124Y321047I-44J-1575D01*
G01X284674Y321835D02*
X284803D01*
G01X282744Y322997D02*
G03X284674Y321835I2015J1163D01*
G01X281438Y323784D02*
G02X282744Y322997I-59J-1575D01*
G01X281328Y323784D02*
X281438D01*
G01X279364Y324947D02*
G03X281328Y323784I2015J1163D01*
G01X278043Y325735D02*
G02X279364Y324947I-44J-1575D01*
G01X277914Y325735D02*
X278043D01*
G01X275984Y326897D02*
G03X277914Y325735I2015J1163D01*
G01X274690Y327684D02*
G02X275984Y326897I-71J-1574D01*
G01X274549Y327684D02*
X274690D01*
G01X272604Y328847D02*
G03X274549Y327684I2015J1162D01*
G01X271283Y329635D02*
G02X272604Y328847I-44J-1575D01*
G01X271154Y329635D02*
X271283D01*
G01X269224Y330797D02*
G03X271154Y329635I2015J1163D01*
G01X267918Y331584D02*
G02X269224Y330797I-59J-1575D01*
G01X267061Y331584D02*
X267918D01*
G01X273254Y340922D02*
G03X271309Y342085I-2015J-1162D01*
G01X274575Y340134D02*
G02X273254Y340922I44J1575D01*
G01X274704Y340134D02*
X274575D01*
G01X276634Y338972D02*
G03X274704Y340134I-2015J-1163D01*
G01X277940Y338185D02*
G02X276634Y338972I59J1575D01*
G01X278069Y338185D02*
X277940D01*
G01X280014Y337022D02*
G03X278069Y338185I-2015J-1162D01*
G01X281335Y336234D02*
G02X280014Y337022I44J1575D01*
G01X281464Y336234D02*
X281335D01*
G01X283394Y335072D02*
G03X281464Y336234I-2015J-1163D01*
G01X284700Y334285D02*
G02X283394Y335072I59J1575D01*
G01X284829Y334285D02*
X284700D01*
G01X286774Y333122D02*
G03X284829Y334285I-2015J-1162D01*
G01X288095Y332334D02*
G02X286774Y333122I44J1575D01*
G01X288224Y332334D02*
X288095D01*
G01X290154Y331172D02*
G03X288224Y332334I-2015J-1163D01*
G01X291460Y330385D02*
G02X290154Y331172I59J1575D01*
G01X291578Y330385D02*
X291460D01*
G01X292884Y331172D02*
G02X291578Y330385I-1365J788D01*
G01X294814Y332334D02*
G03X292884Y331172I85J-2325D01*
G01X268400Y323700D02*
X265700D01*
G01X270265Y321835D02*
X268400Y323700D01*
G01X271283Y321835D02*
X270265D01*
G01X272604Y321047D02*
G03X271283Y321835I-1365J-787D01*
G01X274549Y319884D02*
G02X272604Y321047I70J2325D01*
G01X274678Y319884D02*
X274549D01*
G01X275984Y319097D02*
G03X274678Y319884I-1365J-788D01*
G01X277914Y317935D02*
G02X275984Y319097I85J2325D01*
G01X278043Y317935D02*
X277914D01*
G01X279364Y317147D02*
G03X278043Y317935I-1365J-787D01*
G01X281309Y315984D02*
G02X279364Y317147I70J2325D01*
G01X281438Y315984D02*
X281309D01*
G01X282744Y315197D02*
G03X281438Y315984I-1365J-788D01*
G01X284674Y314035D02*
G02X282744Y315197I85J2325D01*
G01X284803Y314035D02*
X284674D01*
G01X286124Y313247D02*
G03X284803Y314035I-1365J-787D01*
G01X288069Y312084D02*
G02X286124Y313247I70J2325D01*
G01X288198Y312084D02*
X288069D01*
G01X289504Y311297D02*
G03X288198Y312084I-1365J-788D01*
G01X291434Y310135D02*
G02X289504Y311297I85J2325D01*
G01X291604Y310135D02*
X291434D01*
G01X293534Y311297D02*
G02X291604Y310135I-2015J1163D01*
G01X292884Y319472D02*
G02X294814Y320634I2015J-1163D01*
G01X291578Y318685D02*
G03X292884Y319472I-59J1575D01*
G01X291460Y318685D02*
X291578D01*
G01X290154Y319472D02*
G03X291460Y318685I1365J788D01*
G01X288224Y320634D02*
G02X290154Y319472I-85J-2325D01*
G01X288095Y320634D02*
X288224D01*
G01X286774Y321422D02*
G03X288095Y320634I1365J787D01*
G01X284829Y322585D02*
G02X286774Y321422I-70J-2325D01*
G01X284700Y322585D02*
X284829D01*
G01X283394Y323372D02*
G03X284700Y322585I1365J788D01*
G01X281430Y324535D02*
G02X283394Y323372I-51J-2326D01*
G01X281335Y324535D02*
X281430D01*
G01X280014Y325323D02*
G03X281335Y324535I1365J787D01*
G01X278084Y326485D02*
G02X280014Y325323I-85J-2325D01*
G01X277955Y326485D02*
X278084D01*
G01X276634Y327273D02*
G03X277955Y326485I1365J787D01*
G01X274704Y328435D02*
G02X276634Y327273I-85J-2325D01*
G01X274548Y328435D02*
X274704D01*
G01X273254Y329222D02*
G03X274548Y328435I1365J787D01*
G01X271309Y330385D02*
G02X273254Y329222I-70J-2325D01*
G01X271180Y330385D02*
X271309D01*
G01X269874Y331172D02*
G03X271180Y330385I1365J788D01*
G01X267944Y332334D02*
G02X269874Y331172I-85J-2325D01*
G01X267204Y332334D02*
X267944D01*
G01X266351Y333111D02*
G03X267204Y332334I1508J798D01*
G01X265646Y333535D02*
G02X266351Y333111I0J-797D01*
G01X263936Y333535D02*
X265646D01*
G01X256959Y338039D02*
X256398Y338600D01*
G01X261346Y338039D02*
X256959D01*
G01X262604Y339297D02*
X261346Y338039D01*
G01X262604Y340497D02*
Y339297D01*
G01X263442Y341335D02*
X262604Y340497D01*
G01X265844Y340547D02*
G03X264523Y341335I-1365J-787D01*
G01X267789Y339384D02*
G02X265844Y340547I70J2325D01*
G01X267918Y339384D02*
X267789D01*
G01X269224Y338597D02*
G03X267918Y339384I-1365J-788D01*
G01X271154Y337435D02*
G02X269224Y338597I85J2325D01*
G01X271283Y337435D02*
X271154D01*
G01X272604Y336647D02*
G03X271283Y337435I-1365J-787D01*
G01X274549Y335484D02*
G02X272604Y336647I70J2325D01*
G01X274678Y335484D02*
X274549D01*
G01X275984Y334697D02*
G03X274678Y335484I-1365J-788D01*
G01X277914Y333535D02*
G02X275984Y334697I85J2325D01*
G01X278043Y333535D02*
X277914D01*
G01X279364Y332747D02*
G03X278043Y333535I-1365J-787D01*
G01X281309Y331584D02*
G02X279364Y332747I70J2325D01*
G01X281438Y331584D02*
X281309D01*
G01X282744Y330797D02*
G03X281438Y331584I-1365J-788D01*
G01X284674Y329635D02*
G02X282744Y330797I85J2325D01*
G01X284803Y329635D02*
X284674D01*
G01X286124Y328847D02*
G03X284803Y329635I-1365J-787D01*
G01X288069Y327684D02*
G02X286124Y328847I70J2325D01*
G01X288210Y327684D02*
X288069D01*
G01X289504Y326897D02*
G03X288210Y327684I-1365J-787D01*
G01X291434Y325735D02*
G02X289504Y326897I85J2325D01*
G01X291604Y325735D02*
X291434D01*
G01X293534Y326897D02*
G02X291604Y325735I-2015J1163D01*
G01X292884Y323372D02*
G02X294848Y324535I2015J-1163D01*
G01X291578Y322585D02*
G03X292884Y323372I-59J1575D01*
G01X291460Y322585D02*
X291578D01*
G01X290154Y323372D02*
G03X291460Y322585I1365J788D01*
G01X288190Y324535D02*
G02X290154Y323372I-51J-2326D01*
G01X288095Y324535D02*
X288190D01*
G01X286774Y325323D02*
G03X288095Y324535I1365J787D01*
G01X284844Y326485D02*
G02X286774Y325323I-85J-2325D01*
G01X284715Y326485D02*
X284844D01*
G01X283394Y327273D02*
G03X284715Y326485I1365J787D01*
G01X281464Y328435D02*
G02X283394Y327273I-85J-2325D01*
G01X281308Y328435D02*
X281464D01*
G01X280014Y329222D02*
G03X281308Y328435I1365J787D01*
G01X278069Y330385D02*
G02X280014Y329222I-70J-2325D01*
G01X277940Y330385D02*
X278069D01*
G01X276634Y331172D02*
G03X277940Y330385I1365J788D01*
G01X274704Y332334D02*
G02X276634Y331172I-85J-2325D01*
G01X274575Y332334D02*
X274704D01*
G01X273254Y333122D02*
G03X274575Y332334I1365J787D01*
G01X271309Y334285D02*
G02X273254Y333122I-70J-2325D01*
G01X271180Y334285D02*
X271309D01*
G01X269874Y335072D02*
G03X271180Y334285I1365J788D01*
G01X267944Y336234D02*
G02X269874Y335072I-85J-2325D01*
G01X267204Y336234D02*
X267944D01*
G01X266351Y337011D02*
G03X267204Y336234I1508J798D01*
G01X265505Y337520D02*
G02X266351Y337011I0J-957D01*
G01X263568Y337520D02*
X265505D01*
G01X265700Y324451D02*
X263751Y326400D01*
G01X266012Y324451D02*
X265700D01*
G01X266014Y324449D02*
X266012Y324451D01*
G01X268712Y324449D02*
X266014D01*
G01X270576Y322585D02*
X268712Y324449D01*
G01X271309Y322585D02*
X270576D01*
G01X273254Y321422D02*
G03X271309Y322585I-2015J-1162D01*
G01X274575Y320634D02*
G02X273254Y321422I44J1575D01*
G01X274704Y320634D02*
X274575D01*
G01X276634Y319472D02*
G03X274704Y320634I-2015J-1163D01*
G01X277940Y318685D02*
G02X276634Y319472I59J1575D01*
G01X278069Y318685D02*
X277940D01*
G01X280014Y317522D02*
G03X278069Y318685I-2015J-1162D01*
G01X281335Y316734D02*
G02X280014Y317522I44J1575D01*
G01X281464Y316734D02*
X281335D01*
G01X283394Y315572D02*
G03X281464Y316734I-2015J-1163D01*
G01X284700Y314785D02*
G02X283394Y315572I59J1575D01*
G01X284829Y314785D02*
X284700D01*
G01X286774Y313622D02*
G03X284829Y314785I-2015J-1162D01*
G01X288095Y312834D02*
G02X286774Y313622I44J1575D01*
G01X288224Y312834D02*
X288095D01*
G01X290154Y311672D02*
G03X288224Y312834I-2015J-1163D01*
G01X291460Y310885D02*
G02X290154Y311672I59J1575D01*
G01X291578Y310885D02*
X291460D01*
G01X292884Y311672D02*
G02X291578Y310885I-1365J788D01*
G01X296914Y311672D02*
G03X292884I-2015J-1163D01*
G01X272604Y340547D02*
G03X271283Y341335I-1365J-787D01*
G01X274549Y339384D02*
G02X272604Y340547I70J2325D01*
G01X274678Y339384D02*
X274549D01*
G01X275984Y338597D02*
G03X274678Y339384I-1365J-788D01*
G01X277914Y337435D02*
G02X275984Y338597I85J2325D01*
G01X278043Y337435D02*
X277914D01*
G01X279364Y336647D02*
G03X278043Y337435I-1365J-787D01*
G01X281309Y335484D02*
G02X279364Y336647I70J2325D01*
G01X281438Y335484D02*
X281309D01*
G01X282744Y334697D02*
G03X281438Y335484I-1365J-788D01*
G01X284674Y333535D02*
G02X282744Y334697I85J2325D01*
G01X284803Y333535D02*
X284674D01*
G01X286124Y332747D02*
G03X284803Y333535I-1365J-787D01*
G01X288069Y331584D02*
G02X286124Y332747I70J2325D01*
G01X288198Y331584D02*
X288069D01*
G01X289504Y330797D02*
G03X288198Y331584I-1365J-788D01*
G01X291434Y329635D02*
G02X289504Y330797I85J2325D01*
G01X291604Y329635D02*
X291434D01*
G01X293534Y330797D02*
G02X291604Y329635I-2015J1163D01*
G01X292118Y341335D02*
X293958Y340446D01*
G01X292884Y327273D02*
G02X294814Y328435I2015J-1163D01*
G01X290154Y327273D02*
G03X292884I1365J787D01*
G01X288224Y328435D02*
G02X290154Y327273I-85J-2325D01*
G01X288068Y328435D02*
X288224D01*
G01X286774Y329222D02*
G03X288068Y328435I1365J787D01*
G01X284829Y330385D02*
G02X286774Y329222I-70J-2325D01*
G01X284700Y330385D02*
X284829D01*
G01X283394Y331172D02*
G03X284700Y330385I1365J788D01*
G01X281464Y332334D02*
G02X283394Y331172I-85J-2325D01*
G01X281335Y332334D02*
X281464D01*
G01X280014Y333122D02*
G03X281335Y332334I1365J787D01*
G01X278069Y334285D02*
G02X280014Y333122I-70J-2325D01*
G01X277940Y334285D02*
X278069D01*
G01X276634Y335072D02*
G03X277940Y334285I1365J788D01*
G01X274704Y336234D02*
G02X276634Y335072I-85J-2325D01*
G01X274575Y336234D02*
X274704D01*
G01X273254Y337022D02*
G03X274575Y336234I1365J787D01*
G01X271309Y338185D02*
G02X273254Y337022I-70J-2325D01*
G01X271180Y338185D02*
X271309D01*
G01X269874Y338972D02*
G03X271180Y338185I1365J788D01*
G01X267944Y340134D02*
G02X269874Y338972I-85J-2325D01*
G01X267815Y340134D02*
X267944D01*
G01X266494Y340922D02*
G03X267815Y340134I1365J787D01*
G01X264549Y342085D02*
G02X266494Y340922I-70J-2325D01*
G01X261854Y340808D02*
X263131Y342085D01*
G01X261854Y339642D02*
Y340808D01*
G01X261001Y338789D02*
X261854Y339642D01*
G01X258467Y338789D02*
X261001D01*
G01X256756Y340500D02*
X258467Y338789D01*
G01X292884Y307772D02*
G02X294814Y308934I2015J-1163D01*
G01X291578Y306985D02*
G03X292884Y307772I-59J1575D01*
G01X291460Y306985D02*
X291578D01*
G01X290154Y307772D02*
G03X291460Y306985I1365J788D01*
G01X288224Y308934D02*
G02X290154Y307772I-85J-2325D01*
G01X288095Y308934D02*
X288224D01*
G01X286774Y309722D02*
G03X288095Y308934I1365J787D01*
G01X284829Y310885D02*
G02X286774Y309722I-70J-2325D01*
G01X284700Y310885D02*
X284829D01*
G01X283394Y311672D02*
G03X284700Y310885I1365J788D01*
G01X281464Y312834D02*
G02X283394Y311672I-85J-2325D01*
G01X281335Y312834D02*
X281464D01*
G01X280014Y313622D02*
G03X281335Y312834I1365J787D01*
G01X278069Y314785D02*
G02X280014Y313622I-70J-2325D01*
G01X277940Y314785D02*
X278069D01*
G01X276634Y315572D02*
G03X277940Y314785I1365J788D01*
G01X274704Y316734D02*
G02X276634Y315572I-85J-2325D01*
G01X273844Y316734D02*
X274704D01*
G01X273103Y317424D02*
G03X273844Y316734I1516J885D01*
G01X271723Y318540D02*
G02X273103Y317424I-784J-2380D01*
G01X271045Y318591D02*
X271723Y318540D01*
G01X271037Y318600D02*
X271045Y318591D01*
G01X269926Y318600D02*
X271037D01*
G01X267985Y316659D02*
X269926Y318600D01*
G01X266515Y316659D02*
X267985D01*
G01X265438Y317736D02*
X266515Y316659D01*
G01X265438Y317738D02*
Y317736D01*
G01X291589Y353785D02*
G02X293534Y352622I-70J-2325D01*
G01X291460Y353785D02*
X291589D01*
G01X290154Y354572D02*
G03X291460Y353785I1365J788D01*
G01X288224Y355734D02*
G02X290154Y354572I-85J-2325D01*
G01X288095Y355734D02*
X288224D01*
G01X286774Y356522D02*
G03X288095Y355734I1365J787D01*
G01X284829Y357685D02*
G02X286774Y356522I-70J-2325D01*
G01X284700Y357685D02*
X284829D01*
G01X283394Y358472D02*
G03X284700Y357685I1365J788D01*
G01X281464Y359634D02*
G02X283394Y358472I-85J-2325D01*
G01X281335Y359634D02*
X281464D01*
G01X280014Y360422D02*
G03X281335Y359634I1365J787D01*
G01X278069Y361585D02*
G02X280014Y360422I-70J-2325D01*
G01X277940Y361585D02*
X278069D01*
G01X276634Y362372D02*
G03X277940Y361585I1365J788D01*
G01X274704Y363534D02*
G02X276634Y362372I-85J-2325D01*
G01X272855Y363534D02*
X274704D01*
G01X269648Y366741D02*
X272855Y363534D01*
G01X265648Y366741D02*
X269648D01*
G01X258248Y374141D02*
X265648Y366741D01*
G01X254275Y374141D02*
X258248D01*
G01X253248Y375168D02*
X254275Y374141D01*
G01X272740Y400314D02*
Y403207D01*
G01X273254Y399422D02*
X272740Y400314D01*
G01X274575Y398634D02*
G02X273254Y399422I44J1575D01*
G01X274704Y398634D02*
X274575D01*
G01X276634Y395146D02*
G03X274704Y398634I-2015J1163D01*
G01X276634Y393572D02*
G02Y395146I1365J787D01*
G01X276659Y393530D02*
X276634Y393572D01*
G01Y391247D02*
G03X276659Y393530I-2015J1164D01*
G01X276634Y389673D02*
G02Y391247I1365J787D01*
G01Y387347D02*
G03Y389673I-2015J1163D01*
G01X277955Y384985D02*
G02X276634Y387347I44J1575D01*
G01X278069Y384985D02*
X277955D01*
G01X280014Y383822D02*
G03X278069Y384985I-2015J-1162D01*
G01X281335Y383034D02*
G02X280014Y383822I44J1575D01*
G01X281464Y383034D02*
X281335D01*
G01X283394Y381872D02*
G03X281464Y383034I-2015J-1163D01*
G01X284700Y381085D02*
G02X283394Y381872I59J1575D01*
G01X284829Y381085D02*
X284700D01*
G01X286774Y379922D02*
G03X284829Y381085I-2015J-1162D01*
G01X288095Y379134D02*
G02X286774Y379922I44J1575D01*
G01X288224Y379134D02*
X288095D01*
G01X290154Y377972D02*
G03X288224Y379134I-2015J-1163D01*
G01X291460Y377185D02*
G02X290154Y377972I59J1575D01*
G01X291589Y377185D02*
X291460D01*
G01X293534Y376022D02*
G03X291589Y377185I-2015J-1162D01*
G01X253828Y344089D02*
X252989Y344928D01*
G01X260488Y344089D02*
X253828D01*
G01X262384Y345985D02*
X260488Y344089D01*
G01X264533Y345985D02*
X262384D01*
G01X266494Y344822D02*
G03X264533Y345985I-2015J-1162D01*
G01X267815Y344034D02*
G02X266494Y344822I44J1575D01*
G01X267944Y344034D02*
X267815D01*
G01X269874Y342872D02*
G03X267944Y344034I-2015J-1163D01*
G01X271180Y342085D02*
G02X269874Y342872I59J1575D01*
G01X271309Y342085D02*
X271180D01*
G01X254862Y367841D02*
X254448Y367427D01*
G01X259148Y367841D02*
X254862D01*
G01X263848Y363141D02*
X259148Y367841D01*
G01X268248Y363141D02*
X263848D01*
G01X271678Y359711D02*
X268248Y363141D01*
G01X272756Y359711D02*
X271678D01*
G01X273583Y358884D02*
X272756Y359711D01*
G01X274678Y358884D02*
X273583D01*
G01X275984Y358097D02*
G03X274678Y358884I-1365J-788D01*
G01X277914Y356935D02*
G02X275984Y358097I85J2325D01*
G01X278043Y356935D02*
X277914D01*
G01X279364Y356147D02*
G03X278043Y356935I-1365J-787D01*
G01X281309Y354984D02*
G02X279364Y356147I70J2325D01*
G01X281438Y354984D02*
X281309D01*
G01X282744Y354197D02*
G03X281438Y354984I-1365J-788D01*
G01X284674Y353035D02*
G02X282744Y354197I85J2325D01*
G01X284803Y353035D02*
X284674D01*
G01X286124Y352247D02*
G03X284803Y353035I-1365J-787D01*
G01X288069Y351084D02*
G02X286124Y352247I70J2325D01*
G01X288198Y351084D02*
X288069D01*
G01X289504Y350297D02*
G03X288198Y351084I-1365J-788D01*
G01X291434Y349135D02*
G02X289504Y350297I85J2325D01*
G01X291563Y349135D02*
X291434D01*
G01X292884Y348347D02*
G03X291563Y349135I-1365J-787D01*
G01X294829Y347184D02*
G02X292884Y348347I70J2325D01*
G01X254040Y373393D02*
X253248Y372601D01*
G01X257938Y373393D02*
X254040D01*
G01X265338Y365993D02*
X257938Y373393D01*
G01X269338Y365993D02*
X265338D01*
G01X272326Y363005D02*
X269338Y365993D01*
G01X272325Y363005D02*
X272326D01*
G01X272325Y363003D02*
Y363005D01*
G01X272544Y362784D02*
X272325Y363003D01*
G01X274678Y362784D02*
X272544D01*
G01X275984Y361997D02*
G03X274678Y362784I-1365J-788D01*
G01X277914Y360835D02*
G02X275984Y361997I85J2325D01*
G01X278043Y360835D02*
X277914D01*
G01X279364Y360047D02*
G03X278043Y360835I-1365J-787D01*
G01X281309Y358884D02*
G02X279364Y360047I70J2325D01*
G01X281438Y358884D02*
X281309D01*
G01X282744Y358097D02*
G03X281438Y358884I-1365J-788D01*
G01X284674Y356935D02*
G02X282744Y358097I85J2325D01*
G01X284803Y356935D02*
X284674D01*
G01X286124Y356147D02*
G03X284803Y356935I-1365J-787D01*
G01X288069Y354984D02*
G02X286124Y356147I70J2325D01*
G01X288198Y354984D02*
X288069D01*
G01X289504Y354197D02*
G03X288198Y354984I-1365J-788D01*
G01X291434Y353035D02*
G02X289504Y354197I85J2325D01*
G01X291563Y353035D02*
X291434D01*
G01X292884Y352247D02*
G03X291563Y353035I-1365J-787D01*
G01X294829Y351084D02*
G02X292884Y352247I70J2325D01*
G01X250147Y362431D02*
X249205Y363373D01*
G01X261058Y362431D02*
X250147D01*
G01X262780Y360709D02*
X261058Y362431D01*
G01X265764Y360709D02*
X262780D01*
G01X266839Y359634D02*
X265764Y360709D01*
G01X267944Y359634D02*
X266839D01*
G01X269874Y358472D02*
G03X267944Y359634I-2015J-1163D01*
G01X271019Y357699D02*
G02X269874Y358472I215J1554D01*
G01X271520Y357669D02*
G03X271019Y357699I-493J-4042D01*
G01X273254Y356522D02*
G03X271520Y357669I-2016J-1163D01*
G01X274575Y355734D02*
G02X273254Y356522I44J1575D01*
G01X274704Y355734D02*
X274575D01*
G01X276634Y354572D02*
G03X274704Y355734I-2015J-1163D01*
G01X277940Y353785D02*
G02X276634Y354572I59J1575D01*
G01X278069Y353785D02*
X277940D01*
G01X280014Y352622D02*
G03X278069Y353785I-2015J-1162D01*
G01X281335Y351834D02*
G02X280014Y352622I44J1575D01*
G01X281464Y351834D02*
X281335D01*
G01X283394Y350672D02*
G03X281464Y351834I-2015J-1163D01*
G01X284700Y349885D02*
G02X283394Y350672I59J1575D01*
G01X284829Y349885D02*
X284700D01*
G01X286774Y348722D02*
G03X284829Y349885I-2015J-1162D01*
G01X288095Y347934D02*
G02X286774Y348722I44J1575D01*
G01X288224Y347934D02*
X288095D01*
G01X290154Y346772D02*
G03X288224Y347934I-2015J-1163D01*
G01X291460Y345985D02*
G02X290154Y346772I59J1575D01*
G01X291661Y345985D02*
X291460D01*
G01X294899Y345609D02*
X291661Y345985D01*
G01X256477Y389489D02*
X255677Y390289D01*
G01X264458Y389489D02*
X256477D01*
G01X265696Y388251D02*
X264458Y389489D01*
G01X265696Y379851D02*
Y388251D01*
G01X267358Y378189D02*
X265696Y379851D01*
G01X271119Y378189D02*
X267358D01*
G01X273133Y376175D02*
X271119Y378189D01*
G01X273254Y376022D02*
G03X273133Y376175I-580J-335D01*
G01X274548Y375235D02*
G02X273254Y376022I71J1574D01*
G01X274689Y375235D02*
X274548D01*
G01X276634Y374072D02*
G03X274689Y375235I-2015J-1162D01*
G01X277940Y373285D02*
G02X276634Y374072I59J1575D01*
G01X278050Y373285D02*
X277940D01*
G01X280014Y372122D02*
G03X278050Y373285I-2015J-1163D01*
G01X281308Y371335D02*
G02X280014Y372122I71J1574D01*
G01X281449Y371335D02*
X281308D01*
G01X283394Y370172D02*
G03X281449Y371335I-2015J-1162D01*
G01X284688Y369385D02*
G02X283394Y370172I71J1574D01*
G01X284844Y369385D02*
X284688D01*
G01X286774Y368223D02*
G03X284844Y369385I-2015J-1163D01*
G01X288095Y367435D02*
G02X286774Y368223I44J1575D01*
G01X288190Y367435D02*
X288095D01*
G01X290154Y366272D02*
G03X288190Y367435I-2015J-1163D01*
G01X291460Y365485D02*
G02X290154Y366272I59J1575D01*
G01X291661Y365485D02*
X291460D01*
G01X294899Y365109D02*
X291661Y365485D01*
G01X264523Y341335D02*
X263442D01*
G01X250448Y361683D02*
X249621Y360856D01*
G01X260748Y361683D02*
X250448D01*
G01X262470Y359961D02*
X260748Y361683D01*
G01X265454Y359961D02*
X262470D01*
G01X266531Y358884D02*
X265454Y359961D01*
G01X267918Y358884D02*
X266531D01*
G01X269224Y358097D02*
G03X267918Y358884I-1365J-788D01*
G01X271063Y356940D02*
G02X269224Y358097I178J2323D01*
G01X271412Y356926D02*
G03X271063Y356940I-274J-2484D01*
G01X272604Y356147D02*
G03X271412Y356926I-1365J-787D01*
G01X274549Y354984D02*
G02X272604Y356147I70J2325D01*
G01X274678Y354984D02*
X274549D01*
G01X275984Y354197D02*
G03X274678Y354984I-1365J-788D01*
G01X277914Y353035D02*
G02X275984Y354197I85J2325D01*
G01X278043Y353035D02*
X277914D01*
G01X279364Y352247D02*
G03X278043Y353035I-1365J-787D01*
G01X281309Y351084D02*
G02X279364Y352247I70J2325D01*
G01X281438Y351084D02*
X281309D01*
G01X282744Y350297D02*
G03X281438Y351084I-1365J-788D01*
G01X284674Y349135D02*
G02X282744Y350297I85J2325D01*
G01X284803Y349135D02*
X284674D01*
G01X286124Y348347D02*
G03X284803Y349135I-1365J-787D01*
G01X288069Y347184D02*
G02X286124Y348347I70J2325D01*
G01X288198Y347184D02*
X288069D01*
G01X289504Y346397D02*
G03X288198Y347184I-1365J-788D01*
G01X291434Y345235D02*
G02X289504Y346397I85J2325D01*
G01X291563Y345235D02*
X291434D01*
G01X292884Y344447D02*
G03X291563Y345235I-1365J-787D01*
G01X294829Y343284D02*
G02X292884Y344447I70J2325D01*
G01X260347Y394140D02*
X259499Y393292D01*
G01X268147Y394140D02*
X260347D01*
G01X269004Y393578D02*
X268147Y394140D01*
G01X269224Y393197D02*
X269004Y393578D01*
G01X269224Y391623D02*
G03Y393197I-1365J787D01*
G01Y389297D02*
G02Y391623I2015J1163D01*
G01X269243Y387756D02*
G03X269224Y389297I-1384J754D01*
G01Y387722D02*
X269243Y387756D01*
G01X269199Y387680D02*
X269224Y387722D01*
G01Y385397D02*
G02X269199Y387680I2015J1164D01*
G01X269243Y383856D02*
G03X269224Y385397I-1384J754D01*
G01X268826Y383132D02*
X269243Y383856D01*
G01X292884Y367847D02*
G03X294848Y366684I2015J1163D01*
G01X291590Y368634D02*
G02X292884Y367847I-71J-1574D01*
G01X291449Y368634D02*
X291590D01*
G01X289504Y369797D02*
G03X291449Y368634I2015J1162D01*
G01X288210Y370584D02*
G02X289504Y369797I-71J-1574D01*
G01X288054Y370584D02*
X288210D01*
G01X286124Y371746D02*
G03X288054Y370584I2015J1163D01*
G01X284803Y372534D02*
G02X286124Y371746I-44J-1575D01*
G01X284708Y372534D02*
X284803D01*
G01X282744Y373697D02*
G03X284708Y372534I2015J1163D01*
G01X281438Y374484D02*
G02X282744Y373697I-59J-1575D01*
G01X281309Y374484D02*
X281438D01*
G01X279364Y375647D02*
G03X281309Y374484I2015J1162D01*
G01X278043Y376435D02*
G02X279364Y375647I-44J-1575D01*
G01X277914Y376435D02*
X278043D01*
G01X275984Y377597D02*
G03X277914Y376435I2015J1163D01*
G01X274678Y378384D02*
G02X275984Y377597I-59J-1575D01*
G01X274549Y378384D02*
X274678D01*
G01X272604Y379547D02*
G03X274549Y378384I2015J1162D01*
G01X271283Y380335D02*
G02X272604Y379547I-44J-1575D01*
G01X270439Y380335D02*
X271283D01*
G01X268826Y383132D02*
G03X270439Y380335I2413J-472D01*
G01X250283Y357389D02*
X249436Y358236D01*
G01X262356Y357389D02*
X250283D01*
G01X262652Y357685D02*
X262356Y357389D01*
G01X264179Y357685D02*
X262652D01*
G01X266472Y356316D02*
G03X264179Y357685I-2293J-1236D01*
G01X267204Y355734D02*
G02X266472Y356316I655J1575D01*
G01X267944Y355734D02*
X267204D01*
G01X269874Y354572D02*
G03X267944Y355734I-2015J-1163D01*
G01X271180Y353785D02*
G02X269874Y354572I59J1575D01*
G01X271309Y353785D02*
X271180D01*
G01X273254Y352622D02*
G03X271309Y353785I-2015J-1162D01*
G01X274575Y351834D02*
G02X273254Y352622I44J1575D01*
G01X274704Y351834D02*
X274575D01*
G01X276634Y350672D02*
G03X274704Y351834I-2015J-1163D01*
G01X277940Y349885D02*
G02X276634Y350672I59J1575D01*
G01X278069Y349885D02*
X277940D01*
G01X280014Y348722D02*
G03X278069Y349885I-2015J-1162D01*
G01X281335Y347934D02*
G02X280014Y348722I44J1575D01*
G01X281464Y347934D02*
X281335D01*
G01X283394Y346772D02*
G03X281464Y347934I-2015J-1163D01*
G01X284700Y345985D02*
G02X283394Y346772I59J1575D01*
G01X284829Y345985D02*
X284700D01*
G01X286774Y344822D02*
G03X284829Y345985I-2015J-1162D01*
G01X288095Y344034D02*
G02X286774Y344822I44J1575D01*
G01X288224Y344034D02*
X288095D01*
G01X290154Y342872D02*
G03X288224Y344034I-2015J-1163D01*
G01X291460Y342085D02*
G02X290154Y342872I59J1575D01*
G01X292202Y342085D02*
X291460D01*
G01X292797Y342016D02*
X292202Y342085D01*
G01X294899Y341709D02*
X292797Y342016D01*
G01X254900Y368589D02*
X253558Y369931D01*
G01X259458Y368589D02*
X254900D01*
G01X264158Y363889D02*
X259458Y368589D01*
G01X268561Y363889D02*
X264158D01*
G01X271989Y360461D02*
X268561Y363889D01*
G01X273069Y360461D02*
X271989D01*
G01X273896Y359634D02*
X273069Y360461D01*
G01X274704Y359634D02*
X273896D01*
G01X276634Y358472D02*
G03X274704Y359634I-2015J-1163D01*
G01X277940Y357685D02*
G02X276634Y358472I59J1575D01*
G01X278069Y357685D02*
X277940D01*
G01X280014Y356522D02*
G03X278069Y357685I-2015J-1162D01*
G01X281335Y355734D02*
G02X280014Y356522I44J1575D01*
G01X281464Y355734D02*
X281335D01*
G01X283394Y354572D02*
G03X281464Y355734I-2015J-1163D01*
G01X284700Y353785D02*
G02X283394Y354572I59J1575D01*
G01X284829Y353785D02*
X284700D01*
G01X286774Y352622D02*
G03X284829Y353785I-2015J-1162D01*
G01X288095Y351834D02*
G02X286774Y352622I44J1575D01*
G01X288224Y351834D02*
X288095D01*
G01X290154Y350672D02*
G03X288224Y351834I-2015J-1163D01*
G01X291460Y349885D02*
G02X290154Y350672I59J1575D01*
G01X291589Y349885D02*
X291460D01*
G01X293534Y348722D02*
G03X291589Y349885I-2015J-1162D01*
G01X267476Y400444D02*
Y401870D01*
G01X268768Y399152D02*
X267476Y400444D01*
G01X269849Y397508D02*
X268768Y399152D01*
G01X269874Y397472D02*
X269849Y397508D01*
G01X271180Y396685D02*
G02X269874Y397472I59J1575D01*
G01X271290Y396685D02*
X271180D01*
G01X273279Y393239D02*
G03X271290Y396685I-2040J1120D01*
G01X273254Y393197D02*
X273279Y393239D01*
G01X273254Y391623D02*
G02Y393197I1365J787D01*
G01Y389297D02*
G03Y391623I-2015J1163D01*
G01Y387723D02*
G02Y389297I1365J787D01*
G01Y385397D02*
G03Y387723I-2015J1163D01*
G01X274575Y383035D02*
G02X273254Y385397I44J1575D01*
G01X274670Y383035D02*
X274575D01*
G01X276634Y381872D02*
G03X274670Y383035I-2015J-1163D01*
G01X277940Y381085D02*
G02X276634Y381872I59J1575D01*
G01X278069Y381085D02*
X277940D01*
G01X280014Y379922D02*
G03X278069Y381085I-2015J-1162D01*
G01X281335Y379134D02*
G02X280014Y379922I44J1575D01*
G01X281464Y379134D02*
X281335D01*
G01X283394Y377972D02*
G03X281464Y379134I-2015J-1163D01*
G01X284700Y377185D02*
G02X283394Y377972I59J1575D01*
G01X284829Y377185D02*
X284700D01*
G01X286774Y376022D02*
G03X284829Y377185I-2015J-1162D01*
G01X288095Y375234D02*
G02X286774Y376022I44J1575D01*
G01X288224Y375234D02*
X288095D01*
G01X290154Y374072D02*
G03X288224Y375234I-2015J-1163D01*
G01X291460Y373285D02*
G02X290154Y374072I59J1575D01*
G01X291570Y373285D02*
X291460D01*
G01X293534Y372122D02*
G03X291570Y373285I-2015J-1163D01*
G01X253801Y343341D02*
X252888Y342428D01*
G01X260798Y343341D02*
X253801D01*
G01X262692Y345235D02*
X260798Y343341D01*
G01X264523Y345235D02*
X262692D01*
G01X265844Y344447D02*
G03X264523Y345235I-1365J-787D01*
G01X267789Y343284D02*
G02X265844Y344447I70J2325D01*
G01X267918Y343284D02*
X267789D01*
G01X269224Y342497D02*
G03X267918Y343284I-1365J-788D01*
G01X271154Y341335D02*
G02X269224Y342497I85J2325D01*
G01X271283Y341335D02*
X271154D01*
G01X291434D02*
X292118D01*
G01X289504Y342497D02*
G03X291434Y341335I2015J1163D01*
G01X288198Y343284D02*
G02X289504Y342497I-59J-1575D01*
G01X288069Y343284D02*
X288198D01*
G01X286124Y344447D02*
G03X288069Y343284I2015J1162D01*
G01X284803Y345235D02*
G02X286124Y344447I-44J-1575D01*
G01X284674Y345235D02*
X284803D01*
G01X282744Y346397D02*
G03X284674Y345235I2015J1163D01*
G01X281438Y347184D02*
G02X282744Y346397I-59J-1575D01*
G01X281309Y347184D02*
X281438D01*
G01X279364Y348347D02*
G03X281309Y347184I2015J1162D01*
G01X278043Y349135D02*
G02X279364Y348347I-44J-1575D01*
G01X277914Y349135D02*
X278043D01*
G01X275984Y350297D02*
G03X277914Y349135I2015J1163D01*
G01X274678Y351084D02*
G02X275984Y350297I-59J-1575D01*
G01X274549Y351084D02*
X274678D01*
G01X272604Y352247D02*
G03X274549Y351084I2015J1162D01*
G01X271283Y353035D02*
G02X272604Y352247I-44J-1575D01*
G01X271154Y353035D02*
X271283D01*
G01X269224Y354197D02*
G03X271154Y353035I2015J1163D01*
G01X267918Y354984D02*
G02X269224Y354197I-59J-1575D01*
G01X267061Y354984D02*
X267918D01*
G01X265687Y356158D02*
G03X267061Y354984I2172J1151D01*
G01X264179Y356935D02*
G02X265687Y356158I0J-1852D01*
G01X262960Y356935D02*
X264179D01*
G01X262666Y356641D02*
X262960Y356935D01*
G01X250362Y356641D02*
X262666D01*
G01X249457Y355736D02*
X250362Y356641D01*
G01X263131Y342085D02*
X264549D01*
G01X266769Y400093D02*
X265699D01*
G01X268185Y398677D02*
X266769Y400093D01*
G01X269224Y397097D02*
X268185Y398677D01*
G01X271188Y395934D02*
G02X269224Y397097I51J2326D01*
G01X271283Y395934D02*
X271188D01*
G01X272604Y393572D02*
G03X271283Y395934I-1365J787D01*
G01X272579Y393530D02*
X272604Y393572D01*
G01Y391247D02*
G02X272579Y393530I2015J1164D01*
G01X272604Y389673D02*
G03Y391247I-1365J787D01*
G01Y387347D02*
G02Y389673I2015J1163D01*
G01Y385773D02*
G03Y387347I-1365J787D01*
G01X274568Y382284D02*
G02X272604Y385773I51J2326D01*
G01X274678Y382284D02*
X274568D01*
G01X275984Y381497D02*
G03X274678Y382284I-1365J-788D01*
G01X277914Y380335D02*
G02X275984Y381497I85J2325D01*
G01X278043Y380335D02*
X277914D01*
G01X279364Y379547D02*
G03X278043Y380335I-1365J-787D01*
G01X281309Y378384D02*
G02X279364Y379547I70J2325D01*
G01X281438Y378384D02*
X281309D01*
G01X282744Y377597D02*
G03X281438Y378384I-1365J-788D01*
G01X284674Y376435D02*
G02X282744Y377597I85J2325D01*
G01X284803Y376435D02*
X284674D01*
G01X286124Y375647D02*
G03X284803Y376435I-1365J-787D01*
G01X288069Y374484D02*
G02X286124Y375647I70J2325D01*
G01X288198Y374484D02*
X288069D01*
G01X289504Y373697D02*
G03X288198Y374484I-1365J-788D01*
G01X291468Y372534D02*
G02X289504Y373697I51J2326D01*
G01X291563Y372534D02*
X291468D01*
G01X292884Y371746D02*
G03X291563Y372534I-1365J-787D01*
G01X294814Y370584D02*
G02X292884Y371746I85J2325D01*
G01X290500Y399574D02*
Y405894D01*
G01X290158Y399054D02*
X290500Y399574D01*
G01X290135Y399013D02*
X290158Y399054D01*
G01X290154Y397472D02*
G02X290135Y399013I1365J787D01*
G01X290154Y395146D02*
G03Y397472I-2015J1163D01*
G01Y393572D02*
G02Y395146I1365J787D01*
G01X290179Y393530D02*
X290154Y393572D01*
G01Y391247D02*
G03X290179Y393530I-2015J1164D01*
G01X290135Y391213D02*
X290154Y391247D01*
G01X291460Y388885D02*
G02X290135Y391213I59J1575D01*
G01X291589Y388885D02*
X291460D01*
G01X293534Y387722D02*
G03X291589Y388885I-2015J-1162D01*
G01X256949Y388741D02*
X255997Y387789D01*
G01X264148Y388741D02*
X256949D01*
G01X264948Y387941D02*
X264148Y388741D01*
G01X264948Y379541D02*
Y387941D01*
G01X267048Y377441D02*
X264948Y379541D01*
G01X270809Y377441D02*
X267048D01*
G01X272604Y375646D02*
X270809Y377441D01*
G01X274534Y374484D02*
G02X272604Y375646I85J2325D01*
G01X274690Y374484D02*
X274534D01*
G01X275984Y373697D02*
G03X274690Y374484I-1365J-787D01*
G01X277948Y372534D02*
G02X275984Y373697I51J2326D01*
G01X278043Y372534D02*
X277948D01*
G01X279364Y371746D02*
G03X278043Y372534I-1365J-787D01*
G01X281294Y370584D02*
G02X279364Y371746I85J2325D01*
G01X281450Y370584D02*
X281294D01*
G01X282744Y369797D02*
G03X281450Y370584I-1365J-787D01*
G01X284689Y368634D02*
G02X282744Y369797I70J2325D01*
G01X284830Y368634D02*
X284689D01*
G01X286124Y367847D02*
G03X284830Y368634I-1365J-787D01*
G01X288088Y366684D02*
G02X286124Y367847I51J2326D01*
G01X288198Y366684D02*
X288088D01*
G01X289504Y365897D02*
G03X288198Y366684I-1365J-788D01*
G01X291434Y364735D02*
G02X289504Y365897I85J2325D01*
G01X291563Y364735D02*
X291434D01*
G01X292884Y363947D02*
G03X291563Y364735I-1365J-787D01*
G01X292950Y363831D02*
X292884Y363947D01*
G01X294899Y361209D02*
X292950Y363831D01*
G01X271992Y402897D02*
X270292Y404597D01*
G01X271992Y400109D02*
Y402897D01*
G01X272604Y399047D02*
X271992Y400109D01*
G01X274549Y397884D02*
G02X272604Y399047I70J2325D01*
G01X274678Y397884D02*
X274549D01*
G01X276003Y395556D02*
G03X274678Y397884I-1384J753D01*
G01X275984Y395522D02*
X276003Y395556D01*
G01X275959Y393239D02*
G02X275984Y395522I2040J1119D01*
G01Y393197D02*
X275959Y393239D01*
G01X275984Y391623D02*
G03Y393197I-1365J787D01*
G01Y389297D02*
G02Y391623I2015J1163D01*
G01Y387723D02*
G03Y389297I-1365J787D01*
G01X277914Y384235D02*
G02X275984Y387723I85J2325D01*
G01X278043Y384235D02*
X277914D01*
G01X279364Y383447D02*
G03X278043Y384235I-1365J-787D01*
G01X281309Y382284D02*
G02X279364Y383447I70J2325D01*
G01X281438Y382284D02*
X281309D01*
G01X282744Y381497D02*
G03X281438Y382284I-1365J-788D01*
G01X284674Y380335D02*
G02X282744Y381497I85J2325D01*
G01X284803Y380335D02*
X284674D01*
G01X286124Y379547D02*
G03X284803Y380335I-1365J-787D01*
G01X288069Y378384D02*
G02X286124Y379547I70J2325D01*
G01X288198Y378384D02*
X288069D01*
G01X289504Y377597D02*
G03X288198Y378384I-1365J-788D01*
G01X291434Y376435D02*
G02X289504Y377597I85J2325D01*
G01X291563Y376435D02*
X291434D01*
G01X292884Y375647D02*
G03X291563Y376435I-1365J-787D01*
G01X294829Y374484D02*
G02X292884Y375647I70J2325D01*
G01X260434Y394888D02*
X259499Y395823D01*
G01X268371Y394888D02*
X260434D01*
G01X269565Y394106D02*
X268371Y394888D01*
G01X269802Y393692D02*
X269565Y394106D01*
G01X269899Y393530D02*
X269802Y393692D01*
G01X269874Y391247D02*
G03X269899Y393530I-2015J1164D01*
G01X269855Y391213D02*
X269874Y391247D01*
G01Y389672D02*
G02X269855Y391213I1365J787D01*
G01X269899Y387389D02*
G03X269874Y389672I-2040J1119D01*
G01Y387347D02*
X269899Y387389D01*
G01X269855Y387313D02*
X269874Y387347D01*
G01Y385772D02*
G02X269855Y387313I1365J787D01*
G01X269899Y383489D02*
G03X269874Y385772I-2040J1119D01*
G01X269547Y382879D02*
X269899Y383489D01*
G01X270582Y381085D02*
G02X269547Y382879I657J1575D01*
G01X271309Y381085D02*
X270582D01*
G01X273254Y379922D02*
G03X271309Y381085I-2015J-1162D01*
G01X274575Y379134D02*
G02X273254Y379922I44J1575D01*
G01X274704Y379134D02*
X274575D01*
G01X276634Y377972D02*
G03X274704Y379134I-2015J-1163D01*
G01X277940Y377185D02*
G02X276634Y377972I59J1575D01*
G01X278069Y377185D02*
X277940D01*
G01X280014Y376022D02*
G03X278069Y377185I-2015J-1162D01*
G01X281335Y375234D02*
G02X280014Y376022I44J1575D01*
G01X281464Y375234D02*
X281335D01*
G01X283394Y374072D02*
G03X281464Y375234I-2015J-1163D01*
G01X284700Y373285D02*
G02X283394Y374072I59J1575D01*
G01X284810Y373285D02*
X284700D01*
G01X286774Y372122D02*
G03X284810Y373285I-2015J-1163D01*
G01X288068Y371335D02*
G02X286774Y372122I71J1574D01*
G01X288209Y371335D02*
X288068D01*
G01X290154Y370172D02*
G03X288209Y371335I-2015J-1162D01*
G01X291448Y369385D02*
G02X290154Y370172I71J1574D01*
G01X291604Y369385D02*
X291448D01*
G01X293534Y368223D02*
G03X291604Y369385I-2015J-1163D01*
G01X289752Y399799D02*
Y405584D01*
G01X289504Y399422D02*
X289752Y399799D01*
G01X289479Y399380D02*
X289504Y399422D01*
G01Y397097D02*
G02X289479Y399380I2015J1164D01*
G01X289523Y395556D02*
G03X289504Y397097I-1384J754D01*
G01Y395522D02*
X289523Y395556D01*
G01X289479Y393239D02*
G02X289504Y395522I2040J1119D01*
G01Y393197D02*
X289479Y393239D01*
G01X289504Y391623D02*
G03Y393197I-1365J787D01*
G01X291434Y388135D02*
G02X289504Y391623I85J2325D01*
G01X291563Y388135D02*
X291434D01*
G01X292884Y387347D02*
G03X291563Y388135I-1365J-787D01*
G01X294829Y386184D02*
G02X292884Y387347I70J2325D01*
G01X270872Y405075D02*
Y406365D01*
G01X272740Y403207D02*
X270872Y405075D01*
G01X288793Y414896D02*
X286903D01*
G01X296653Y407036D02*
X288793Y414896D01*
G01X285116Y411278D02*
Y412309D01*
G01X290500Y405894D02*
X285116Y411278D01*
G01X270292Y404597D02*
X269104D01*
G01X288671Y416076D02*
Y416664D01*
G01X297401Y407346D02*
X288671Y416076D01*
G01X284545Y410791D02*
X283098D01*
G01X289752Y405584D02*
X284545Y410791D01*
G01X340988Y201300D02*
X342218Y205210D01*
G01X340988Y200519D02*
Y201300D01*
G01X348978Y202196D02*
Y205210D01*
G01X346988Y200206D02*
X348978Y202196D01*
G01X346988Y199062D02*
Y200206D01*
G01X306392Y204015D02*
Y202936D01*
G01X311112Y208735D02*
X306392Y204015D01*
G01X311798Y208735D02*
X311112D01*
G01X313813Y209897D02*
G02X311798Y208735I-2013J1162D01*
G01X315119Y210684D02*
G03X313813Y209897I59J-1575D01*
G01X316671Y210684D02*
X315119D01*
G01X318589Y212602D02*
X316671Y210684D01*
G01X318589Y213979D02*
Y212602D01*
G01X323539Y218929D02*
X318589Y213979D01*
G01X334798Y195511D02*
X335718Y194591D01*
G01X334798Y196351D02*
Y195511D01*
G01X332688Y198461D02*
X334798Y196351D01*
G01X332688Y199701D02*
Y198461D01*
G01X337228Y204241D02*
X332688Y199701D01*
G01X337228Y211684D02*
Y204241D01*
G01X338179Y212635D02*
X337228Y211684D01*
G01X338923Y212635D02*
X338179D01*
G01X340878Y216080D02*
G02X338923Y212635I-2040J-1120D01*
G01X340853Y216122D02*
X340878Y216080D01*
G01X340834Y216156D02*
X340853Y216122D01*
G01Y217697D02*
G03X340834Y216156I1365J-787D01*
G01X340878Y219980D02*
G02X340853Y217697I-2040J-1119D01*
G01X352992Y217100D02*
G03X353671Y217985I-3014J3015D01*
G01X352148Y216561D02*
G03X352992Y217100I-800J2183D01*
G01X351815Y216439D02*
X352148Y216561D01*
G01X350993Y214173D02*
G02X351815Y216439I1364J787D01*
G01X351028Y211907D02*
G03X350993Y214173I-2050J1102D01*
G01Y211847D02*
X351028Y211907D01*
G01X350993Y210273D02*
G02Y211847I1364J787D01*
G01X351792Y207289D02*
G03X350993Y210273I-5970J0D01*
G01X351792Y201376D02*
Y207289D01*
G01X352188Y200980D02*
X351792Y201376D01*
G01X352188Y199802D02*
Y200980D01*
G01X329986Y196153D02*
X330718Y195421D01*
G01X329986Y197134D02*
Y196153D01*
G01X329373Y197747D02*
X329986Y197134D01*
G01X329373Y202034D02*
Y197747D01*
G01X334202Y206863D02*
X329373Y202034D01*
G01X334202Y212351D02*
Y206863D01*
G01X337303Y215452D02*
X334202Y212351D01*
G01X337473Y215747D02*
X337303Y215452D01*
G01X337498Y218030D02*
G02X337473Y215747I-2040J-1119D01*
G01X323866Y216439D02*
X326353Y218926D01*
G01X323866Y213483D02*
Y216439D01*
G01X322708Y212325D02*
X323866Y213483D01*
G01X322708Y210701D02*
Y212325D01*
G01X315407Y203400D02*
X322708Y210701D01*
G01X313889Y203400D02*
X315407D01*
G01X350188Y200096D02*
Y199305D01*
G01X350592Y200500D02*
X350188Y200096D01*
G01X350592Y208964D02*
Y200500D01*
G01X350342Y209896D02*
G02X350592Y208964I-1614J-932D01*
G01X350307Y212162D02*
G03X350342Y209896I2050J-1102D01*
G01Y212222D02*
X350307Y212162D01*
G01X350342Y213796D02*
G02Y212222I-1364J-787D01*
G01X350307Y216062D02*
G03X350342Y213796I2050J-1102D01*
G01X350406Y216235D02*
X350307Y216062D01*
G01X352357Y218860D02*
X350406Y216235D01*
G01X294970Y207535D02*
X294829D01*
G01X296264Y208322D02*
G02X294970Y207535I-1365J787D01*
G01X298228Y209485D02*
G03X296264Y208322I51J-2326D01*
G01X298338Y209485D02*
X298228D01*
G01X299644Y210272D02*
G02X298338Y209485I-1365J788D01*
G01X301574Y211434D02*
G03X299644Y210272I85J-2325D01*
G01X301678Y211434D02*
X301574D01*
G01X303024Y212223D02*
G02X301678Y211434I-1365J786D01*
G01X304969Y213386D02*
G03X303024Y212223I70J-2325D01*
G01X305087Y213386D02*
X304969D01*
G01X306403Y214173D02*
G02X305087Y213386I-1364J787D01*
G01X308320Y215334D02*
G03X306403Y214173I98J-2325D01*
G01X308462Y215334D02*
X308320D01*
G01X309783Y216122D02*
G02X308462Y215334I-1365J787D01*
G01X311728Y217285D02*
G03X309783Y216122I70J-2325D01*
G01X311857Y217285D02*
X311728D01*
G01X313163Y218072D02*
G02X311857Y217285I-1365J788D01*
G01X354092Y203500D02*
X356188Y201404D01*
G01X354092Y208863D02*
Y203500D01*
G01X354372Y209897D02*
G03X354092Y208863I1771J-1034D01*
G01X354438Y210010D02*
X354372Y209897D01*
G01X355737Y213009D02*
X354438Y210010D01*
G01X343980Y207347D02*
X342218Y209109D01*
G01X343980Y201788D02*
Y207347D01*
G01X342988Y200796D02*
X343980Y201788D01*
G01X342988Y199608D02*
Y200796D01*
G01X305903Y204600D02*
X304512D01*
G01X310788Y209485D02*
X305903Y204600D01*
G01X311798Y209485D02*
X310788D01*
G01X313163Y210272D02*
G02X311798Y209485I-1363J787D01*
G01X315093Y211434D02*
G03X313163Y210272I85J-2325D01*
G01X316357Y211434D02*
X315093D01*
G01X317839Y212916D02*
X316357Y211434D01*
G01X317839Y214293D02*
Y212916D01*
G01X322942Y219396D02*
X317839Y214293D01*
G01X354188Y201286D02*
Y200166D01*
G01X353092Y202382D02*
X354188Y201286D01*
G01X353092Y208100D02*
Y202382D01*
G01X353631Y210114D02*
G03X353092Y208100I3494J-2014D01*
G01X353722Y210272D02*
X353631Y210114D01*
G01X353741Y211813D02*
G02X353722Y210272I-1384J-754D01*
G01Y211847D02*
X353741Y211813D01*
G01X353697Y211889D02*
X353722Y211847D01*
G01Y214172D02*
G03X353697Y211889I2015J-1164D01*
G01X354092Y214542D02*
X353722Y214172D01*
G01X354092Y216653D02*
Y214542D01*
G01X354372Y217698D02*
G03X354092Y216653I1811J-1045D01*
G01X354372Y220024D02*
G02Y217698I-2015J-1163D01*
G01X294840Y210684D02*
G03X293534Y209897I59J-1575D01*
G01X294969Y210684D02*
X294840D01*
G01X296914Y211847D02*
G02X294969Y210684I-2015J1162D01*
G01X298235Y212635D02*
G03X296914Y211847I44J-1575D01*
G01X298364Y212635D02*
X298235D01*
G01X300294Y213797D02*
G02X298364Y212635I-2015J1163D01*
G01X301600Y214584D02*
G03X300294Y213797I59J-1575D01*
G01X301729Y214584D02*
X301600D01*
G01X303674Y215747D02*
G02X301729Y214584I-2015J1162D01*
G01X304995Y216535D02*
G03X303674Y215747I44J-1575D01*
G01X305137Y216535D02*
X304995D01*
G01X307054Y217696D02*
G02X305137Y216535I-2015J1164D01*
G01X307067Y217719D02*
X307054Y217696D01*
G01X308418Y218484D02*
G03X307067Y217719I0J-1575D01*
G01X294828Y206784D02*
G03X293534Y205997I71J-1574D01*
G01X294984Y206784D02*
X294828D01*
G01X296914Y207946D02*
G02X294984Y206784I-2015J1163D01*
G01X298235Y208734D02*
G03X296914Y207946I44J-1575D01*
G01X298330Y208734D02*
X298235D01*
G01X300294Y209897D02*
G02X298330Y208734I-2015J1163D01*
G01X301600Y210684D02*
G03X300294Y209897I59J-1575D01*
G01X301729Y210684D02*
X301600D01*
G01X303674Y211847D02*
G02X301729Y210684I-2015J1162D01*
G01X304980Y212635D02*
G03X303674Y211847I59J-1574D01*
G01X305137Y212635D02*
X304980D01*
G01X307054Y213796D02*
G02X305137Y212635I-2015J1164D01*
G01X307067Y213819D02*
X307054Y213796D01*
G01X308418Y214584D02*
G03X307067Y213819I0J-1575D01*
G01X308488Y214584D02*
X308418D01*
G01X310433Y215747D02*
G02X308488Y214584I-2015J1162D01*
G01X311754Y216535D02*
G03X310433Y215747I44J-1575D01*
G01X311883Y216535D02*
X311754D01*
G01X313813Y217697D02*
G02X311883Y216535I-2015J1163D01*
G01X315119Y218484D02*
G03X313813Y217697I59J-1575D01*
G01X340178Y215789D02*
G02X340203Y218072I2040J1119D01*
G01Y215747D02*
X340178Y215789D01*
G01X340222Y215713D02*
X340203Y215747D01*
G01X338897Y213385D02*
G03X340222Y215713I-59J1575D01*
G01X337857Y213385D02*
X338897D01*
G01X336478Y212006D02*
X337857Y213385D01*
G01X336478Y204551D02*
Y212006D01*
G01X331938Y200011D02*
X336478Y204551D01*
G01X331938Y198151D02*
Y200011D01*
G01X334048Y196041D02*
X331938Y198151D01*
G01X334048Y195421D02*
Y196041D01*
G01X333218Y194591D02*
X334048Y195421D01*
G01X316124Y203059D02*
Y201765D01*
G01X323458Y210393D02*
X316124Y203059D01*
G01X323458Y212013D02*
Y210393D01*
G01X324616Y213171D02*
X323458Y212013D01*
G01X324616Y216128D02*
Y213171D01*
G01X327103Y218615D02*
X324616Y216128D01*
G01X294943Y211434D02*
X294814D01*
G01X296264Y212222D02*
G02X294943Y211434I-1365J787D01*
G01X298209Y213385D02*
G03X296264Y212222I70J-2325D01*
G01X298338Y213385D02*
X298209D01*
G01X299644Y214172D02*
G02X298338Y213385I-1365J788D01*
G01X301574Y215334D02*
G03X299644Y214172I85J-2325D01*
G01X301703Y215334D02*
X301574D01*
G01X303024Y216122D02*
G02X301703Y215334I-1365J787D01*
G01X304969Y217285D02*
G03X303024Y216122I70J-2325D01*
G01X305039Y217285D02*
X304969D01*
G01X306390Y218050D02*
G02X305039Y217285I-1351J810D01*
G01X336798Y217739D02*
G02X336823Y220022I2040J1119D01*
G01Y217697D02*
X336798Y217739D01*
G01X336842Y217663D02*
X336823Y217697D01*
G01Y216122D02*
G03X336842Y217663I-1365J787D01*
G01X336703Y215914D02*
X336823Y216122D01*
G01X333452Y212663D02*
X336703Y215914D01*
G01X333452Y207175D02*
Y212663D01*
G01X328623Y202346D02*
X333452Y207175D01*
G01X328623Y197436D02*
Y202346D01*
G01X329238Y196821D02*
X328623Y197436D01*
G01X329238Y196301D02*
Y196821D01*
G01X328368Y195431D02*
X329238Y196301D01*
G01X344988Y200397D02*
Y199498D01*
G01X347218Y202627D02*
X344988Y200397D01*
G01X347218Y205539D02*
Y202627D01*
G01X345598Y207159D02*
X347218Y205539D01*
G01X301805Y242634D02*
X305039Y242260D01*
G01X301615Y242634D02*
X301805D01*
G01X300294Y243422D02*
G03X301615Y242634I1365J787D01*
G01X298349Y244585D02*
G02X300294Y243422I-70J-2325D01*
G01X298220Y244585D02*
X298349D01*
G01X296914Y245372D02*
G03X298220Y244585I1365J788D01*
G01X294984Y246534D02*
G02X296914Y245372I-85J-2325D01*
G01X294855Y246534D02*
X294984D01*
G01X293923Y246872D02*
G03X294855Y246534I976J1237D01*
G01X298425Y251635D02*
X301659Y252009D01*
G01X298194Y251635D02*
X298425D01*
G01X296264Y252797D02*
G03X298194Y251635I2015J1163D01*
G01X294958Y253584D02*
G02X296264Y252797I-59J-1575D01*
G01X294829Y253584D02*
X294958D01*
G01X294828Y230184D02*
G03X293534Y229397I71J-1574D01*
G01X295043Y230184D02*
X294828D01*
G01X298279Y230559D02*
X295043Y230184D01*
G01X323953Y219646D02*
X323539Y218929D01*
G01X323953Y221972D02*
G02Y219646I-2015J-1163D01*
G01X323934Y223513D02*
G03X323953Y221972I1384J-754D01*
G01Y223547D02*
X323934Y223513D01*
G01X323978Y223589D02*
X323953Y223547D01*
G01Y225872D02*
G02X323978Y223589I-2015J-1164D01*
G01X323934Y227413D02*
G03X323953Y225872I1384J-754D01*
G01Y227447D02*
X323934Y227413D01*
G01X323978Y229730D02*
G02X323953Y227447I-2040J-1119D01*
G01Y229772D02*
X323978Y229730D01*
G01X323953Y231346D02*
G03Y229772I1365J-787D01*
G01Y233672D02*
G02Y231346I-2015J-1163D01*
G01X323934Y235213D02*
G03X323953Y233672I1384J-754D01*
G01Y235247D02*
X323934Y235213D01*
G01X323978Y235289D02*
X323953Y235247D01*
G01Y237572D02*
G02X323978Y235289I-2015J-1164D01*
G01X323934Y239113D02*
G03X323953Y237572I1384J-754D01*
G01Y239147D02*
X323934Y239113D01*
G01X323978Y239189D02*
X323953Y239147D01*
G01Y241472D02*
G02X323978Y239189I-2015J-1164D01*
G01X323934Y243013D02*
G03X323953Y241472I1384J-754D01*
G01Y243047D02*
X323934Y243013D01*
G01X323978Y243089D02*
X323953Y243047D01*
G01Y245372D02*
G02X323978Y243089I-2015J-1164D01*
G01X323934Y246913D02*
G03X323953Y245372I1384J-754D01*
G01Y246947D02*
X323934Y246913D01*
G01X323978Y246989D02*
X323953Y246947D01*
G01Y249272D02*
G02X323978Y246989I-2015J-1164D01*
G01X323934Y250813D02*
G03X323953Y249272I1384J-754D01*
G01Y250847D02*
X323934Y250813D01*
G01X323978Y250889D02*
X323953Y250847D01*
G01Y253172D02*
G02X323978Y250889I-2015J-1164D01*
G01X324752Y255431D02*
G03X323953Y253172I566J-1471D01*
G01X326426Y256626D02*
X324752Y255431D01*
G01X326683Y257072D02*
X326426Y256626D01*
G01X326702Y258613D02*
G02X326683Y257072I-1384J-754D01*
G01X326615Y258764D02*
X326702Y258613D01*
G01X325318Y261760D02*
X326615Y258764D01*
G01X340853Y220022D02*
X340878Y219980D01*
G01X340834Y220056D02*
X340853Y220022D01*
G01Y221597D02*
G03X340834Y220056I1365J-787D01*
G01X340878Y223880D02*
G02X340853Y221597I-2040J-1119D01*
G01Y223922D02*
X340878Y223880D01*
G01X340834Y223956D02*
X340853Y223922D01*
G01Y225497D02*
G03X340834Y223956I1365J-787D01*
G01X340853Y227823D02*
G02Y225497I-2015J-1163D01*
G01Y229397D02*
G03Y227823I1365J-787D01*
G01X340878Y229439D02*
X340853Y229397D01*
G01Y231722D02*
G02X340878Y229439I-2015J-1164D01*
G01X340834Y231756D02*
X340853Y231722D01*
G01Y233297D02*
G03X340834Y231756I1365J-787D01*
G01X340878Y235580D02*
G02X340853Y233297I-2040J-1119D01*
G01Y235622D02*
X340878Y235580D01*
G01X340834Y235656D02*
X340853Y235622D01*
G01Y237197D02*
G03X340834Y235656I1365J-787D01*
G01X340878Y239480D02*
G02X340853Y237197I-2040J-1119D01*
G01Y239522D02*
X340878Y239480D01*
G01X340834Y239556D02*
X340853Y239522D01*
G01Y241097D02*
G03X340834Y239556I1365J-787D01*
G01X340878Y243380D02*
G02X340853Y241097I-2040J-1119D01*
G01Y243422D02*
X340878Y243380D01*
G01X340834Y243456D02*
X340853Y243422D01*
G01Y244997D02*
G03X340834Y243456I1365J-787D01*
G01X340878Y247280D02*
G02X340853Y244997I-2040J-1119D01*
G01Y247322D02*
X340878Y247280D01*
G01X340834Y247356D02*
X340853Y247322D01*
G01Y248897D02*
G03X340834Y247356I1365J-787D01*
G01X340878Y251180D02*
G02X340853Y248897I-2040J-1119D01*
G01Y251222D02*
X340878Y251180D01*
G01X340834Y251256D02*
X340853Y251222D01*
G01Y252797D02*
G03X340834Y251256I1365J-787D01*
G01X340878Y255080D02*
G02X340853Y252797I-2040J-1119D01*
G01Y255122D02*
X340878Y255080D01*
G01X340834Y255156D02*
X340853Y255122D01*
G01Y256697D02*
G03X340834Y255156I1365J-787D01*
G01X340878Y258980D02*
G02X340853Y256697I-2040J-1119D01*
G01Y259022D02*
X340878Y258980D01*
G01X340787Y259138D02*
X340853Y259022D01*
G01X338838Y261760D02*
X340787Y259138D01*
G01X303090Y260481D02*
X305039Y257860D01*
G01X303024Y260597D02*
X303090Y260481D01*
G01X301718Y261384D02*
G02X303024Y260597I-59J-1575D01*
G01X301600Y261384D02*
X301718D01*
G01X300843Y261158D02*
G02X301600Y261384I815J-1349D01*
G01X298678Y260185D02*
X300843Y261158D01*
G01X298220Y260185D02*
X298678D01*
G01X296754Y261362D02*
G03X298220Y260185I1525J398D01*
G01X296499Y262469D02*
X296754Y261362D01*
G01X296553Y263348D02*
X296499Y262469D01*
G01X296496Y264096D02*
X296553Y263348D01*
G01X296264Y264497D02*
X296496Y264096D01*
G01X294958Y265284D02*
G02X296264Y264497I-59J-1575D01*
G01X294829Y265284D02*
X294958D01*
G01X351124Y221397D02*
X348978Y224709D01*
G01X352929Y220329D02*
X351124Y221397D01*
G01X353722Y218074D02*
G03X352929Y220329I-1365J787D01*
G01X353671Y217985D02*
X353722Y218074D01*
G01X356352Y246160D02*
X352357D01*
G01X311672Y230717D02*
X311798Y230559D01*
G01X309799Y230935D02*
X311672Y230717D01*
G01X308348Y230935D02*
X309799D01*
G01X306403Y229772D02*
G02X308348Y230935I2015J-1162D01*
G01X305087Y228985D02*
G03X306403Y229772I-48J1574D01*
G01X304954Y228985D02*
X305087D01*
G01X303024Y227823D02*
G02X304954Y228985I2015J-1163D01*
G01X301703Y227035D02*
G03X303024Y227823I-44J1575D01*
G01X301608Y227035D02*
X301703D01*
G01X299644Y225872D02*
G02X301608Y227035I2015J-1163D01*
G01X298338Y225085D02*
G03X299644Y225872I-59J1575D01*
G01X298209Y225085D02*
X298338D01*
G01X296264Y223922D02*
G02X298209Y225085I2015J-1162D01*
G01X294943Y223134D02*
G03X296264Y223922I-44J1575D01*
G01X294814Y223134D02*
X294943D01*
G01X337473Y218072D02*
X337498Y218030D01*
G01X337454Y218106D02*
X337473Y218072D01*
G01Y219647D02*
G03X337454Y218106I1365J-787D01*
G01X337498Y219689D02*
X337473Y219647D01*
G01Y221972D02*
G02X337498Y219689I-2015J-1164D01*
G01X337454Y223513D02*
G03X337473Y221972I1384J-754D01*
G01Y223547D02*
X337454Y223513D01*
G01X337498Y223589D02*
X337473Y223547D01*
G01Y225872D02*
G02X337498Y223589I-2015J-1164D01*
G01X337454Y227413D02*
G03X337473Y225872I1384J-754D01*
G01Y227447D02*
X337454Y227413D01*
G01X337498Y229730D02*
G02X337473Y227447I-2040J-1119D01*
G01Y229772D02*
X337498Y229730D01*
G01X337473Y231346D02*
G03Y229772I1365J-787D01*
G01Y233672D02*
G02Y231346I-2015J-1163D01*
G01X337454Y235213D02*
G03X337473Y233672I1384J-754D01*
G01Y235247D02*
X337454Y235213D01*
G01X337498Y235289D02*
X337473Y235247D01*
G01Y237572D02*
G02X337498Y235289I-2015J-1164D01*
G01X337454Y239113D02*
G03X337473Y237572I1384J-754D01*
G01Y239147D02*
X337454Y239113D01*
G01X337498Y239189D02*
X337473Y239147D01*
G01Y241472D02*
G02X337498Y239189I-2015J-1164D01*
G01X337454Y243013D02*
G03X337473Y241472I1384J-754D01*
G01Y243047D02*
X337454Y243013D01*
G01X337498Y243089D02*
X337473Y243047D01*
G01Y245372D02*
G02X337498Y243089I-2015J-1164D01*
G01X337454Y246913D02*
G03X337473Y245372I1384J-754D01*
G01Y246947D02*
X337454Y246913D01*
G01X337498Y246989D02*
X337473Y246947D01*
G01Y249272D02*
G02X337498Y246989I-2015J-1164D01*
G01X337473Y250847D02*
G03Y249272I1364J-788D01*
G01Y253173D02*
G02Y250847I-2015J-1163D01*
G01Y254747D02*
G03Y253173I1365J-787D01*
G01Y257073D02*
G02Y254747I-2015J-1163D01*
G01X337010Y259540D02*
G03X337473Y257073I3741J-575D01*
G01X336823Y260597D02*
G02X337010Y259540I-1365J-787D01*
G01X335458Y263709D02*
X336823Y260597D01*
G01X328532Y255733D02*
X328698Y255909D01*
G01X326699Y253201D02*
G02X328532Y255733I13166J-7602D01*
G01X326683Y253173D02*
X326699Y253201D01*
G01X326683Y250847D02*
G02Y253173I2015J1163D01*
G01Y249272D02*
G03Y250847I-1364J787D01*
G01X326658Y246989D02*
G02X326683Y249272I2040J1119D01*
G01Y246947D02*
X326658Y246989D01*
G01X326702Y246913D02*
X326683Y246947D01*
G01Y245372D02*
G03X326702Y246913I-1365J787D01*
G01X326658Y243089D02*
G02X326683Y245372I2040J1119D01*
G01Y243047D02*
X326658Y243089D01*
G01X326702Y243013D02*
X326683Y243047D01*
G01Y241472D02*
G03X326702Y243013I-1365J787D01*
G01X326658Y239189D02*
G02X326683Y241472I2040J1119D01*
G01Y239147D02*
X326658Y239189D01*
G01X326702Y239113D02*
X326683Y239147D01*
G01Y237572D02*
G03X326702Y239113I-1365J787D01*
G01X326658Y235289D02*
G02X326683Y237572I2040J1119D01*
G01Y235247D02*
X326658Y235289D01*
G01X326702Y235213D02*
X326683Y235247D01*
G01Y233672D02*
G03X326702Y235213I-1365J787D01*
G01X326683Y231346D02*
G02Y233672I2015J1163D01*
G01Y229772D02*
G03Y231346I-1365J787D01*
G01X326658Y229730D02*
X326683Y229772D01*
G01Y227447D02*
G02X326658Y229730I2015J1164D01*
G01X326702Y227413D02*
X326683Y227447D01*
G01Y225872D02*
G03X326702Y227413I-1365J787D01*
G01X326658Y223589D02*
G02X326683Y225872I2040J1119D01*
G01Y223547D02*
X326658Y223589D01*
G01X326702Y223513D02*
X326683Y223547D01*
G01Y221972D02*
G03X326702Y223513I-1365J787D01*
G01X326353Y221399D02*
X326683Y221972D01*
G01X326353Y218926D02*
Y221399D01*
G01X347547Y243538D02*
X345598Y246160D01*
G01X347613Y243422D02*
X347547Y243538D01*
G01X348180Y242850D02*
G02X347613Y243422I798J1358D01*
G01X358537Y236851D02*
X348180Y242850D01*
G01X315093Y219234D02*
G03X313163Y218072I85J-2325D01*
G01X315222Y219234D02*
X315093D01*
G01X316543Y220022D02*
G02X315222Y219234I-1365J787D01*
G01X316979Y220568D02*
G03X316543Y220022I1579J-1708D01*
G01X318558Y222760D02*
X316979Y220568D01*
G01X294840Y226284D02*
G03X293534Y225497I59J-1575D01*
G01X294950Y226284D02*
X294840D01*
G01X296914Y227447D02*
G02X294950Y226284I-2015J1163D01*
G01X298208Y228234D02*
G03X296914Y227447I71J-1574D01*
G01X298349Y228234D02*
X298208D01*
G01X300294Y229397D02*
G02X298349Y228234I-2015J1162D01*
G01X301588Y230184D02*
G03X300294Y229397I71J-1574D01*
G01X301744Y230184D02*
X301588D01*
G01X303674Y231346D02*
G02X301744Y230184I-2015J1163D01*
G01X304995Y232134D02*
G03X303674Y231346I44J-1575D01*
G01X305109Y232134D02*
X304995D01*
G01X307054Y233296D02*
G02X305109Y232134I-2015J1164D01*
G01X307067Y233319D02*
X307054Y233296D01*
G01X309499Y233656D02*
G03X307067Y233319I-1080J-1147D01*
G01X310645Y233142D02*
X309499Y233656D01*
G01X311568Y232885D02*
X310645Y233142D01*
G01X311857Y232885D02*
X311568D01*
G01X313163Y233672D02*
G02X311857Y232885I-1365J788D01*
G01X313229Y233788D02*
X313163Y233672D01*
G01X315178Y236409D02*
X313229Y233788D01*
G01X323303Y220021D02*
X322942Y219396D01*
G01X323303Y221597D02*
G02Y220021I-1365J-788D01*
G01X323278Y223880D02*
G03X323303Y221597I2040J-1119D01*
G01Y223922D02*
X323278Y223880D01*
G01X323322Y223956D02*
X323303Y223922D01*
G01Y225497D02*
G02X323322Y223956I-1365J-787D01*
G01X323303Y227823D02*
G03Y225497I2015J-1163D01*
G01Y229397D02*
G02Y227823I-1365J-787D01*
G01X323278Y229439D02*
X323303Y229397D01*
G01Y231722D02*
G03X323278Y229439I2015J-1164D01*
G01X323322Y231756D02*
X323303Y231722D01*
G01Y233297D02*
G02X323322Y231756I-1365J-787D01*
G01X323278Y235580D02*
G03X323303Y233297I2040J-1119D01*
G01Y235622D02*
X323278Y235580D01*
G01X323322Y235656D02*
X323303Y235622D01*
G01Y237197D02*
G02X323322Y235656I-1365J-787D01*
G01X323278Y239480D02*
G03X323303Y237197I2040J-1119D01*
G01Y239522D02*
X323278Y239480D01*
G01X323322Y239556D02*
X323303Y239522D01*
G01Y241097D02*
G02X323322Y239556I-1365J-787D01*
G01X323278Y243380D02*
G03X323303Y241097I2040J-1119D01*
G01Y243422D02*
X323278Y243380D01*
G01X323322Y243456D02*
X323303Y243422D01*
G01Y244997D02*
G02X323322Y243456I-1365J-787D01*
G01X323278Y247280D02*
G03X323303Y244997I2040J-1119D01*
G01Y247322D02*
X323278Y247280D01*
G01X323322Y247356D02*
X323303Y247322D01*
G01Y248897D02*
G02X323322Y247356I-1365J-787D01*
G01X323278Y251180D02*
G03X323303Y248897I2040J-1119D01*
G01Y251222D02*
X323278Y251180D01*
G01X323322Y251256D02*
X323303Y251222D01*
G01Y252797D02*
G02X323322Y251256I-1365J-787D01*
G01X323278Y255080D02*
G03X323303Y252797I2040J-1119D01*
G01Y255122D02*
X323278Y255080D01*
G01X323369Y255238D02*
X323303Y255122D01*
G01X325318Y257860D02*
X323369Y255238D01*
G01X354307Y220137D02*
X354372Y220024D01*
G01X352357Y222760D02*
X354307Y220137D01*
G01X308488Y218484D02*
X308418D01*
G01X310433Y219647D02*
G02X308488Y218484I-2015J1162D01*
G01X311754Y220435D02*
G03X310433Y219647I44J-1575D01*
G01X311883Y220435D02*
X311754D01*
G01X313813Y221597D02*
G02X311883Y220435I-2015J1163D01*
G01X315119Y222384D02*
G03X313813Y221597I59J-1575D01*
G01X315248Y222384D02*
X315119D01*
G01X317193Y223547D02*
G02X315248Y222384I-2015J1162D01*
G01X318514Y224335D02*
G03X317193Y223547I44J-1575D01*
G01X318643Y224335D02*
X318514D01*
G01X320573Y225497D02*
G02X318643Y224335I-2015J1163D01*
G01X320639Y225611D02*
X320573Y225497D01*
G01X321938Y228610D02*
X320639Y225611D01*
G01X298301Y261817D02*
X298279Y261760D01*
G01X297163Y264445D02*
X298301Y261817D01*
G01X296914Y264872D02*
X297163Y264445D01*
G01X294984Y266034D02*
G02X296914Y264872I-85J-2325D01*
G01X294855Y266034D02*
X294984D01*
G01X293534Y266822D02*
G03X294855Y266034I1365J787D01*
G01X315248Y218484D02*
X315119D01*
G01X317193Y219647D02*
G02X315248Y218484I-2015J1162D01*
G01X318514Y220435D02*
G03X317193Y219647I44J-1575D01*
G01X318643Y220435D02*
X318514D01*
G01X320687Y221822D02*
G02X318643Y220435I-2129J938D01*
G01X321938Y224709D02*
X320687Y221822D01*
G01X340135Y254864D02*
X338838Y257860D01*
G01X340222Y254713D02*
X340135Y254864D01*
G01X340203Y253172D02*
G03X340222Y254713I-1365J787D01*
G01X340178Y250889D02*
G02X340203Y253172I2040J1119D01*
G01Y250847D02*
X340178Y250889D01*
G01X340222Y250813D02*
X340203Y250847D01*
G01Y249272D02*
G03X340222Y250813I-1365J787D01*
G01X340178Y246989D02*
G02X340203Y249272I2040J1119D01*
G01Y246947D02*
X340178Y246989D01*
G01X340222Y246913D02*
X340203Y246947D01*
G01Y245372D02*
G03X340222Y246913I-1365J787D01*
G01X340178Y243089D02*
G02X340203Y245372I2040J1119D01*
G01Y243047D02*
X340178Y243089D01*
G01X340222Y243013D02*
X340203Y243047D01*
G01Y241472D02*
G03X340222Y243013I-1365J787D01*
G01X340178Y239189D02*
G02X340203Y241472I2040J1119D01*
G01Y239147D02*
X340178Y239189D01*
G01X340222Y239113D02*
X340203Y239147D01*
G01Y237572D02*
G03X340222Y239113I-1365J787D01*
G01X340178Y235289D02*
G02X340203Y237572I2040J1119D01*
G01Y235247D02*
X340178Y235289D01*
G01X340222Y235213D02*
X340203Y235247D01*
G01Y233672D02*
G03X340222Y235213I-1365J787D01*
G01X340203Y231346D02*
G02Y233672I2015J1163D01*
G01Y229772D02*
G03Y231346I-1365J787D01*
G01X340178Y229730D02*
X340203Y229772D01*
G01Y227447D02*
G02X340178Y229730I2015J1164D01*
G01X340222Y227413D02*
X340203Y227447D01*
G01Y225872D02*
G03X340222Y227413I-1365J787D01*
G01X340178Y223589D02*
G02X340203Y225872I2040J1119D01*
G01Y223547D02*
X340178Y223589D01*
G01X340222Y223513D02*
X340203Y223547D01*
G01Y221972D02*
G03X340222Y223513I-1365J787D01*
G01X340178Y219689D02*
G02X340203Y221972I2040J1119D01*
G01Y219647D02*
X340178Y219689D01*
G01X340222Y219613D02*
X340203Y219647D01*
G01Y218072D02*
G03X340222Y219613I-1365J787D01*
G01X299710Y246831D02*
X301659Y244209D01*
G01X299644Y246947D02*
X299710Y246831D01*
G01X298323Y247735D02*
G02X299644Y246947I-44J-1575D01*
G01X298194Y247735D02*
X298323D01*
G01X296264Y248897D02*
G03X298194Y247735I2015J1163D01*
G01X294958Y249684D02*
G02X296264Y248897I-59J-1575D01*
G01X294840Y249684D02*
X294958D01*
G01X293959Y249374D02*
G02X294840Y249684I940J-1265D01*
G01X327103Y221199D02*
Y218615D01*
G01X327333Y221597D02*
X327103Y221199D01*
G01X327358Y223880D02*
G02X327333Y221597I-2040J-1119D01*
G01Y223922D02*
X327358Y223880D01*
G01X327314Y223956D02*
X327333Y223922D01*
G01Y225497D02*
G03X327314Y223956I1365J-787D01*
G01X327333Y227823D02*
G02Y225497I-2015J-1163D01*
G01Y229397D02*
G03Y227823I1365J-787D01*
G01X327358Y229439D02*
X327333Y229397D01*
G01Y231722D02*
G02X327358Y229439I-2015J-1164D01*
G01X327314Y231756D02*
X327333Y231722D01*
G01Y233297D02*
G03X327314Y231756I1365J-787D01*
G01X327358Y235580D02*
G02X327333Y233297I-2040J-1119D01*
G01Y235622D02*
X327358Y235580D01*
G01X327314Y235656D02*
X327333Y235622D01*
G01Y237197D02*
G03X327314Y235656I1365J-787D01*
G01X327358Y239480D02*
G02X327333Y237197I-2040J-1119D01*
G01Y239522D02*
X327358Y239480D01*
G01X327314Y239556D02*
X327333Y239522D01*
G01Y241097D02*
G03X327314Y239556I1365J-787D01*
G01X327358Y243380D02*
G02X327333Y241097I-2040J-1119D01*
G01Y243422D02*
X327358Y243380D01*
G01X327314Y243456D02*
X327333Y243422D01*
G01Y244997D02*
G03X327314Y243456I1365J-787D01*
G01X327358Y247280D02*
G02X327333Y244997I-2040J-1119D01*
G01Y247322D02*
X327358Y247280D01*
G01X327314Y247356D02*
X327333Y247322D01*
G01Y248897D02*
G03X327314Y247356I1365J-787D01*
G01X327333Y251223D02*
G02Y248897I-2017J-1163D01*
G01Y252797D02*
G03Y251223I1365J-787D01*
G01X329272Y254443D02*
G03X327333Y252797I1328J-3530D01*
G01X329948Y256869D02*
G02X329272Y254443I-1250J-959D01*
G01X328094Y258355D02*
G02X329948Y256869I-1636J-3940D01*
G01X327333Y260597D02*
G03X328094Y258355I1365J-787D01*
G01X327356Y260643D02*
G02X327333Y260597I-418J180D01*
G01X328685Y263704D02*
X327356Y260643D01*
G01X328698Y263709D02*
X328685Y263704D01*
G01X301805Y262134D02*
X305039Y261760D01*
G01X301615Y262134D02*
X301805D01*
G01X300294Y262922D02*
G03X301615Y262134I1365J787D01*
G01X300140Y263189D02*
X300294Y262922D01*
G01X299936Y264073D02*
X300140Y263189D01*
G01X299852Y265567D02*
X299936Y264073D01*
G01X298323Y267235D02*
G02X299852Y265567I-44J-1575D01*
G01X298194Y267235D02*
X298323D01*
G01X296264Y268397D02*
G03X298194Y267235I2015J1163D01*
G01X294958Y269184D02*
G02X296264Y268397I-59J-1575D01*
G01X294829Y269184D02*
X294958D01*
G01X308777Y234808D02*
X311798Y234460D01*
G01X308503Y234834D02*
G02X308777Y234808I-82J-2325D01*
G01X308320Y234834D02*
X308503D01*
G01X306403Y233673D02*
G02X308320Y234834I2015J-1164D01*
G01X306390Y233650D02*
X306403Y233673D01*
G01X305039Y232885D02*
G03X306390Y233650I0J1575D01*
G01X304988Y232885D02*
X305039D01*
G01X303024Y231722D02*
G02X304988Y232885I2015J-1163D01*
G01X301730Y230935D02*
G03X303024Y231722I-71J1574D01*
G01X301589Y230935D02*
X301730D01*
G01X299644Y229772D02*
G02X301589Y230935I2015J-1162D01*
G01X298350Y228985D02*
G03X299644Y229772I-71J1574D01*
G01X298194Y228985D02*
X298350D01*
G01X296264Y227823D02*
G02X298194Y228985I2015J-1163D01*
G01X294943Y227035D02*
G03X296264Y227823I-44J1575D01*
G01X294848Y227035D02*
X294943D01*
G01X295045Y250434D02*
X298279Y250060D01*
G01X294855Y250434D02*
X295045D01*
G01X293960Y250744D02*
G03X294855Y250434I939J1265D01*
G01X347547Y239638D02*
X345598Y242260D01*
G01X347613Y239522D02*
X347547Y239638D01*
G01X348186Y238947D02*
G02X347613Y239522I792J1362D01*
G01X355933Y234393D02*
X348186Y238947D01*
G01X303090Y240981D02*
X305039Y238360D01*
G01X303024Y241097D02*
X303090Y240981D01*
G01X301718Y241884D02*
G02X303024Y241097I-59J-1575D01*
G01X301600Y241884D02*
X301718D01*
G01X300789Y241624D02*
G02X301600Y241884I869J-1315D01*
G01X298618Y240685D02*
X300789Y241624D01*
G01X298220Y240685D02*
X298618D01*
G01X296914Y241472D02*
G03X298220Y240685I1365J788D01*
G01X294984Y242634D02*
G02X296914Y241472I-85J-2325D01*
G01X294855Y242634D02*
X294984D01*
G01X293809Y243071D02*
G03X294855Y242634I1090J1138D01*
G01X306403Y218073D02*
X306390Y218050D01*
G01X308320Y219234D02*
G03X306403Y218073I98J-2325D01*
G01X308462Y219234D02*
X308320D01*
G01X309783Y220022D02*
G02X308462Y219234I-1365J787D01*
G01X311728Y221185D02*
G03X309783Y220022I70J-2325D01*
G01X311857Y221185D02*
X311728D01*
G01X313163Y221972D02*
G02X311857Y221185I-1365J788D01*
G01X313229Y222088D02*
X313163Y221972D01*
G01X315178Y224709D02*
X313229Y222088D01*
G01X294855Y269934D02*
G02X293534Y270722I44J1575D01*
G01X294984Y269934D02*
X294855D01*
G01X296914Y268772D02*
G03X294984Y269934I-2015J-1163D01*
G01X298220Y267985D02*
G02X296914Y268772I59J1575D01*
G01X298349Y267985D02*
X298220D01*
G01X300457Y266480D02*
G03X298349Y267985I-2177J-821D01*
G01X301659Y263709D02*
X300457Y266480D01*
G01X294840Y222384D02*
G03X293534Y221597I59J-1575D01*
G01X294969Y222384D02*
X294840D01*
G01X296914Y223547D02*
G02X294969Y222384I-2015J1162D01*
G01X298235Y224335D02*
G03X296914Y223547I44J-1575D01*
G01X298364Y224335D02*
X298235D01*
G01X300294Y225497D02*
G02X298364Y224335I-2015J1163D01*
G01X301600Y226284D02*
G03X300294Y225497I59J-1575D01*
G01X301710Y226284D02*
X301600D01*
G01X303674Y227447D02*
G02X301710Y226284I-2015J1163D01*
G01X304968Y228234D02*
G03X303674Y227447I71J-1574D01*
G01X305124Y228234D02*
X304968D01*
G01X307054Y229396D02*
G02X305124Y228234I-2015J1163D01*
G01X307067Y229419D02*
X307054Y229396D01*
G01X308418Y230184D02*
G03X307067Y229419I0J-1575D01*
G01X308489Y230184D02*
X308418D01*
G01X309213Y229971D02*
G03X308489Y230184I-794J-1361D01*
G01X309594Y229659D02*
G03X309213Y229971I-1177J-1048D01*
G01X311218Y228985D02*
X309594Y229659D01*
G01X312298Y228985D02*
X311218D01*
G01X312648Y229203D02*
X312298Y228985D01*
G01X313073Y229467D02*
X312648Y229203D01*
G01X313372Y230134D02*
X313073Y229467D01*
G01X313624Y232248D02*
X313372Y230134D01*
G01X315119Y234084D02*
G03X313624Y232248I59J-1575D01*
G01X315320Y234084D02*
X315119D01*
G01X318558Y234460D02*
X315320Y234084D01*
G01X336692Y253061D02*
X335458Y255909D01*
G01X336823Y252797D02*
G02X336692Y253061I2014J1164D01*
G01X336823Y251223D02*
G03Y252797I-1365J787D01*
G01Y248897D02*
G02Y251223I2017J1163D01*
G01X336842Y247356D02*
G03X336823Y248897I-1384J754D01*
G01Y247322D02*
X336842Y247356D01*
G01X336798Y247280D02*
X336823Y247322D01*
G01Y244997D02*
G02X336798Y247280I2015J1164D01*
G01X336842Y243456D02*
G03X336823Y244997I-1384J754D01*
G01Y243422D02*
X336842Y243456D01*
G01X336798Y243380D02*
X336823Y243422D01*
G01Y241097D02*
G02X336798Y243380I2015J1164D01*
G01X336842Y239556D02*
G03X336823Y241097I-1384J754D01*
G01Y239522D02*
X336842Y239556D01*
G01X336798Y239480D02*
X336823Y239522D01*
G01Y237197D02*
G02X336798Y239480I2015J1164D01*
G01X336842Y235656D02*
G03X336823Y237197I-1384J754D01*
G01Y235622D02*
X336842Y235656D01*
G01X336798Y235580D02*
X336823Y235622D01*
G01Y233297D02*
G02X336798Y235580I2015J1164D01*
G01X336842Y231756D02*
G03X336823Y233297I-1384J754D01*
G01Y231722D02*
X336842Y231756D01*
G01X336798Y229439D02*
G02X336823Y231722I2040J1119D01*
G01Y229397D02*
X336798Y229439D01*
G01X336823Y227823D02*
G03Y229397I-1365J787D01*
G01Y225497D02*
G02Y227823I2015J1163D01*
G01X336842Y223956D02*
G03X336823Y225497I-1384J754D01*
G01Y223922D02*
X336842Y223956D01*
G01X336798Y223880D02*
X336823Y223922D01*
G01Y221597D02*
G02X336798Y223880I2015J1164D01*
G01X336842Y220056D02*
G03X336823Y221597I-1384J754D01*
G01Y220022D02*
X336842Y220056D01*
G01X294858Y252060D02*
X294899Y252009D01*
G01X296330Y244881D02*
X298279Y242260D01*
G01X296264Y244997D02*
X296330Y244881D01*
G01X294958Y245784D02*
G02X296264Y244997I-59J-1575D01*
G01X294840Y245784D02*
X294958D01*
G01X293959Y245474D02*
G02X294840Y245784I940J-1265D01*
G01Y234084D02*
G03X293534Y233297I59J-1575D01*
G01X295405Y234084D02*
X294840D01*
G01X296215Y233812D02*
X295405Y234084D01*
G01X297253Y233263D02*
X296215Y233812D01*
G01X298220Y232885D02*
G02X297253Y233263I58J1575D01*
G01X298415Y232885D02*
X298220D01*
G01X301659Y232509D02*
X298415Y232885D01*
G01X294840Y323784D02*
G03X293534Y322997I59J-1575D01*
G01X294950Y323784D02*
X294840D01*
G01X296914Y324947D02*
G02X294950Y323784I-2015J1163D01*
G01X298235Y325735D02*
G03X296914Y324947I44J-1575D01*
G01X298364Y325735D02*
X298235D01*
G01X300294Y326897D02*
G02X298364Y325735I-2015J1163D01*
G01X301588Y327684D02*
G03X300294Y326897I71J-1574D01*
G01X301729Y327684D02*
X301588D01*
G01X303674Y328847D02*
G02X301729Y327684I-2015J1162D01*
G01X304995Y329635D02*
G03X303674Y328847I44J-1575D01*
G01X305137Y329635D02*
X304995D01*
G01X307089Y333062D02*
G02X305137Y329635I-2050J-1102D01*
G01X307054Y333122D02*
X307089Y333062D01*
G01X307054Y334696D02*
G03Y333122I1364J-787D01*
G01X307089Y336962D02*
G02X307054Y334696I-2050J-1102D01*
G01Y337022D02*
X307089Y336962D01*
G01X307054Y338596D02*
G03Y337022I1364J-787D01*
G01X307089Y340862D02*
G02X307054Y338596I-2050J-1102D01*
G01Y340922D02*
X307089Y340862D01*
G01X307054Y342496D02*
G03Y340922I1364J-787D01*
G01X354372Y338597D02*
G02X355678Y339384I1365J-788D01*
G01X352442Y337435D02*
G03X354372Y338597I-85J2325D01*
G01X352357Y337435D02*
X352442D01*
G01X351006Y336670D02*
G02X352357Y337435I1351J-810D01*
G01X350993Y336647D02*
X351006Y336670D01*
G01X349048Y335484D02*
G03X350993Y336647I-70J2325D01*
G01X348919Y335484D02*
X349048D01*
G01X347613Y334697D02*
G02X348919Y335484I1365J-788D01*
G01X345683Y333535D02*
G03X347613Y334697I-85J2325D01*
G01X345554Y333535D02*
X345683D01*
G01X344233Y332747D02*
G02X345554Y333535I1365J-787D01*
G01X342288Y331584D02*
G03X344233Y332747I-70J2325D01*
G01X342159Y331584D02*
X342288D01*
G01X340853Y330797D02*
G02X342159Y331584I1365J-788D01*
G01X338923Y329635D02*
G03X340853Y330797I-85J2325D01*
G01X338794Y329635D02*
X338923D01*
G01X337473Y328847D02*
G02X338794Y329635I1365J-787D01*
G01X335528Y327684D02*
G03X337473Y328847I-70J2325D01*
G01X335387Y327684D02*
X335528D01*
G01X334093Y326897D02*
G02X335387Y327684I1365J-787D01*
G01X332163Y325735D02*
G03X334093Y326897I-85J2325D01*
G01X332034Y325735D02*
X332163D01*
G01X330713Y324947D02*
G02X332034Y325735I1365J-787D01*
G01X328749Y323784D02*
G03X330713Y324947I-51J2326D01*
G01X328639Y323784D02*
X328749D01*
G01X327333Y322997D02*
G02X328639Y323784I1365J-788D01*
G01X325403Y321835D02*
G03X327333Y322997I-85J2325D01*
G01X325274Y321835D02*
X325403D01*
G01X323953Y321047D02*
G02X325274Y321835I1365J-787D01*
G01X322008Y319884D02*
G03X323953Y321047I-70J2325D01*
G01X321879Y319884D02*
X322008D01*
G01X320573Y319097D02*
G02X321879Y319884I1365J-788D01*
G01X318643Y317935D02*
G03X320573Y319097I-85J2325D01*
G01X318514Y317935D02*
X318643D01*
G01X317193Y317147D02*
G02X318514Y317935I1365J-787D01*
G01X315248Y315984D02*
G03X317193Y317147I-70J2325D01*
G01X315119Y315984D02*
X315248D01*
G01X313813Y315197D02*
G02X315119Y315984I1365J-788D01*
G01X311883Y314035D02*
G03X313813Y315197I-85J2325D01*
G01X311754Y314035D02*
X311883D01*
G01X310433Y313247D02*
G02X311754Y314035I1365J-787D01*
G01X308488Y312084D02*
G03X310433Y313247I-70J2325D01*
G01X308418Y312084D02*
X308488D01*
G01X307067Y311319D02*
G02X308418Y312084I1351J-810D01*
G01X307054Y311296D02*
X307067Y311319D01*
G01X305137Y310135D02*
G03X307054Y311296I-98J2325D01*
G01X304995Y310135D02*
X305137D01*
G01X303674Y309347D02*
G02X304995Y310135I1365J-787D01*
G01X301729Y308184D02*
G03X303674Y309347I-70J2325D01*
G01X301600Y308184D02*
X301729D01*
G01X300294Y307397D02*
G02X301600Y308184I1365J-788D01*
G01X298364Y306235D02*
G03X300294Y307397I-85J2325D01*
G01X298194Y306235D02*
X298364D01*
G01X296264Y307397D02*
G03X298194Y306235I2015J1163D01*
G01X294958Y308184D02*
G02X296264Y307397I-59J-1575D01*
G01X294840Y308184D02*
X294958D01*
G01X293534Y307397D02*
G02X294840Y308184I1365J-788D01*
G01X310800Y333383D02*
Y336700D01*
G01X310414Y332713D02*
X310800Y333383D01*
G01X310433Y331172D02*
G02X310414Y332713I1365J787D01*
G01X308488Y327684D02*
G03X310433Y331172I-70J2325D01*
G01X308370Y327684D02*
X308488D01*
G01X307054Y326897D02*
G02X308370Y327684I1364J-787D01*
G01X305124Y325735D02*
G03X307054Y326897I-85J2325D01*
G01X304995Y325735D02*
X305124D01*
G01X303674Y324947D02*
G02X304995Y325735I1365J-787D01*
G01X301710Y323784D02*
G03X303674Y324947I-51J2326D01*
G01X301600Y323784D02*
X301710D01*
G01X300294Y322997D02*
G02X301600Y323784I1365J-788D01*
G01X298364Y321835D02*
G03X300294Y322997I-85J2325D01*
G01X298235Y321835D02*
X298364D01*
G01X296914Y321047D02*
G02X298235Y321835I1365J-787D01*
G01X294969Y319884D02*
G03X296914Y321047I-70J2325D01*
G01X294840Y319884D02*
X294969D01*
G01X293534Y319097D02*
G02X294840Y319884I1365J-788D01*
G01X326658Y340589D02*
G02X326683Y342872I2040J1119D01*
G01Y340547D02*
X326658Y340589D01*
G01X326749Y340431D02*
X326683Y340547D01*
G01X328698Y337809D02*
X326749Y340431D01*
G01X294943Y332334D02*
X294814D01*
G01X296264Y333122D02*
G02X294943Y332334I-1365J787D01*
G01X296330Y333238D02*
X296264Y333122D01*
G01X298279Y335860D02*
X296330Y333238D01*
G01X296264Y311297D02*
G03X293534I-1365J-788D01*
G01X298194Y310135D02*
G02X296264Y311297I85J2325D01*
G01X298364Y310135D02*
X298194D01*
G01X300294Y311297D02*
G02X298364Y310135I-2015J1163D01*
G01X301600Y312084D02*
G03X300294Y311297I59J-1575D01*
G01X301729Y312084D02*
X301600D01*
G01X303674Y313247D02*
G02X301729Y312084I-2015J1162D01*
G01X304995Y314035D02*
G03X303674Y313247I44J-1575D01*
G01X305137Y314035D02*
X304995D01*
G01X307054Y315196D02*
G02X305137Y314035I-2015J1164D01*
G01X307067Y315219D02*
X307054Y315196D01*
G01X308418Y315984D02*
G03X307067Y315219I0J-1575D01*
G01X308488Y315984D02*
X308418D01*
G01X310433Y317147D02*
G02X308488Y315984I-2015J1162D01*
G01X311754Y317935D02*
G03X310433Y317147I44J-1575D01*
G01X311883Y317935D02*
X311754D01*
G01X313813Y319097D02*
G02X311883Y317935I-2015J1163D01*
G01X315119Y319884D02*
G03X313813Y319097I59J-1575D01*
G01X315248Y319884D02*
X315119D01*
G01X317193Y321047D02*
G02X315248Y319884I-2015J1162D01*
G01X318514Y321835D02*
G03X317193Y321047I44J-1575D01*
G01X318643Y321835D02*
X318514D01*
G01X320573Y322997D02*
G02X318643Y321835I-2015J1163D01*
G01X321879Y323784D02*
G03X320573Y322997I59J-1575D01*
G01X321989Y323784D02*
X321879D01*
G01X323953Y324947D02*
G02X321989Y323784I-2015J1163D01*
G01X325274Y325735D02*
G03X323953Y324947I44J-1575D01*
G01X325403Y325735D02*
X325274D01*
G01X327333Y326897D02*
G02X325403Y325735I-2015J1163D01*
G01X328627Y327684D02*
G03X327333Y326897I71J-1574D01*
G01X328768Y327684D02*
X328627D01*
G01X330713Y328847D02*
G02X328768Y327684I-2015J1162D01*
G01X332034Y329635D02*
G03X330713Y328847I44J-1575D01*
G01X332163Y329635D02*
X332034D01*
G01X334093Y330797D02*
G02X332163Y329635I-2015J1163D01*
G01X335399Y331584D02*
G03X334093Y330797I59J-1575D01*
G01X335528Y331584D02*
X335399D01*
G01X337473Y332747D02*
G02X335528Y331584I-2015J1162D01*
G01X338794Y333535D02*
G03X337473Y332747I44J-1575D01*
G01X338923Y333535D02*
X338794D01*
G01X340853Y334697D02*
G02X338923Y333535I-2015J1163D01*
G01X342159Y335484D02*
G03X340853Y334697I59J-1575D01*
G01X342288Y335484D02*
X342159D01*
G01X344233Y336647D02*
G02X342288Y335484I-2015J1162D01*
G01X345554Y337435D02*
G03X344233Y336647I44J-1575D01*
G01X345683Y337435D02*
X345554D01*
G01X347613Y338597D02*
G02X345683Y337435I-2015J1163D01*
G01X348919Y339384D02*
G03X347613Y338597I59J-1575D01*
G01X349048Y339384D02*
X348919D01*
G01X350993Y342873D02*
G02X349048Y339384I-2015J-1163D01*
G01X310000Y333499D02*
Y337600D01*
G01X309758Y333080D02*
X310000Y333499D01*
G01X309783Y330797D02*
G02X309758Y333080I2015J1164D01*
G01X308489Y328435D02*
G03X309783Y330797I-71J1574D01*
G01X308333Y328435D02*
X308489D01*
G01X306403Y327273D02*
G02X308333Y328435I2015J-1163D01*
G01X306390Y327250D02*
X306403Y327273D01*
G01X305039Y326485D02*
G03X306390Y327250I0J1575D01*
G01X304954Y326485D02*
X305039D01*
G01X303024Y325323D02*
G02X304954Y326485I2015J-1163D01*
G01X301703Y324535D02*
G03X303024Y325323I-44J1575D01*
G01X301608Y324535D02*
X301703D01*
G01X299644Y323372D02*
G02X301608Y324535I2015J-1163D01*
G01X298338Y322585D02*
G03X299644Y323372I-59J1575D01*
G01X298209Y322585D02*
X298338D01*
G01X296264Y321422D02*
G02X298209Y322585I2015J-1162D01*
G01X294943Y320634D02*
G03X296264Y321422I-44J1575D01*
G01X294814Y320634D02*
X294943D01*
G01X294828Y327684D02*
G03X293534Y326897I71J-1574D01*
G01X294969Y327684D02*
X294828D01*
G01X296914Y328847D02*
G02X294969Y327684I-2015J1162D01*
G01X298235Y329635D02*
G03X296914Y328847I44J-1575D01*
G01X298364Y329635D02*
X298235D01*
G01X300294Y330797D02*
G02X298364Y329635I-2015J1163D01*
G01X301600Y331584D02*
G03X300294Y330797I59J-1575D01*
G01X301729Y331584D02*
X301600D01*
G01X303674Y332747D02*
G02X301729Y331584I-2015J1162D01*
G01X303742Y332864D02*
X303674Y332747D01*
G01X305039Y335860D02*
X303742Y332864D01*
G01X306368Y340607D02*
G02X306403Y342873I2050J1102D01*
G01Y340547D02*
X306368Y340607D01*
G01X306403Y338973D02*
G03Y340547I-1364J787D01*
G01X306368Y336707D02*
G02X306403Y338973I2050J1102D01*
G01Y336647D02*
X306368Y336707D01*
G01X306403Y335073D02*
G03Y336647I-1364J787D01*
G01X306368Y332807D02*
G02X306403Y335073I2050J1102D01*
G01Y332747D02*
X306368Y332807D01*
G01X305039Y330385D02*
G03X306403Y332747I0J1575D01*
G01X304969Y330385D02*
X305039D01*
G01X303024Y329222D02*
G02X304969Y330385I2015J-1162D01*
G01X301730Y328435D02*
G03X303024Y329222I-71J1574D01*
G01X301574Y328435D02*
X301730D01*
G01X299644Y327273D02*
G02X301574Y328435I2015J-1163D01*
G01X298323Y326485D02*
G03X299644Y327273I-44J1575D01*
G01X298194Y326485D02*
X298323D01*
G01X296264Y325323D02*
G02X298194Y326485I2015J-1163D01*
G01X294943Y324535D02*
G03X296264Y325323I-44J1575D01*
G01X294848Y324535D02*
X294943D01*
G01X298220Y310885D02*
G02X296914Y311672I59J1575D01*
G01X298338Y310885D02*
X298220D01*
G01X299644Y311672D02*
G02X298338Y310885I-1365J788D01*
G01X301574Y312834D02*
G03X299644Y311672I85J-2325D01*
G01X301703Y312834D02*
X301574D01*
G01X303024Y313622D02*
G02X301703Y312834I-1365J787D01*
G01X304969Y314785D02*
G03X303024Y313622I70J-2325D01*
G01X305039Y314785D02*
X304969D01*
G01X306390Y315550D02*
G02X305039Y314785I-1351J810D01*
G01X306403Y315573D02*
X306390Y315550D01*
G01X308320Y316734D02*
G03X306403Y315573I98J-2325D01*
G01X308462Y316734D02*
X308320D01*
G01X309783Y317522D02*
G02X308462Y316734I-1365J787D01*
G01X311728Y318685D02*
G03X309783Y317522I70J-2325D01*
G01X311857Y318685D02*
X311728D01*
G01X313163Y319472D02*
G02X311857Y318685I-1365J788D01*
G01X315093Y320634D02*
G03X313163Y319472I85J-2325D01*
G01X315222Y320634D02*
X315093D01*
G01X316543Y321422D02*
G02X315222Y320634I-1365J787D01*
G01X318488Y322585D02*
G03X316543Y321422I70J-2325D01*
G01X318617Y322585D02*
X318488D01*
G01X319923Y323372D02*
G02X318617Y322585I-1365J788D01*
G01X321887Y324535D02*
G03X319923Y323372I51J-2326D01*
G01X321982Y324535D02*
X321887D01*
G01X323303Y325323D02*
G02X321982Y324535I-1365J787D01*
G01X325233Y326485D02*
G03X323303Y325323I85J-2325D01*
G01X325362Y326485D02*
X325233D01*
G01X326683Y327273D02*
G02X325362Y326485I-1365J787D01*
G01X328613Y328435D02*
G03X326683Y327273I85J-2325D01*
G01X328769Y328435D02*
X328613D01*
G01X330063Y329222D02*
G02X328769Y328435I-1365J787D01*
G01X332008Y330385D02*
G03X330063Y329222I70J-2325D01*
G01X332137Y330385D02*
X332008D01*
G01X333443Y331172D02*
G02X332137Y330385I-1365J788D01*
G01X335373Y332334D02*
G03X333443Y331172I85J-2325D01*
G01X335502Y332334D02*
X335373D01*
G01X336823Y333122D02*
G02X335502Y332334I-1365J787D01*
G01X338768Y334285D02*
G03X336823Y333122I70J-2325D01*
G01X338897Y334285D02*
X338768D01*
G01X340203Y335072D02*
G02X338897Y334285I-1365J788D01*
G01X342133Y336234D02*
G03X340203Y335072I85J-2325D01*
G01X342262Y336234D02*
X342133D01*
G01X343583Y337022D02*
G02X342262Y336234I-1365J787D01*
G01X345528Y338185D02*
G03X343583Y337022I70J-2325D01*
G01X345657Y338185D02*
X345528D01*
G01X346963Y338972D02*
G02X345657Y338185I-1365J788D01*
G01X348893Y340134D02*
G03X346963Y338972I85J-2325D01*
G01X348978Y340134D02*
X348893D01*
G01X350342Y342496D02*
G02X348978Y340134I-1364J-787D01*
G01X294840Y331584D02*
G03X293534Y330797I59J-1575D01*
G01X294969Y331584D02*
X294840D01*
G01X296914Y332747D02*
G02X294969Y331584I-2015J1162D01*
G01X298235Y333535D02*
G03X296914Y332747I44J-1575D01*
G01X298364Y333535D02*
X298235D01*
G01X300294Y334697D02*
G02X298364Y333535I-2015J1163D01*
G01X301600Y335484D02*
G03X300294Y334697I59J-1575D01*
G01X301729Y335484D02*
X301600D01*
G01X303674Y336647D02*
G02X301729Y335484I-2015J1162D01*
G01X303742Y336764D02*
X303674Y336647D01*
G01X305039Y339760D02*
X303742Y336764D01*
G01X296264Y340922D02*
G02X296979Y341335I715J-412D01*
G01X294902Y340135D02*
G03X296264Y340922I0J1572D01*
G01X294896Y340135D02*
X294902D01*
G01X293958Y340446D02*
G03X294896Y340135I939J1261D01*
G01X299710Y331288D02*
X301659Y333909D01*
G01X299644Y331172D02*
X299710Y331288D01*
G01X298338Y330385D02*
G03X299644Y331172I-59J1575D01*
G01X298209Y330385D02*
X298338D01*
G01X296264Y329222D02*
G02X298209Y330385I2015J-1162D01*
G01X294970Y328435D02*
G03X296264Y329222I-71J1574D01*
G01X294814Y328435D02*
X294970D01*
G01X337498Y340589D02*
G03X337473Y342872I-2040J1119D01*
G01Y340547D02*
X337498Y340589D01*
G01X337454Y340513D02*
X337473Y340547D01*
G01Y338972D02*
G02X337454Y340513I1365J787D01*
G01X337539Y338859D02*
X337473Y338972D01*
G01X338838Y335860D02*
X337539Y338859D01*
G01X353722Y338972D02*
G02X355652Y340134I2015J-1163D01*
G01X352416Y338185D02*
G03X353722Y338972I-59J1575D01*
G01X352287Y338185D02*
X352416D01*
G01X350342Y337022D02*
G02X352287Y338185I2015J-1162D01*
G01X350329Y336999D02*
X350342Y337022D01*
G01X348978Y336234D02*
G03X350329Y336999I0J1575D01*
G01X348893Y336234D02*
X348978D01*
G01X346963Y335072D02*
G02X348893Y336234I2015J-1163D01*
G01X345657Y334285D02*
G03X346963Y335072I-59J1575D01*
G01X345528Y334285D02*
X345657D01*
G01X343583Y333122D02*
G02X345528Y334285I2015J-1162D01*
G01X342262Y332334D02*
G03X343583Y333122I-44J1575D01*
G01X342133Y332334D02*
X342262D01*
G01X340203Y331172D02*
G02X342133Y332334I2015J-1163D01*
G01X338897Y330385D02*
G03X340203Y331172I-59J1575D01*
G01X338768Y330385D02*
X338897D01*
G01X336823Y329222D02*
G02X338768Y330385I2015J-1162D01*
G01X335529Y328435D02*
G03X336823Y329222I-71J1574D01*
G01X335373Y328435D02*
X335529D01*
G01X333443Y327273D02*
G02X335373Y328435I2015J-1163D01*
G01X332122Y326485D02*
G03X333443Y327273I-44J1575D01*
G01X331993Y326485D02*
X332122D01*
G01X330063Y325323D02*
G02X331993Y326485I2015J-1163D01*
G01X328742Y324535D02*
G03X330063Y325323I-44J1575D01*
G01X328647Y324535D02*
X328742D01*
G01X326683Y323372D02*
G02X328647Y324535I2015J-1163D01*
G01X325377Y322585D02*
G03X326683Y323372I-59J1575D01*
G01X325248Y322585D02*
X325377D01*
G01X323303Y321422D02*
G02X325248Y322585I2015J-1162D01*
G01X321982Y320634D02*
G03X323303Y321422I-44J1575D01*
G01X321853Y320634D02*
X321982D01*
G01X319923Y319472D02*
G02X321853Y320634I2015J-1163D01*
G01X318617Y318685D02*
G03X319923Y319472I-59J1575D01*
G01X318488Y318685D02*
X318617D01*
G01X316543Y317522D02*
G02X318488Y318685I2015J-1162D01*
G01X315222Y316734D02*
G03X316543Y317522I-44J1575D01*
G01X315093Y316734D02*
X315222D01*
G01X313163Y315572D02*
G02X315093Y316734I2015J-1163D01*
G01X311857Y314785D02*
G03X313163Y315572I-59J1575D01*
G01X311728Y314785D02*
X311857D01*
G01X309783Y313622D02*
G02X311728Y314785I2015J-1162D01*
G01X308462Y312834D02*
G03X309783Y313622I-44J1575D01*
G01X308320Y312834D02*
X308462D01*
G01X306403Y311673D02*
G02X308320Y312834I2015J-1164D01*
G01X306390Y311650D02*
X306403Y311673D01*
G01X305039Y310885D02*
G03X306390Y311650I0J1575D01*
G01X304969Y310885D02*
X305039D01*
G01X303024Y309722D02*
G02X304969Y310885I2015J-1162D01*
G01X301703Y308934D02*
G03X303024Y309722I-44J1575D01*
G01X301574Y308934D02*
X301703D01*
G01X299644Y307772D02*
G02X301574Y308934I2015J-1163D01*
G01X298338Y306985D02*
G03X299644Y307772I-59J1575D01*
G01X298220Y306985D02*
X298338D01*
G01X296914Y307772D02*
G03X298220Y306985I1365J788D01*
G01X294984Y308934D02*
G02X296914Y307772I-85J-2325D01*
G01X294814Y308934D02*
X294984D01*
G01X330641Y340407D02*
G03X330580Y341602I-1197J538D01*
G01X330713Y338974D02*
G02X330641Y340407I1365J787D01*
G01X332078Y335860D02*
X330713Y338974D01*
G01X340834Y340956D02*
G02X340853Y342497I1384J754D01*
G01X340921Y340805D02*
X340834Y340956D01*
G01X342218Y337809D02*
X340921Y340805D01*
G01X353722Y370172D02*
G02X355667Y371335I2015J-1162D01*
G01X352428Y369385D02*
G03X353722Y370172I-71J1574D01*
G01X352272Y369385D02*
X352428D01*
G01X350342Y365896D02*
G02X352272Y369385I2015J1164D01*
G01X350342Y364322D02*
G03Y365896I-1364J787D01*
G01X350307Y364262D02*
X350342Y364322D01*
G01Y361996D02*
G02X350307Y364262I2015J1164D01*
G01X350342Y360422D02*
G03Y361996I-1364J787D01*
G01X350276Y360308D02*
X350342Y360422D01*
G01X348978Y357309D02*
X350276Y360308D01*
G01X296330Y352738D02*
X298279Y355360D01*
G01X296264Y352622D02*
X296330Y352738D01*
G01X293534Y352622D02*
G03X296264I1365J787D01*
G01X354118Y393080D02*
X356368Y395330D01*
G01X354118Y388162D02*
Y393080D01*
G01X354440Y387605D02*
X354118Y388162D01*
G01X354445Y387594D02*
X354440Y387605D01*
G01X355737Y384609D02*
X354445Y387594D01*
G01X294855Y375234D02*
G02X293534Y376022I44J1575D01*
G01X294984Y375234D02*
X294855D01*
G01X296914Y374072D02*
G03X294984Y375234I-2015J-1163D01*
G01X298220Y373285D02*
G02X296914Y374072I59J1575D01*
G01X298330Y373285D02*
X298220D01*
G01X300294Y372122D02*
G03X298330Y373285I-2015J-1163D01*
G01X301588Y371335D02*
G02X300294Y372122I71J1574D01*
G01X301729Y371335D02*
X301588D01*
G01X303674Y370172D02*
G03X301729Y371335I-2015J-1162D01*
G01X304968Y369385D02*
G02X303674Y370172I71J1574D01*
G01X305124Y369385D02*
X304968D01*
G01X307054Y368223D02*
G03X305124Y369385I-2015J-1163D01*
G01X307067Y368200D02*
X307054Y368223D01*
G01X308418Y367435D02*
G02X307067Y368200I0J1575D01*
G01X309524Y367435D02*
X308418D01*
G01X309611Y367427D02*
X309524Y367435D01*
G01X311798Y367060D02*
X309611Y367427D01*
G01X342353Y399461D02*
Y401161D01*
G01X340292Y397400D02*
X342353Y399461D01*
G01X340292Y395400D02*
Y397400D01*
G01X341192Y394500D02*
X340292Y395400D01*
G01X342392Y394500D02*
X341192D01*
G01X344061Y392831D02*
X342392Y394500D01*
G01X344061Y390807D02*
Y392831D01*
G01X344233Y389672D02*
G02X344061Y390807I1365J787D01*
G01X344299Y389559D02*
X344233Y389672D01*
G01X345598Y386560D02*
X344299Y389559D01*
G01X307089Y344762D02*
G02X307054Y342496I-2050J-1102D01*
G01Y344822D02*
X307089Y344762D01*
G01X307054Y346396D02*
G03Y344822I1364J-787D01*
G01X307089Y348662D02*
G02X307054Y346396I-2050J-1102D01*
G01Y348722D02*
X307089Y348662D01*
G01X307054Y350296D02*
G03Y348722I1364J-787D01*
G01X307067Y350319D02*
X307054Y350296D01*
G01X308418Y351084D02*
G03X307067Y350319I0J-1575D01*
G01X308488Y351084D02*
X308418D01*
G01X310433Y352247D02*
G02X308488Y351084I-2015J1162D01*
G01X311570Y353019D02*
G03X310433Y352247I228J-1559D01*
G01X311798Y352791D02*
X311570Y353019D01*
G01X311798Y351460D02*
Y352791D01*
G01X352918Y397081D02*
Y405606D01*
G01X350618Y394781D02*
X352918Y397081D01*
G01X350618Y389580D02*
Y394781D01*
G01X350342Y387722D02*
G03X350618Y389580I-2184J1274D01*
G01X350307Y387662D02*
X350342Y387722D01*
G01Y385396D02*
G02X350307Y387662I2015J1164D01*
G01X350342Y383822D02*
G03Y385396I-1364J787D01*
G01X350307Y383762D02*
X350342Y383822D01*
G01Y381496D02*
G02X350307Y383762I2015J1164D01*
G01X350342Y379922D02*
G03Y381496I-1364J787D01*
G01X350307Y379862D02*
X350342Y379922D01*
G01Y377596D02*
G02X350307Y379862I2015J1164D01*
G01X350342Y376022D02*
G03Y377596I-1364J787D01*
G01X350307Y375962D02*
X350342Y376022D01*
G01X350155Y375613D02*
G02X350307Y375962I2202J-752D01*
G01X349075Y373006D02*
G03X350155Y375613I-2607J2607D01*
G01X348978Y372909D02*
X349075Y373006D01*
G01X305248Y403009D02*
X304375Y403882D01*
G01X305248Y398041D02*
Y403009D01*
G01X307248Y396041D02*
X305248Y398041D01*
G01X307248Y392941D02*
Y396041D01*
G01X310173Y390016D02*
X307248Y392941D01*
G01X310173Y388417D02*
Y390016D01*
G01X309758Y387680D02*
X310173Y388417D01*
G01X311713Y384235D02*
G02X309758Y387680I85J2325D01*
G01X311842Y384235D02*
X311713D01*
G01X313163Y383447D02*
G03X311842Y384235I-1365J-787D01*
G01X315108Y382284D02*
G02X313163Y383447I70J2325D01*
G01X315237Y382284D02*
X315108D01*
G01X316543Y381497D02*
G03X315237Y382284I-1365J-788D01*
G01X318473Y380335D02*
G02X316543Y381497I85J2325D01*
G01X318602Y380335D02*
X318473D01*
G01X319923Y377972D02*
G03X318602Y380335I-1365J788D01*
G01X321868Y374484D02*
G02X319923Y377972I70J2325D01*
G01X321997Y374484D02*
X321868D01*
G01X323322Y372156D02*
G03X321997Y374484I-1384J753D01*
G01X323303Y372122D02*
X323322Y372156D01*
G01X323278Y369839D02*
G02X323303Y372122I2040J1119D01*
G01Y369797D02*
X323278Y369839D01*
G01X323303Y368223D02*
G03Y369797I-1365J787D01*
G01Y365897D02*
G02Y368223I2015J1163D01*
G01X323322Y364356D02*
G03X323303Y365897I-1384J754D01*
G01Y364322D02*
X323322Y364356D01*
G01X323278Y364280D02*
X323303Y364322D01*
G01X325233Y360835D02*
G02X323278Y364280I85J2325D01*
G01X325362Y360835D02*
X325233D01*
G01X326683Y358472D02*
G03X325362Y360835I-1365J788D01*
G01X326658Y356189D02*
G02X326683Y358472I2040J1119D01*
G01Y356147D02*
X326658Y356189D01*
G01X326702Y356113D02*
X326683Y356147D01*
G01Y354572D02*
G03X326702Y356113I-1365J787D01*
G01X326658Y352289D02*
G02X326683Y354572I2040J1119D01*
G01Y352247D02*
X326658Y352289D01*
G01X326702Y352213D02*
X326683Y352247D01*
G01Y350672D02*
G03X326702Y352213I-1365J787D01*
G01X326658Y348389D02*
G02X326683Y350672I2040J1119D01*
G01Y348347D02*
X326658Y348389D01*
G01X326702Y348313D02*
X326683Y348347D01*
G01Y346772D02*
G03X326702Y348313I-1365J787D01*
G01X326658Y344489D02*
G02X326683Y346772I2040J1119D01*
G01Y344447D02*
X326658Y344489D01*
G01X326702Y344413D02*
X326683Y344447D01*
G01Y342872D02*
G03X326702Y344413I-1365J787D01*
G01X352357Y345235D02*
G03X350993Y342873I0J-1575D01*
G01X352442Y345235D02*
X352357D01*
G01X354372Y346397D02*
G02X352442Y345235I-2015J1163D01*
G01X355678Y347184D02*
G03X354372Y346397I59J-1575D01*
G01X294969Y347184D02*
X294829D01*
G01X296914Y348347D02*
G02X294969Y347184I-2015J1162D01*
G01X298235Y349135D02*
G03X296914Y348347I44J-1575D01*
G01X298364Y349135D02*
X298235D01*
G01X300294Y350297D02*
G02X298364Y349135I-2015J1163D01*
G01X301600Y351084D02*
G03X300294Y350297I59J-1575D01*
G01X301729Y351084D02*
X301600D01*
G01X303674Y352247D02*
G02X301729Y351084I-2015J1162D01*
G01X303742Y352364D02*
X303674Y352247D01*
G01X305039Y355360D02*
X303742Y352364D01*
G01X294969Y351084D02*
X294829D01*
G01X296914Y352247D02*
G02X294969Y351084I-2015J1162D01*
G01X298235Y353035D02*
G03X296914Y352247I44J-1575D01*
G01X298364Y353035D02*
X298235D01*
G01X300294Y354197D02*
G02X298364Y353035I-2015J1163D01*
G01X301600Y354984D02*
G03X300294Y354197I59J-1575D01*
G01X301729Y354984D02*
X301600D01*
G01X303674Y356147D02*
G02X301729Y354984I-2015J1162D01*
G01X303742Y356264D02*
X303674Y356147D01*
G01X305039Y359260D02*
X303742Y356264D01*
G01X333884Y388305D02*
X326848Y395341D01*
G01X333884Y383956D02*
Y388305D01*
G01X334805Y383035D02*
X333884Y383956D01*
G01X335192Y383035D02*
X334805D01*
G01X335193Y383034D02*
X335192Y383035D01*
G01X335543Y383034D02*
X335193D01*
G01X337498Y379589D02*
G03X335543Y383034I-2040J1120D01*
G01X337473Y379547D02*
X337498Y379589D01*
G01X337454Y379513D02*
X337473Y379547D01*
G01Y377972D02*
G02X337454Y379513I1365J787D01*
G01X337498Y375689D02*
G03X337473Y377972I-2040J1119D01*
G01Y375647D02*
X337498Y375689D01*
G01X337454Y375613D02*
X337473Y375647D01*
G01Y374072D02*
G02X337454Y375613I1365J787D01*
G01X337473Y371746D02*
G03Y374072I-2015J1163D01*
G01X338767Y369385D02*
G02X337473Y371746I71J1574D01*
G01X338923Y369385D02*
X338767D01*
G01X340853Y365897D02*
G03X338923Y369385I-2015J1163D01*
G01X340834Y364356D02*
G02X340853Y365897I1384J754D01*
G01Y364322D02*
X340834Y364356D01*
G01X340878Y364280D02*
X340853Y364322D01*
G01Y361997D02*
G03X340878Y364280I-2015J1164D01*
G01X340834Y360456D02*
G02X340853Y361997I1384J754D01*
G01Y360422D02*
X340834Y360456D01*
G01X340878Y360380D02*
X340853Y360422D01*
G01Y358097D02*
G03X340878Y360380I-2015J1164D01*
G01X340834Y356556D02*
G02X340853Y358097I1384J754D01*
G01Y356522D02*
X340834Y356556D01*
G01X340878Y356480D02*
X340853Y356522D01*
G01Y354197D02*
G03X340878Y356480I-2015J1164D01*
G01X340834Y352656D02*
G02X340853Y354197I1384J754D01*
G01Y352622D02*
X340834Y352656D01*
G01X340878Y352580D02*
X340853Y352622D01*
G01Y350297D02*
G03X340878Y352580I-2015J1164D01*
G01X340834Y348756D02*
G02X340853Y350297I1384J754D01*
G01Y348722D02*
X340834Y348756D01*
G01X340878Y348680D02*
X340853Y348722D01*
G01Y346397D02*
G03X340878Y348680I-2015J1164D01*
G01X340787Y346281D02*
X340853Y346397D01*
G01X338838Y343660D02*
X340787Y346281D01*
G01X326848Y401641D02*
X325048Y403441D01*
G01X326848Y395341D02*
Y401641D01*
G01X352953Y393715D02*
X355318Y396080D01*
G01X352953Y388683D02*
Y393715D01*
G01X353741Y387313D02*
X352953Y388683D01*
G01X353722Y385772D02*
G03X353741Y387313I-1365J787D01*
G01X353697Y383489D02*
G02X353722Y385772I2040J1119D01*
G01Y383447D02*
X353697Y383489D01*
G01X353741Y383413D02*
X353722Y383447D01*
G01Y381872D02*
G03X353741Y383413I-1365J787D01*
G01X352357Y378760D02*
G02X353722Y381872I14816J-4643D01*
G01X294969Y343284D02*
X294829D01*
G01X296914Y344447D02*
G02X294969Y343284I-2015J1162D01*
G01X296982Y344564D02*
X296914Y344447D01*
G01X298279Y347560D02*
X296982Y344564D01*
G01X296653Y400118D02*
Y407036D01*
G01X296239Y399380D02*
X296653Y400118D01*
G01X296264Y397097D02*
G02X296239Y399380I2015J1164D01*
G01X296283Y395556D02*
G03X296264Y397097I-1384J754D01*
G01Y395522D02*
X296283Y395556D01*
G01X296239Y393239D02*
G02X296264Y395522I2040J1119D01*
G01Y393197D02*
X296239Y393239D01*
G01X296264Y391623D02*
G03Y393197I-1365J787D01*
G01X298194Y388135D02*
G02X296264Y391623I85J2325D01*
G01X298323Y388135D02*
X298194D01*
G01X299644Y387347D02*
G03X298323Y388135I-1365J-787D01*
G01X301589Y386184D02*
G02X299644Y387347I70J2325D01*
G01X301718Y386184D02*
X301589D01*
G01X303024Y385397D02*
G03X301718Y386184I-1365J-788D01*
G01X304954Y384235D02*
G02X303024Y385397I85J2325D01*
G01X305039Y384235D02*
X304954D01*
G01X306390Y383470D02*
G03X305039Y384235I-1351J-810D01*
G01X306403Y383447D02*
X306390Y383470D01*
G01X308348Y382284D02*
G02X306403Y383447I70J2325D01*
G01X308477Y382284D02*
X308348D01*
G01X309783Y381497D02*
G03X308477Y382284I-1365J-788D01*
G01X311713Y380335D02*
G02X309783Y381497I85J2325D01*
G01X311842Y380335D02*
X311713D01*
G01X313163Y379547D02*
G03X311842Y380335I-1365J-787D01*
G01X315108Y378384D02*
G02X313163Y379547I70J2325D01*
G01X315237Y378384D02*
X315108D01*
G01X316562Y376056D02*
G03X315237Y378384I-1384J753D01*
G01X316543Y376022D02*
X316562Y376056D01*
G01X316543Y375198D02*
G02Y376022I714J412D01*
G01X317193Y374072D02*
X316543Y375198D01*
G01X318499Y373285D02*
G02X317193Y374072I59J1575D01*
G01X318694Y373285D02*
X318499D01*
G01X321938Y372909D02*
X318694Y373285D01*
G01X298425Y364735D02*
X301659Y365109D01*
G01X298194Y364735D02*
X298425D01*
G01X296264Y365897D02*
G03X298194Y364735I2015J1163D01*
G01X294958Y366684D02*
G02X296264Y365897I-59J-1575D01*
G01X294848Y366684D02*
X294958D01*
G01X341853Y390085D02*
X339209Y392729D01*
G01X342237Y390085D02*
X341853D01*
G01X343602Y387756D02*
G03X342237Y390085I-1384J753D01*
G01X343515Y387605D02*
X343602Y387756D01*
G01X342218Y384609D02*
X343515Y387605D01*
G01X330296Y396227D02*
Y404899D01*
G01X338331Y388192D02*
X330296Y396227D01*
G01X340878Y383780D02*
X338331Y388192D01*
G01X340853Y381497D02*
G03X340878Y383780I-2015J1164D01*
G01X340834Y379956D02*
G02X340853Y381497I1384J754D01*
G01Y379922D02*
X340834Y379956D01*
G01X340878Y379880D02*
X340853Y379922D01*
G01Y377597D02*
G03X340878Y379880I-2015J1164D01*
G01X340834Y376056D02*
G02X340853Y377597I1384J754D01*
G01Y376022D02*
X340834Y376056D01*
G01X340878Y375980D02*
X340853Y376022D01*
G01Y373697D02*
G03X340878Y375980I-2015J1164D01*
G01X342147Y371335D02*
G02X340853Y373697I71J1574D01*
G01X342288Y371335D02*
X342147D01*
G01X344233Y367847D02*
G03X342288Y371335I-2015J1163D01*
G01X344214Y367813D02*
X344233Y367847D01*
G01Y366272D02*
G02X344214Y367813I1365J787D01*
G01X344258Y363989D02*
G03X344233Y366272I-2040J1119D01*
G01Y363947D02*
X344258Y363989D01*
G01X344214Y363913D02*
X344233Y363947D01*
G01Y362372D02*
G02X344214Y363913I1365J787D01*
G01X344258Y360089D02*
G03X344233Y362372I-2040J1119D01*
G01Y360047D02*
X344258Y360089D01*
G01X344214Y360013D02*
X344233Y360047D01*
G01Y358472D02*
G02X344214Y360013I1365J787D01*
G01X344258Y356189D02*
G03X344233Y358472I-2040J1119D01*
G01Y356147D02*
X344258Y356189D01*
G01X344214Y356113D02*
X344233Y356147D01*
G01Y354572D02*
G02X344214Y356113I1365J787D01*
G01X344258Y352289D02*
G03X344233Y354572I-2040J1119D01*
G01Y352247D02*
X344258Y352289D01*
G01X344214Y352213D02*
X344233Y352247D01*
G01Y350672D02*
G02X344214Y352213I1365J787D01*
G01X344258Y348389D02*
G03X344233Y350672I-2040J1119D01*
G01Y348347D02*
X344258Y348389D01*
G01X344214Y348313D02*
X344233Y348347D01*
G01Y346772D02*
G02X344214Y348313I1365J787D01*
G01X344258Y344489D02*
G03X344233Y346772I-2040J1119D01*
G01Y344447D02*
X344258Y344489D01*
G01X344167Y344331D02*
X344233Y344447D01*
G01X342218Y341709D02*
X344167Y344331D01*
G01X311798Y354029D02*
Y355360D01*
G01X311541Y353772D02*
X311798Y354029D01*
G01X309783Y352622D02*
G02X311541Y353772I2015J-1162D01*
G01X308462Y351834D02*
G03X309783Y352622I-44J1575D01*
G01X308320Y351834D02*
X308462D01*
G01X306403Y350673D02*
G02X308320Y351834I2015J-1164D01*
G01X306368Y348407D02*
G02X306403Y350673I2050J1102D01*
G01Y348347D02*
X306368Y348407D01*
G01X306403Y346773D02*
G03Y348347I-1364J787D01*
G01X306368Y344507D02*
G02X306403Y346773I2050J1102D01*
G01Y344447D02*
X306368Y344507D01*
G01X306403Y342873D02*
G03Y344447I-1364J787D01*
G01X352287Y345985D02*
G03X350342Y342496I69J-2325D01*
G01X352416Y345985D02*
X352287D01*
G01X353722Y346772D02*
G02X352416Y345985I-1365J788D01*
G01X355652Y347934D02*
G03X353722Y346772I85J-2325D01*
G01X296264Y348722D02*
G02X293534I-1365J787D01*
G01X298209Y349885D02*
G03X296264Y348722I70J-2325D01*
G01X298338Y349885D02*
X298209D01*
G01X299644Y350672D02*
G02X298338Y349885I-1365J788D01*
G01X299710Y350788D02*
X299644Y350672D01*
G01X301659Y353409D02*
X299710Y350788D01*
G01X294828Y371335D02*
G02X293534Y372122I71J1574D01*
G01X294969Y371335D02*
X294828D01*
G01X296914Y370172D02*
G03X294969Y371335I-2015J-1162D01*
G01X298208Y369385D02*
G02X296914Y370172I71J1574D01*
G01X298364Y369385D02*
X298208D01*
G01X300294Y368223D02*
G03X298364Y369385I-2015J-1163D01*
G01X301615Y367435D02*
G02X300294Y368223I44J1575D01*
G01X301710Y367435D02*
X301615D01*
G01X303674Y366272D02*
G03X301710Y367435I-2015J-1163D01*
G01X304980Y365485D02*
G02X303674Y366272I59J1575D01*
G01X305109Y365485D02*
X304980D01*
G01X307054Y364322D02*
G03X305109Y365485I-2015J-1162D01*
G01X307067Y364299D02*
X307054Y364322D01*
G01X308418Y363534D02*
G02X307067Y364299I0J1575D01*
G01X308564Y363534D02*
X308418D01*
G01X311798Y363160D02*
X308564Y363534D01*
G01X353722Y366272D02*
G02X355686Y367435I2015J-1163D01*
G01X353656Y366159D02*
X353722Y366272D01*
G01X352357Y363160D02*
X353656Y366159D01*
G01X300360Y342610D02*
X301659Y345609D01*
G01X300294Y342497D02*
X300360Y342610D01*
G01X298364Y341335D02*
G03X300294Y342497I-85J2325D01*
G01X296979Y341335D02*
X298364D01*
G01X326100Y401289D02*
X324248Y403141D01*
G01X326100Y395031D02*
Y401289D01*
G01X333136Y387995D02*
X326100Y395031D01*
G01X333136Y383646D02*
Y387995D01*
G01X334495Y382287D02*
X333136Y383646D01*
G01X334882Y382287D02*
X334495D01*
G01X334883Y382286D02*
X334882Y382287D01*
G01X335165Y382286D02*
X334883D01*
G01X335167Y382284D02*
X335165Y382286D01*
G01X335517Y382284D02*
X335167D01*
G01X336842Y379956D02*
G03X335517Y382284I-1384J753D01*
G01X336823Y379922D02*
X336842Y379956D01*
G01X336798Y379880D02*
X336823Y379922D01*
G01Y377597D02*
G02X336798Y379880I2015J1164D01*
G01X336842Y376056D02*
G03X336823Y377597I-1384J754D01*
G01Y376022D02*
X336842Y376056D01*
G01X336798Y375980D02*
X336823Y376022D01*
G01Y373697D02*
G02X336798Y375980I2015J1164D01*
G01X336842Y372156D02*
G03X336823Y373697I-1384J754D01*
G01Y372122D02*
X336842Y372156D01*
G01X338768Y368634D02*
G02X336823Y372122I70J2325D01*
G01X338909Y368634D02*
X338768D01*
G01X340203Y366272D02*
G03X338909Y368634I-1365J788D01*
G01X340178Y363989D02*
G02X340203Y366272I2040J1119D01*
G01Y363947D02*
X340178Y363989D01*
G01X340222Y363913D02*
X340203Y363947D01*
G01Y362372D02*
G03X340222Y363913I-1365J787D01*
G01X340178Y360089D02*
G02X340203Y362372I2040J1119D01*
G01Y360047D02*
X340178Y360089D01*
G01X340222Y360013D02*
X340203Y360047D01*
G01Y358472D02*
G03X340222Y360013I-1365J787D01*
G01X340178Y356189D02*
G02X340203Y358472I2040J1119D01*
G01Y356147D02*
X340178Y356189D01*
G01X340222Y356113D02*
X340203Y356147D01*
G01Y354572D02*
G03X340222Y356113I-1365J787D01*
G01X340178Y352289D02*
G02X340203Y354572I2040J1119D01*
G01Y352247D02*
X340178Y352289D01*
G01X340222Y352213D02*
X340203Y352247D01*
G01Y350672D02*
G03X340222Y352213I-1365J787D01*
G01X340178Y348389D02*
G02X340203Y350672I2040J1119D01*
G01Y348347D02*
X340178Y348389D01*
G01X340222Y348313D02*
X340203Y348347D01*
G01X338897Y345985D02*
G03X340222Y348313I-59J1575D01*
G01X338838Y345985D02*
X338897D01*
G01X338121Y345571D02*
G02X338838Y345985I717J-414D01*
G01X337454Y344413D02*
X338121Y345571D01*
G01X337473Y342872D02*
G02X337454Y344413I1365J787D01*
G01X311196Y394851D02*
Y403447D01*
G01X313601Y392446D02*
X311196Y394851D01*
G01X313601Y388493D02*
Y392446D01*
G01X315121Y386934D02*
G02X313601Y388493I57J1576D01*
G01X315263Y386934D02*
X315121D01*
G01X317193Y385772D02*
G03X315263Y386934I-2015J-1163D01*
G01X318499Y384985D02*
G02X317193Y385772I59J1575D01*
G01X318628Y384985D02*
X318499D01*
G01X320573Y383822D02*
G03X318628Y384985I-2015J-1162D01*
G01X321938Y383034D02*
G02X320573Y383822I0J1576D01*
G01X322023Y383034D02*
X321938D01*
G01X323978Y379589D02*
G03X322023Y383034I-2040J1120D01*
G01X323953Y379547D02*
X323978Y379589D01*
G01X323934Y379513D02*
X323953Y379547D01*
G01X325259Y377185D02*
G02X323934Y379513I59J1575D01*
G01X325388Y377185D02*
X325259D01*
G01X327333Y373697D02*
G03X325388Y377185I-2015J1163D01*
G01X327314Y372156D02*
G02X327333Y373697I1384J754D01*
G01Y372122D02*
X327314Y372156D01*
G01X327358Y369839D02*
G03X327333Y372122I-2040J1119D01*
G01Y369797D02*
X327358Y369839D01*
G01X327333Y368223D02*
G02Y369797I1365J787D01*
G01Y365898D02*
G03Y368223I-2016J1162D01*
G01X328699Y363534D02*
G02X327333Y365898I0J1577D01*
G01X328700Y363534D02*
X328699D01*
G01X330713Y360048D02*
G03X328700Y363534I-2013J1162D01*
G01X330713Y358474D02*
G02Y360048I1365J787D01*
G01Y356148D02*
G03Y358474I-2015J1163D01*
G01Y354574D02*
G02Y356148I1365J787D01*
G01Y352248D02*
G03Y354574I-2015J1163D01*
G01Y350674D02*
G02Y352248I1365J787D01*
G01Y348348D02*
G03Y350674I-2015J1163D01*
G01Y346774D02*
G02Y348348I1365J787D01*
G01X330871Y346443D02*
G03X330713Y346774I-2172J-834D01*
G01X332078Y343660D02*
X330871Y346443D01*
G01X294970Y370584D02*
X294814D01*
G01X296264Y369797D02*
G03X294970Y370584I-1365J-787D01*
G01X298209Y368634D02*
G02X296264Y369797I70J2325D01*
G01X298350Y368634D02*
X298209D01*
G01X299644Y367847D02*
G03X298350Y368634I-1365J-787D01*
G01X301608Y366684D02*
G02X299644Y367847I51J2326D01*
G01X301718Y366684D02*
X301608D01*
G01X303024Y365897D02*
G03X301718Y366684I-1365J-788D01*
G01X304954Y364735D02*
G02X303024Y365897I85J2325D01*
G01X305039Y364735D02*
X304954D01*
G01X306390Y363970D02*
G03X305039Y364735I-1351J-810D01*
G01X306403Y363947D02*
X306390Y363970D01*
G01X308348Y362784D02*
G02X306403Y363947I70J2325D01*
G01X308477Y362784D02*
X308348D01*
G01X309783Y361997D02*
G03X308477Y362784I-1365J-788D01*
G01X310497Y361585D02*
G02X309783Y361997I0J825D01*
G01X311940Y361585D02*
X310497D01*
G01X315178Y361209D02*
X311940Y361585D01*
G01X346354Y393037D02*
Y395968D01*
G01X346489Y392251D02*
X346354Y393037D01*
G01X346963Y391247D02*
G02X346489Y392251I7091J3962D01*
G01X346982Y391213D02*
X346963Y391247D01*
G01Y389672D02*
G03X346982Y391213I-1365J787D01*
G01X346938Y387389D02*
G02X346963Y389672I2040J1119D01*
G01Y387347D02*
X346938Y387389D01*
G01X346982Y387313D02*
X346963Y387347D01*
G01X345657Y384985D02*
G03X346982Y387313I-59J1575D01*
G01X345528Y384985D02*
X345657D01*
G01X343583Y383822D02*
G02X345528Y384985I2015J-1162D01*
G01X343515Y383705D02*
X343583Y383822D01*
G01X342218Y380709D02*
X343515Y383705D01*
G01X305996Y403003D02*
X306875Y403882D01*
G01X305996Y398351D02*
Y403003D01*
G01X307996Y396351D02*
X305996Y398351D01*
G01X307996Y393251D02*
Y396351D01*
G01X310921Y390326D02*
X307996Y393251D01*
G01X310921Y388220D02*
Y390326D01*
G01X310414Y387313D02*
X310921Y388220D01*
G01X311739Y384985D02*
G02X310414Y387313I59J1575D01*
G01X311868Y384985D02*
X311739D01*
G01X313813Y383822D02*
G03X311868Y384985I-2015J-1162D01*
G01X315134Y383034D02*
G02X313813Y383822I44J1575D01*
G01X315263Y383034D02*
X315134D01*
G01X317193Y381872D02*
G03X315263Y383034I-2015J-1163D01*
G01X318499Y381085D02*
G02X317193Y381872I59J1575D01*
G01X318628Y381085D02*
X318499D01*
G01X320573Y377597D02*
G03X318628Y381085I-2015J1163D01*
G01X321894Y375234D02*
G02X320573Y377597I44J1575D01*
G01X322023Y375234D02*
X321894D01*
G01X323953Y371746D02*
G03X322023Y375234I-2015J1163D01*
G01X323953Y370172D02*
G02Y371746I1365J787D01*
G01X323978Y370130D02*
X323953Y370172D01*
G01Y367847D02*
G03X323978Y370130I-2015J1164D01*
G01X323934Y367813D02*
X323953Y367847D01*
G01Y366272D02*
G02X323934Y367813I1365J787D01*
G01X323978Y363989D02*
G03X323953Y366272I-2040J1119D01*
G01Y363947D02*
X323978Y363989D01*
G01X323934Y363913D02*
X323953Y363947D01*
G01X325259Y361585D02*
G02X323934Y363913I59J1575D01*
G01X325388Y361585D02*
X325259D01*
G01X327333Y358097D02*
G03X325388Y361585I-2015J1163D01*
G01X327314Y356556D02*
G02X327333Y358097I1384J754D01*
G01Y356522D02*
X327314Y356556D01*
G01X327358Y356480D02*
X327333Y356522D01*
G01Y354197D02*
G03X327358Y356480I-2015J1164D01*
G01X327314Y352656D02*
G02X327333Y354197I1384J754D01*
G01Y352622D02*
X327314Y352656D01*
G01X327358Y352580D02*
X327333Y352622D01*
G01Y350297D02*
G03X327358Y352580I-2015J1164D01*
G01X327314Y348756D02*
G02X327333Y350297I1384J754D01*
G01Y348722D02*
X327314Y348756D01*
G01X327358Y348680D02*
X327333Y348722D01*
G01Y346397D02*
G03X327358Y348680I-2015J1164D01*
G01X327314Y344856D02*
G02X327333Y346397I1384J754D01*
G01X327401Y344705D02*
X327314Y344856D01*
G01X328698Y341709D02*
X327401Y344705D01*
G01X348354Y394604D02*
Y396007D01*
G01X347404Y393654D02*
X348354Y394604D01*
G01X347404Y392403D02*
Y393654D01*
G01X347613Y391623D02*
G02X347404Y392403I1352J780D01*
G01X347920Y390317D02*
G03X347613Y391623I-2322J143D01*
G01X348978Y389259D02*
X347920Y390317D01*
G01X348978Y388509D02*
Y389259D01*
G01X294855Y386934D02*
G02X293534Y387722I44J1575D01*
G01X294984Y386934D02*
X294855D01*
G01X296914Y385772D02*
G03X294984Y386934I-2015J-1163D01*
G01X298220Y384985D02*
G02X296914Y385772I59J1575D01*
G01X298349Y384985D02*
X298220D01*
G01X300294Y383822D02*
G03X298349Y384985I-2015J-1162D01*
G01X301615Y383034D02*
G02X300294Y383822I44J1575D01*
G01X301744Y383034D02*
X301615D01*
G01X303674Y381872D02*
G03X301744Y383034I-2015J-1163D01*
G01X304980Y381085D02*
G02X303674Y381872I59J1575D01*
G01X305109Y381085D02*
X304980D01*
G01X307054Y379922D02*
G03X305109Y381085I-2015J-1162D01*
G01X307067Y379899D02*
X307054Y379922D01*
G01X308418Y379134D02*
G02X307067Y379899I0J1575D01*
G01X308503Y379134D02*
X308418D01*
G01X310433Y377972D02*
G03X308503Y379134I-2015J-1163D01*
G01X311739Y377185D02*
G02X310433Y377972I59J1575D01*
G01X311868Y377185D02*
X311739D01*
G01X313813Y376022D02*
G03X311868Y377185I-2015J-1162D01*
G01X313881Y375905D02*
X313813Y376022D01*
G01X315178Y372909D02*
X313881Y375905D01*
G01X310448Y394541D02*
Y403653D01*
G01X312851Y392138D02*
X310448Y394541D01*
G01X312851Y388489D02*
Y392138D01*
G01X315108Y386184D02*
G02X312851Y388489I70J2326D01*
G01X315237Y386184D02*
X315108D01*
G01X316543Y385397D02*
G03X315237Y386184I-1365J-788D01*
G01X318473Y384235D02*
G02X316543Y385397I85J2325D01*
G01X318602Y384235D02*
X318473D01*
G01X319923Y383447D02*
G03X318602Y384235I-1365J-787D01*
G01X321938Y382284D02*
G02X319923Y383447I0J2327D01*
G01X321997Y382284D02*
X321938D01*
G01X323322Y379956D02*
G03X321997Y382284I-1384J753D01*
G01X323303Y379922D02*
X323322Y379956D01*
G01X323278Y379880D02*
X323303Y379922D01*
G01X325233Y376435D02*
G02X323278Y379880I85J2325D01*
G01X325362Y376435D02*
X325233D01*
G01X326683Y374072D02*
G03X325362Y376435I-1365J788D01*
G01X326683Y371746D02*
G02Y374072I2015J1163D01*
G01Y370172D02*
G03Y371746I-1365J787D01*
G01X326658Y370130D02*
X326683Y370172D01*
G01Y367847D02*
G02X326658Y370130I2015J1164D01*
G01X326683Y366274D02*
G03Y367847I-1363J787D01*
G01X328698Y362784D02*
G02X326683Y366274I0J2327D01*
G01X328700Y362784D02*
X328698D01*
G01X330063Y360424D02*
G03X328700Y362784I-1363J786D01*
G01X330063Y358098D02*
G02Y360424I2015J1163D01*
G01Y356524D02*
G03Y358098I-1365J787D01*
G01Y354198D02*
G02Y356524I2015J1163D01*
G01Y352624D02*
G03Y354198I-1365J787D01*
G01Y350298D02*
G02Y352624I2015J1163D01*
G01Y348724D02*
G03Y350298I-1365J787D01*
G01Y346398D02*
G02Y348724I2015J1163D01*
G01Y344824D02*
G03Y346398I-1365J787D01*
G01Y342498D02*
G02Y344824I2015J1163D01*
G01X330580Y341602D02*
X330063Y342498D01*
G01X311739Y365485D02*
G02X310951Y365720I63J1648D01*
G01X311868Y365485D02*
X311739D01*
G01X313813Y364322D02*
G03X311868Y365485I-2015J-1162D01*
G01X315134Y363534D02*
G02X313813Y364322I44J1575D01*
G01X315324Y363534D02*
X315134D01*
G01X318558Y363160D02*
X315324Y363534D01*
G01X294958Y374484D02*
X294829D01*
G01X296264Y373697D02*
G03X294958Y374484I-1365J-788D01*
G01X298228Y372534D02*
G02X296264Y373697I51J2326D01*
G01X298323Y372534D02*
X298228D01*
G01X299644Y371746D02*
G03X298323Y372534I-1365J-787D01*
G01X301574Y370584D02*
G02X299644Y371746I85J2325D01*
G01X301730Y370584D02*
X301574D01*
G01X303024Y369797D02*
G03X301730Y370584I-1365J-787D01*
G01X304969Y368634D02*
G02X303024Y369797I70J2325D01*
G01X305087Y368634D02*
X304969D01*
G01X306403Y367847D02*
G03X305087Y368634I-1364J-787D01*
G01X306402Y367847D02*
X306403D01*
G01X306416Y367822D02*
X306402Y367847D01*
G01X308418Y366683D02*
G02X306416Y367822I-1J2328D01*
G01X309352Y366683D02*
X308418D01*
G01X310951Y365720D02*
X309352Y366683D01*
G01X294855Y367435D02*
G02X293534Y368223I44J1575D01*
G01X295036Y367435D02*
X294855D01*
G01X298279Y367060D02*
X295036Y367435D01*
G01X354168Y396579D02*
Y404276D01*
G01X351768Y394179D02*
X354168Y396579D01*
G01X351768Y388694D02*
Y394179D01*
G01X350993Y387347D02*
G03X351768Y388694I-551038J317938D01*
G01X350993Y385773D02*
G02Y387347I1364J787D01*
G01X351028Y383507D02*
G03X350993Y385773I-2050J1102D01*
G01Y383447D02*
X351028Y383507D01*
G01X350993Y381873D02*
G02Y383447I1364J787D01*
G01X351028Y379607D02*
G03X350993Y381873I-2050J1102D01*
G01Y379547D02*
X351028Y379607D01*
G01X350993Y377973D02*
G02Y379547I1364J787D01*
G01X351056Y377866D02*
X350993Y377973D01*
G01X352357Y374860D02*
X351056Y377866D01*
G01X329548Y395917D02*
Y404899D01*
G01X337732Y387733D02*
X329548Y395917D01*
G01X340222Y383413D02*
X337732Y387733D01*
G01X340203Y381872D02*
G03X340222Y383413I-1365J787D01*
G01X340178Y379589D02*
G02X340203Y381872I2040J1119D01*
G01Y379547D02*
X340178Y379589D01*
G01X340222Y379513D02*
X340203Y379547D01*
G01Y377972D02*
G03X340222Y379513I-1365J787D01*
G01X340178Y375689D02*
G02X340203Y377972I2040J1119D01*
G01Y375647D02*
X340178Y375689D01*
G01X340222Y375613D02*
X340203Y375647D01*
G01Y374072D02*
G03X340222Y375613I-1365J787D01*
G01X342133Y370584D02*
G02X340203Y374072I85J2325D01*
G01X342289Y370584D02*
X342133D01*
G01X343583Y368223D02*
G03X342289Y370584I-1365J787D01*
G01X343583Y365897D02*
G02Y368223I2015J1163D01*
G01X343602Y364356D02*
G03X343583Y365897I-1384J754D01*
G01Y364322D02*
X343602Y364356D01*
G01X343558Y364280D02*
X343583Y364322D01*
G01Y361997D02*
G02X343558Y364280I2015J1164D01*
G01X343602Y360456D02*
G03X343583Y361997I-1384J754D01*
G01Y360422D02*
X343602Y360456D01*
G01X343558Y360380D02*
X343583Y360422D01*
G01Y358097D02*
G02X343558Y360380I2015J1164D01*
G01X343602Y356556D02*
G03X343583Y358097I-1384J754D01*
G01Y356522D02*
X343602Y356556D01*
G01X343558Y356480D02*
X343583Y356522D01*
G01Y354197D02*
G02X343558Y356480I2015J1164D01*
G01X343602Y352656D02*
G03X343583Y354197I-1384J754D01*
G01Y352622D02*
X343602Y352656D01*
G01X343558Y352580D02*
X343583Y352622D01*
G01Y350297D02*
G02X343558Y352580I2015J1164D01*
G01X343602Y348756D02*
G03X343583Y350297I-1384J754D01*
G01Y348722D02*
X343602Y348756D01*
G01X343558Y348680D02*
X343583Y348722D01*
G01Y346397D02*
G02X343558Y348680I2015J1164D01*
G01X342262Y344034D02*
G03X343583Y346397I-44J1575D01*
G01X342218Y344034D02*
X342262D01*
G01X341501Y343620D02*
G02X342218Y344034I717J-414D01*
G01X340853Y342497D02*
X341501Y343620D01*
G01X297401Y399922D02*
Y407346D01*
G01X296895Y399013D02*
X297401Y399922D01*
G01X296914Y397472D02*
G02X296895Y399013I1365J787D01*
G01X296914Y395146D02*
G03Y397472I-2015J1163D01*
G01Y393572D02*
G02Y395146I1365J787D01*
G01X296939Y393530D02*
X296914Y393572D01*
G01Y391247D02*
G03X296939Y393530I-2015J1164D01*
G01X296895Y391213D02*
X296914Y391247D01*
G01X298220Y388885D02*
G02X296895Y391213I59J1575D01*
G01X298349Y388885D02*
X298220D01*
G01X300294Y387722D02*
G03X298349Y388885I-2015J-1162D01*
G01X301615Y386934D02*
G02X300294Y387722I44J1575D01*
G01X301744Y386934D02*
X301615D01*
G01X303674Y385772D02*
G03X301744Y386934I-2015J-1163D01*
G01X304980Y384985D02*
G02X303674Y385772I59J1575D01*
G01X305109Y384985D02*
X304980D01*
G01X307054Y383822D02*
G03X305109Y384985I-2015J-1162D01*
G01X307067Y383799D02*
X307054Y383822D01*
G01X308418Y383034D02*
G02X307067Y383799I0J1575D01*
G01X308503Y383034D02*
X308418D01*
G01X310433Y381872D02*
G03X308503Y383034I-2015J-1163D01*
G01X311739Y381085D02*
G02X310433Y381872I59J1575D01*
G01X311868Y381085D02*
X311739D01*
G01X313813Y379922D02*
G03X311868Y381085I-2015J-1162D01*
G01X315134Y379134D02*
G02X313813Y379922I44J1575D01*
G01X315263Y379134D02*
X315134D01*
G01X317193Y377972D02*
G03X315263Y379134I-2015J-1163D01*
G01X317259Y377859D02*
X317193Y377972D01*
G01X318558Y374860D02*
X317259Y377859D01*
G01X294958Y386184D02*
X294829D01*
G01X296264Y385397D02*
G03X294958Y386184I-1365J-788D01*
G01X298194Y384235D02*
G02X296264Y385397I85J2325D01*
G01X298323Y384235D02*
X298194D01*
G01X299644Y383447D02*
G03X298323Y384235I-1365J-787D01*
G01X301589Y382284D02*
G02X299644Y383447I70J2325D01*
G01X301718Y382284D02*
X301589D01*
G01X303024Y381497D02*
G03X301718Y382284I-1365J-788D01*
G01X304954Y380335D02*
G02X303024Y381497I85J2325D01*
G01X305039Y380335D02*
X304954D01*
G01X306390Y379570D02*
G03X305039Y380335I-1351J-810D01*
G01X306403Y379547D02*
X306390Y379570D01*
G01X308348Y378384D02*
G02X306403Y379547I70J2325D01*
G01X308477Y378384D02*
X308348D01*
G01X309783Y377597D02*
G03X308477Y378384I-1365J-788D01*
G01X311713Y376435D02*
G02X309783Y377597I85J2325D01*
G01X311842Y376435D02*
X311713D01*
G01X313163Y374072D02*
G03X311842Y376435I-1365J788D01*
G01X313163Y373249D02*
G02Y374072I713J412D01*
G01X313813Y372122D02*
X313163Y373249D01*
G01X315107Y371335D02*
G02X313813Y372122I71J1574D01*
G01X315248Y371335D02*
X315107D01*
G01X317193Y370172D02*
G03X315248Y371335I-2015J-1162D01*
G01X318487Y369385D02*
G02X317193Y370172I71J1574D01*
G01X318702Y369385D02*
X318487D01*
G01X321938Y369010D02*
X318702Y369385D01*
G01X353554Y406242D02*
Y407821D01*
G01X352918Y405606D02*
X353554Y406242D01*
G01X325048Y405345D02*
X325875Y406172D01*
G01X325048Y403441D02*
Y405345D01*
G01X330296Y404899D02*
X331248Y405851D01*
G01X324248Y405299D02*
X323375Y406172D01*
G01X324248Y403141D02*
Y405299D01*
G01X311196Y403447D02*
X312175Y404426D01*
G01X310448Y403653D02*
X309675Y404426D01*
G01X354168Y404276D02*
X355554Y405662D01*
G01X329548Y404899D02*
X328748Y405699D01*
G01X408820Y-18985D02*
X462616D01*
G01X406158Y-21647D02*
X408820Y-18985D01*
G01X376118Y197980D02*
Y196930D01*
G01X371017Y203081D02*
X376118Y197980D01*
G01X371017Y213280D02*
Y203081D01*
G01X369257Y216909D02*
X371017Y213280D01*
G01X394216Y215860D02*
X392916Y218860D01*
G01X394281Y215748D02*
X394216Y215860D01*
G01X394281Y214174D02*
G03Y215748I-1365J787D01*
G01Y211848D02*
G02Y214174I2015J1163D01*
G01Y210274D02*
G03Y211848I-1365J787D01*
G01X393970Y209180D02*
G02X394281Y210274I2326J-70D01*
G01X393970Y207780D02*
Y209180D01*
G01X397192Y202457D02*
X393970Y207780D01*
G01X399198Y194629D02*
X397192Y202457D01*
G01X400898Y192929D02*
X399198Y194629D01*
G01X400898Y191694D02*
Y192929D01*
G01X364512Y215748D02*
G03Y218074I-2015J1163D01*
G01Y214174D02*
G02Y215748I1365J787D01*
G01X364892Y213554D02*
X364512Y214174D01*
G01X364892Y204703D02*
Y213554D01*
G01X364292Y203668D02*
X364892Y204703D01*
G01X364292Y202200D02*
Y203668D01*
G01X366079Y200413D02*
X364292Y202200D01*
G01X366079Y198554D02*
Y200413D01*
G01X406198Y192494D02*
Y190981D01*
G01X401392Y197300D02*
X406198Y192494D01*
G01X401392Y203685D02*
Y197300D01*
G01X400663Y204692D02*
X401392Y203685D01*
G01X398534Y205789D02*
X400663Y204692D01*
G01X397968Y207031D02*
X398534Y205789D01*
G01X397968Y209280D02*
Y207031D01*
G01X396296Y213009D02*
X397968Y209280D01*
G01X360827Y204830D02*
Y234480D01*
G01X361818Y200033D02*
X360827Y204830D01*
G01X361818Y198627D02*
Y200033D01*
G01X381318Y196764D02*
Y190630D01*
G01X374264Y203818D02*
X381318Y196764D01*
G01X374264Y206969D02*
Y203818D01*
G01X374002Y207948D02*
G02X374264Y206969I-1698J-979D01*
G01X373937Y208060D02*
X374002Y207948D01*
G01X372637Y211061D02*
X373937Y208060D01*
G01X372637Y211060D02*
Y211061D01*
G01X379318Y192034D02*
Y191223D01*
G01X379918Y192634D02*
X379318Y192034D01*
G01X379918Y196157D02*
Y192634D01*
G01X374434Y201642D02*
X379918Y196157D01*
G01X372637Y203438D02*
X374434Y201642D01*
G01X372637Y207159D02*
Y203438D01*
G01X370118Y199974D02*
Y198554D01*
G01X368392Y201700D02*
X370118Y199974D01*
G01X368392Y211501D02*
Y201700D01*
G01X367682Y212211D02*
X368392Y211501D01*
G01X367682Y212974D02*
Y212211D01*
G01X367892Y213798D02*
G03X367682Y212974I1365J-787D01*
G01X367892Y216124D02*
G02Y213798I-2015J-1163D01*
G01Y217698D02*
G03Y216124I1365J-787D01*
G01Y220024D02*
G02Y217698I-2015J-1163D01*
G01X356188Y201404D02*
Y200081D01*
G01X384518Y196538D02*
Y194697D01*
G01X380966Y200090D02*
X384518Y196538D01*
G01X380966Y202825D02*
Y200090D01*
G01X378292Y205500D02*
X380966Y202825D01*
G01X377692Y206099D02*
X378292Y205500D01*
G01X377692Y209660D02*
Y206099D01*
G01X376352Y211000D02*
X377692Y209660D01*
G01X375800Y211000D02*
X376352D01*
G01X374318Y212482D02*
X375800Y211000D01*
G01X374318Y238698D02*
Y212482D01*
G01X374118Y198081D02*
Y197381D01*
G01X372496Y199704D02*
X374118Y198081D01*
G01X370002Y202197D02*
X372496Y199704D01*
G01X370002Y211291D02*
Y202197D01*
G01X369257Y213009D02*
X370002Y211291D01*
G01X363862Y217698D02*
G02Y220024I2015J1163D01*
G01Y216124D02*
G03Y217698I-1365J787D01*
G01Y213798D02*
G02Y216124I2015J1163D01*
G01X364073Y212995D02*
G03X363862Y213798I-1576J15D01*
G01X364073Y204788D02*
Y212995D01*
G01X363492Y203785D02*
X364073Y204788D01*
G01X363492Y201200D02*
Y203785D01*
G01X363868Y200824D02*
X363492Y201200D01*
G01X363868Y198651D02*
Y200824D01*
G01X402898Y193042D02*
Y191500D01*
G01X399928Y196012D02*
X402898Y193042D01*
G01X398061Y202973D02*
X399928Y196012D01*
G01X394931Y208324D02*
X398061Y202973D01*
G01X394931Y209898D02*
G03Y208324I1365J-787D01*
G01Y212224D02*
G02Y209898I-2015J-1163D01*
G01Y213798D02*
G03Y212224I1365J-787D01*
G01X394996Y213910D02*
X394931Y213798D01*
G01X396296Y216909D02*
X394996Y213910D01*
G01X397648Y191865D02*
Y190969D01*
G01X393829Y198479D02*
X397648Y191865D01*
G01X391342Y200966D02*
X393829Y198479D01*
G01X391342Y207450D02*
Y200966D01*
G01X392092Y208200D02*
X391342Y207450D01*
G01X392092Y210236D02*
Y208200D01*
G01X392916Y211060D02*
X392092Y210236D01*
G01X392448Y192936D02*
Y191624D01*
G01X391292Y194092D02*
X392448Y192936D01*
G01X391292Y197000D02*
Y194092D01*
G01X387792Y200500D02*
X391292Y197000D01*
G01X387792Y215700D02*
Y200500D01*
G01X386583Y216909D02*
X387792Y215700D01*
G01X382777Y216909D02*
X386583D01*
G01X368118Y200073D02*
Y198724D01*
G01X367492Y200699D02*
X368118Y200073D01*
G01X367492Y211100D02*
Y200699D01*
G01X366930Y211662D02*
X367492Y211100D01*
G01X366930Y213000D02*
Y211662D01*
G01X367242Y214174D02*
G03X366930Y213000I2015J-1164D01*
G01X367242Y215748D02*
G02Y214174I-1365J-787D01*
G01Y218074D02*
G03Y215748I2015J-1163D01*
G01X357541Y214979D02*
Y231830D01*
G01X357752Y214172D02*
G02X357541Y214979I1365J788D01*
G01X357777Y211889D02*
G03X357752Y214172I-2040J1119D01*
G01Y211847D02*
X357777Y211889D01*
G01X357733Y211813D02*
X357752Y211847D01*
G01Y210272D02*
G02X357733Y211813I1365J787D01*
G01X359068Y208128D02*
X357752Y210272D01*
G01X359068Y204830D02*
Y208128D01*
G01X359818Y201581D02*
X359068Y204830D01*
G01X359818Y199064D02*
Y201581D01*
G01X408198Y192394D02*
Y191151D01*
G01X402192Y198400D02*
X408198Y192394D01*
G01X402192Y204643D02*
Y198400D01*
G01X399676Y207159D02*
X402192Y204643D01*
G01X395648Y193480D02*
Y191381D01*
G01X392960Y198132D02*
X395648Y193480D01*
G01X390492Y200600D02*
X392960Y198132D01*
G01X390492Y207700D02*
Y200600D01*
G01X391118Y208326D02*
X390492Y207700D01*
G01X391118Y209630D02*
Y208326D01*
G01X389537Y213009D02*
X391118Y209630D01*
G01X386518Y196794D02*
Y195037D01*
G01X384592Y198720D02*
X386518Y196794D01*
G01X384592Y202688D02*
Y198720D01*
G01X380971Y206309D02*
X384592Y202688D01*
G01X380971Y209121D02*
Y206309D01*
G01X377692Y212400D02*
X380971Y209121D01*
G01X377692Y238634D02*
Y212400D01*
G01X390448Y196444D02*
Y191575D01*
G01X386592Y200300D02*
X390448Y196444D01*
G01X386592Y204498D02*
Y200300D01*
G01X384492Y206598D02*
X386592Y204498D01*
G01X384492Y213600D02*
Y206598D01*
G01X383392Y214700D02*
X384492Y213600D01*
G01X382629Y214700D02*
X383392D01*
G01X380216Y217113D02*
X382629Y214700D01*
G01X379397Y218860D02*
X380216Y217113D01*
G01X357992Y247800D02*
X356352Y246160D01*
G01X359792Y247800D02*
X357992D01*
G01X360921Y246671D02*
X359792Y247800D01*
G01X360921Y244200D02*
Y246671D01*
G01X362453Y242634D02*
G02X360921Y244200I44J1575D01*
G01X362803Y242634D02*
X362453D01*
G01X364302Y241135D02*
X362803Y242634D01*
G01X364302Y238405D02*
Y241135D01*
G01X364512Y237574D02*
G02X364302Y238405I1365J787D01*
G01X364512Y235248D02*
G03Y237574I-2015J1163D01*
G01Y233674D02*
G02Y235248I1365J787D01*
G01Y231348D02*
G03Y233674I-2015J1163D01*
G01Y229774D02*
G02Y231348I1365J787D01*
G01Y227448D02*
G03Y229774I-2015J1163D01*
G01Y225874D02*
G02Y227448I1365J787D01*
G01Y223548D02*
G03Y225874I-2015J1163D01*
G01Y221974D02*
G02Y223548I1365J787D01*
G01Y219648D02*
G03Y221974I-2015J1163D01*
G01Y218074D02*
G02Y219648I1365J787D01*
G01X359338Y236419D02*
X358537Y236851D01*
G01X360437Y235485D02*
X359338Y236419D01*
G01X360827Y234480D02*
X360437Y235485D01*
G01X367892Y221598D02*
G03Y220024I1365J-787D01*
G01Y223924D02*
G02Y221598I-2015J-1163D01*
G01Y225498D02*
G03Y223924I1365J-787D01*
G01Y227824D02*
G02Y225498I-2015J-1163D01*
G01Y229398D02*
G03Y227824I1365J-787D01*
G01Y231724D02*
G02Y229398I-2015J-1163D01*
G01Y233298D02*
G03Y231724I1365J-787D01*
G01Y235624D02*
G02Y233298I-2015J-1163D01*
G01Y237198D02*
G03Y235624I1365J-787D01*
G01X367957Y237310D02*
X367892Y237198D01*
G01X369257Y240309D02*
X367957Y237310D01*
G01X372637Y242260D02*
X374318Y238698D01*
G01X360414Y243164D02*
X359117Y246160D01*
G01X360501Y243013D02*
X360414Y243164D01*
G01X360482Y241472D02*
G03X360501Y243013I-1365J787D01*
G01X362427Y237984D02*
G02X360482Y241472I70J2325D01*
G01X362539Y237984D02*
X362427D01*
G01X362541Y237986D02*
X362539Y237984D01*
G01X363862Y235624D02*
G03X362541Y237986I-1365J787D01*
G01X363862Y233298D02*
G02Y235624I2015J1163D01*
G01Y231724D02*
G03Y233298I-1365J787D01*
G01Y229398D02*
G02Y231724I2015J1163D01*
G01Y227824D02*
G03Y229398I-1365J787D01*
G01Y225498D02*
G02Y227824I2015J1163D01*
G01Y223924D02*
G03Y225498I-1365J787D01*
G01Y221598D02*
G02Y223924I2015J1163D01*
G01Y220024D02*
G03Y221598I-1365J787D01*
G01X367242Y219648D02*
G02Y218074I-1365J-787D01*
G01Y221974D02*
G03Y219648I2015J-1163D01*
G01Y223548D02*
G02Y221974I-1365J-787D01*
G01Y225874D02*
G03Y223548I2015J-1163D01*
G01Y227448D02*
G02Y225874I-1365J-787D01*
G01Y229774D02*
G03Y227448I2015J-1163D01*
G01Y231348D02*
G02Y229774I-1365J-787D01*
G01Y233674D02*
G03Y231348I2015J-1163D01*
G01Y235248D02*
G02Y233674I-1365J-787D01*
G01Y237574D02*
G03Y235248I2015J-1163D01*
G01Y239148D02*
G02Y237574I-1365J-787D01*
G01X367177Y239260D02*
X367242Y239148D01*
G01X365877Y242260D02*
X367177Y239260D01*
G01X356409Y234089D02*
X355933Y234393D01*
G01X357283Y233215D02*
X356409Y234089D01*
G01X357541Y231830D02*
X357283Y233215D01*
G01X376017Y240309D02*
X377692Y238634D01*
G01X357752Y340547D02*
G02X359073Y341335I1365J-787D01*
G01X355807Y339384D02*
G03X357752Y340547I-70J2325D01*
G01X355678Y339384D02*
X355807D01*
G01X357102Y340922D02*
G02X359047Y342085I2015J-1162D01*
G01X355781Y340134D02*
G03X357102Y340922I-44J1575D01*
G01X355652Y340134D02*
X355781D01*
G01X358218Y400326D02*
X359392Y401500D01*
G01X358218Y389330D02*
Y400326D01*
G01X357418Y388530D02*
X358218Y389330D01*
G01X357418Y381121D02*
Y388530D01*
G01X357121Y379956D02*
G03X357418Y381121I-2138J1165D01*
G01X357102Y379922D02*
X357121Y379956D01*
G01X357077Y379880D02*
X357102Y379922D01*
G01Y377597D02*
G02X357077Y379880I2015J1164D01*
G01X357121Y376056D02*
G03X357102Y377597I-1384J754D01*
G01Y376022D02*
X357121Y376056D01*
G01X357077Y375980D02*
X357102Y376022D01*
G01Y373697D02*
G02X357077Y375980I2015J1164D01*
G01X355808Y371335D02*
G03X357102Y373697I-71J1574D01*
G01X355667Y371335D02*
X355808D01*
G01X356368Y395330D02*
Y403476D01*
G01X381592Y401400D02*
Y408614D01*
G01X373418Y393226D02*
X381592Y401400D01*
G01X373418Y391241D02*
Y393226D01*
G01X372637Y390460D02*
X373418Y391241D01*
G01X396092Y390896D02*
Y392507D01*
G01X394491Y389295D02*
X396092Y390896D01*
G01X394491Y386595D02*
Y389295D01*
G01X394281Y385771D02*
G03X394491Y386595I-1365J787D01*
G01X394281Y383445D02*
G02Y385771I2015J1163D01*
G01Y381871D02*
G03Y383445I-1365J787D01*
G01X394216Y381759D02*
X394281Y381871D01*
G01X392916Y378760D02*
X394216Y381759D01*
G01X356891Y344944D02*
X355737Y345609D01*
G01X357243Y345039D02*
X356891Y344944D01*
G01X359047Y345985D02*
G03X357243Y345039I69J-2325D01*
G01X359187Y345985D02*
X359047D01*
G01X359202Y341335D02*
G03X359187Y345985I-85J2325D01*
G01X359073Y341335D02*
X359202D01*
G01X369192Y394099D02*
X369693Y394600D01*
G01X368692Y394099D02*
X369192D01*
G01X367614Y393021D02*
X368692Y394099D01*
G01X367614Y386322D02*
Y393021D01*
G01X367592Y386300D02*
X367614Y386322D01*
G01X367592Y384942D02*
Y386300D01*
G01X367892Y383822D02*
G02X367592Y384942I1940J1120D01*
G01X367892Y381496D02*
G03Y383822I-2015J1163D01*
G01Y379922D02*
G02Y381496I1365J787D01*
G01Y377596D02*
G03Y379922I-2015J1163D01*
G01Y376022D02*
G02Y377596I1365J787D01*
G01Y373696D02*
G03Y376022I-2015J1163D01*
G01Y372122D02*
G02Y373696I1365J787D01*
G01Y369796D02*
G03Y372122I-2015J1163D01*
G01Y368222D02*
G02Y369796I1365J787D01*
G01Y365896D02*
G03Y368222I-2015J1163D01*
G01Y364322D02*
G02Y365896I1365J787D01*
G01Y361996D02*
G03Y364322I-2015J1163D01*
G01Y360422D02*
G02Y361996I1365J787D01*
G01X368117Y359888D02*
G03X367892Y360422I-2240J-629D01*
G01X368892Y358135D02*
X368117Y359888D01*
G01X369257Y357309D02*
X368892Y358135D01*
G01X355807Y347184D02*
X355678D01*
G01X357752Y348347D02*
G02X355807Y347184I-2015J1162D01*
G01X360482Y348347D02*
G03X357752I-1365J-787D01*
G01X362427Y347184D02*
G02X360482Y348347I70J2325D01*
G01X362556Y347184D02*
X362427D01*
G01X363734Y346585D02*
G03X362556Y347184I-1238J-976D01*
G01X363651Y346275D02*
X363734Y346585D01*
G01X362497Y345609D02*
X363651Y346275D01*
G01X360745Y397153D02*
X362292Y398700D01*
G01X360745Y389900D02*
Y397153D01*
G01X360738Y389893D02*
X360745Y389900D01*
G01X360738Y388426D02*
Y389893D01*
G01X361158Y387676D02*
X360738Y388426D01*
G01X361132Y385397D02*
G03X361158Y387676I-2015J1163D01*
G01X361113Y383856D02*
G02X361132Y385397I1384J754D01*
G01Y383822D02*
X361113Y383856D01*
G01X361157Y383780D02*
X361132Y383822D01*
G01Y381497D02*
G03X361157Y383780I-2015J1164D01*
G01X361113Y379956D02*
G02X361132Y381497I1384J754D01*
G01Y379922D02*
X361113Y379956D01*
G01X361157Y379880D02*
X361132Y379922D01*
G01Y377597D02*
G03X361157Y379880I-2015J1164D01*
G01X361113Y376056D02*
G02X361132Y377597I1384J754D01*
G01Y376022D02*
X361113Y376056D01*
G01X361157Y375980D02*
X361132Y376022D01*
G01Y373697D02*
G03X361157Y375980I-2015J1164D01*
G01X361113Y372156D02*
G02X361132Y373697I1384J754D01*
G01Y372122D02*
X361113Y372156D01*
G01X359187Y368634D02*
G03X361132Y372122I-70J2325D01*
G01X359046Y368634D02*
X359187D01*
G01X357752Y367847D02*
G02X359046Y368634I1365J-787D01*
G01X357733Y367813D02*
X357752Y367847D01*
G01X357543Y367067D02*
G02X357733Y367813I1561J0D01*
G01X357543Y353025D02*
Y367067D01*
G01X359108Y351460D02*
X357543Y353025D01*
G01X359117Y351460D02*
X359108D01*
G01X380692Y401600D02*
Y406200D01*
G01X371892Y392800D02*
X380692Y401600D01*
G01X371892Y392000D02*
Y392800D01*
G01X371253Y391213D02*
G02X371892Y392000I2444J-1332D01*
G01X371272Y389672D02*
G02X371253Y391213I1365J787D01*
G01X371297Y387389D02*
G03X371272Y389672I-2040J1119D01*
G01Y387347D02*
X371297Y387389D01*
G01X371253Y387313D02*
X371272Y387347D01*
G01Y385772D02*
G02X371253Y387313I1365J787D01*
G01X371319Y385597D02*
G03X371272Y385772I-351J0D01*
G01X371319Y383927D02*
Y385597D01*
G01X370692Y383300D02*
X371319Y383927D01*
G01X370692Y382144D02*
Y383300D01*
G01X369257Y380709D02*
X370692Y382144D01*
G01X381192Y393000D02*
X382476Y394284D01*
G01X379592Y393000D02*
X381192D01*
G01X379078Y392486D02*
X379592Y393000D01*
G01X378555Y392123D02*
X379078Y392486D01*
G01X378032Y391247D02*
X378555Y392123D01*
G01X378013Y391213D02*
X378032Y391247D01*
G01Y389672D02*
G02X378013Y391213I1365J787D01*
G01X378057Y387389D02*
G03X378032Y389672I-2040J1119D01*
G01Y387347D02*
X378057Y387389D01*
G01X378013Y387313D02*
X378032Y387347D01*
G01Y385772D02*
G02X378013Y387313I1365J787D01*
G01X378057Y383489D02*
G03X378032Y385772I-2040J1119D01*
G01Y383447D02*
X378057Y383489D01*
G01X378013Y383413D02*
X378032Y383447D01*
G01Y381872D02*
G02X378013Y383413I1365J787D01*
G01X378057Y379589D02*
G03X378032Y381872I-2040J1119D01*
G01Y379547D02*
X378057Y379589D01*
G01X378013Y379513D02*
X378032Y379547D01*
G01X377823Y378766D02*
G02X378013Y379513I1562J0D01*
G01X377823Y362507D02*
Y378766D01*
G01X377827Y362503D02*
X377823Y362507D01*
G01X377827Y360389D02*
Y362503D01*
G01X376017Y357309D02*
X377827Y360389D01*
G01X355318Y396080D02*
Y404126D01*
G01X378741Y393972D02*
X379530Y394761D01*
G01X377382Y391622D02*
X378741Y393972D01*
G01X377382Y389296D02*
G02Y391622I2015J1163D01*
G01Y387722D02*
G03Y389296I-1365J787D01*
G01Y385396D02*
G02Y387722I2015J1163D01*
G01Y383822D02*
G03Y385396I-1365J787D01*
G01Y381496D02*
G02Y383822I2015J1163D01*
G01X376061Y379134D02*
G03X377382Y381496I-44J1575D01*
G01X375932Y379134D02*
X376061D01*
G01X374002Y375646D02*
G02X375932Y379134I2015J1163D01*
G01X374002Y374072D02*
G03Y375646I-1365J787D01*
G01Y371746D02*
G02Y374072I2015J1163D01*
G01Y370172D02*
G03Y371746I-1365J787D01*
G01Y367846D02*
G02Y370172I2015J1163D01*
G01Y366272D02*
G03Y367846I-1365J787D01*
G01Y363946D02*
G02Y366272I2015J1163D01*
G01Y362372D02*
G03Y363946I-1365J787D01*
G01X373977Y360089D02*
G02X374002Y362372I2040J1119D01*
G01Y360047D02*
X373977Y360089D01*
G01X374021Y360013D02*
X374002Y360047D01*
G01Y358472D02*
G03X374021Y360013I-1365J787D01*
G01X373847Y358149D02*
G02X374002Y358472I2169J-842D01*
G01X372637Y355360D02*
X373847Y358149D01*
G01X355781Y347934D02*
X355652D01*
G01X357102Y348722D02*
G02X355781Y347934I-1365J787D01*
G01X359047Y349885D02*
G03X357102Y348722I70J-2325D01*
G01X359187Y349885D02*
X359047D01*
G01X361132Y348722D02*
G03X359187Y349885I-2015J-1162D01*
G01X362453Y347934D02*
G02X361132Y348722I44J1575D01*
G01X362582Y347934D02*
X362453D01*
G01X364371Y346989D02*
G03X362582Y347934I-1873J-1380D01*
G01X364723Y346894D02*
X364371Y346989D01*
G01X365877Y347560D02*
X364723Y346894D01*
G01X363592Y397100D02*
X364146Y397654D01*
G01X363592Y394200D02*
Y397100D01*
G01X364096Y393696D02*
X363592Y394200D01*
G01X364096Y384239D02*
Y393696D01*
G01X363862Y383822D02*
X364096Y384239D01*
G01X363837Y383780D02*
X363862Y383822D01*
G01Y381497D02*
G02X363837Y383780I2015J1164D01*
G01X363881Y379956D02*
G03X363862Y381497I-1384J754D01*
G01Y379922D02*
X363881Y379956D01*
G01X363837Y379880D02*
X363862Y379922D01*
G01Y377597D02*
G02X363837Y379880I2015J1164D01*
G01X363881Y376056D02*
G03X363862Y377597I-1384J754D01*
G01Y376022D02*
X363881Y376056D01*
G01X363837Y375980D02*
X363862Y376022D01*
G01Y373697D02*
G02X363837Y375980I2015J1164D01*
G01X363881Y372156D02*
G03X363862Y373697I-1384J754D01*
G01Y372122D02*
X363881Y372156D01*
G01X363837Y369839D02*
G02X363862Y372122I2040J1119D01*
G01Y369797D02*
X363837Y369839D01*
G01X362541Y367435D02*
G03X363862Y369797I-44J1575D01*
G01X362360Y367435D02*
X362541D01*
G01X359117Y367060D02*
X362360Y367435D01*
G01X391292Y391200D02*
X393592Y393500D01*
G01X391292Y388184D02*
Y391200D01*
G01X392916Y386560D02*
X391292Y388184D01*
G01X414593Y401501D02*
Y402640D01*
G01X406492Y393400D02*
X414593Y401501D01*
G01X406492Y365368D02*
Y393400D01*
G01X404292Y363168D02*
X406492Y365368D01*
G01X402360Y363168D02*
X404292D01*
G01X400492Y361300D02*
X402360Y363168D01*
G01X400492Y360076D02*
Y361300D01*
G01X399676Y359260D02*
X400492Y360076D01*
G01X359728Y398986D02*
X360967Y400225D01*
G01X359728Y389015D02*
Y398986D01*
G01X359718Y389005D02*
X359728Y389015D01*
G01X360002Y388205D02*
G02X359718Y389005I2202J1232D01*
G01X360501Y387313D02*
X360002Y388205D01*
G01X360482Y385772D02*
G03X360501Y387313I-1365J787D01*
G01X360457Y383489D02*
G02X360482Y385772I2040J1119D01*
G01Y383447D02*
X360457Y383489D01*
G01X360501Y383413D02*
X360482Y383447D01*
G01Y381872D02*
G03X360501Y383413I-1365J787D01*
G01X360457Y379589D02*
G02X360482Y381872I2040J1119D01*
G01Y379547D02*
X360457Y379589D01*
G01X360501Y379513D02*
X360482Y379547D01*
G01Y377972D02*
G03X360501Y379513I-1365J787D01*
G01X360457Y375689D02*
G02X360482Y377972I2040J1119D01*
G01Y375647D02*
X360457Y375689D01*
G01X360501Y375613D02*
X360482Y375647D01*
G01Y374072D02*
G03X360501Y375613I-1365J787D01*
G01X360482Y371746D02*
G02Y374072I2015J1163D01*
G01X359188Y369385D02*
G03X360482Y371746I-71J1574D01*
G01X359032Y369385D02*
X359188D01*
G01X357102Y368223D02*
G02X359032Y369385I2015J-1163D01*
G01X355781Y367435D02*
G03X357102Y368223I-44J1575D01*
G01X355686Y367435D02*
X355781D01*
G01X398092Y387900D02*
Y391600D01*
G01X397092Y386900D02*
G03X398092Y387900I0J1000D01*
G01X395153Y385780D02*
G02X397092Y386900I1939J-1118D01*
G01X394931Y385395D02*
X395153Y385780D01*
G01X394931Y383821D02*
G02Y385395I1365J787D01*
G01X394996Y383709D02*
X394931Y383821D01*
G01X396296Y380709D02*
X394996Y383709D01*
G01X357963Y344325D02*
X359117Y343660D01*
G01X357880Y344635D02*
X357963Y344325D01*
G01X359176Y342085D02*
G03X357880Y344635I-58J1575D01*
G01X359047Y342085D02*
X359176D01*
G01X365318Y395976D02*
X365667Y396325D01*
G01X365318Y384853D02*
Y395976D01*
G01X364493Y383413D02*
X365318Y384853D01*
G01X364512Y381872D02*
G02X364493Y383413I1365J787D01*
G01X364537Y379589D02*
G03X364512Y381872I-2040J1119D01*
G01Y379547D02*
X364537Y379589D01*
G01X364493Y379513D02*
X364512Y379547D01*
G01Y377972D02*
G02X364493Y379513I1365J787D01*
G01X364537Y375689D02*
G03X364512Y377972I-2040J1119D01*
G01Y375647D02*
X364537Y375689D01*
G01X364493Y375613D02*
X364512Y375647D01*
G01Y374072D02*
G02X364493Y375613I1365J787D01*
G01X364512Y371746D02*
G03Y374072I-2015J1163D01*
G01Y370172D02*
G02Y371746I1365J787D01*
G01X364537Y370130D02*
X364512Y370172D01*
G01Y367847D02*
G03X364537Y370130I-2015J1164D01*
G01X364493Y367813D02*
X364512Y367847D01*
G01X364301Y367050D02*
G02X364493Y367813I1576J9D01*
G01X364301Y360340D02*
Y367050D01*
G01X362497Y357309D02*
X364301Y360340D01*
G01X413642Y396550D02*
X416593Y399501D01*
G01X411042Y396550D02*
X413642D01*
G01X408092Y393600D02*
X411042Y396550D01*
G01X408092Y363709D02*
Y393600D01*
G01X405592Y361209D02*
X408092Y363709D01*
G01X403056Y361209D02*
X405592D01*
G01X366492Y394300D02*
X367042Y394850D01*
G01X366492Y386248D02*
Y394300D01*
G01X367242Y383446D02*
G02X366492Y386248I4861J2802D01*
G01X367242Y381872D02*
G03Y383446I-1365J787D01*
G01Y379546D02*
G02Y381872I2015J1163D01*
G01Y377972D02*
G03Y379546I-1365J787D01*
G01Y375646D02*
G02Y377972I2015J1163D01*
G01Y374072D02*
G03Y375646I-1365J787D01*
G01Y371746D02*
G02Y374072I2015J1163D01*
G01Y370172D02*
G03Y371746I-1365J787D01*
G01Y367846D02*
G02Y370172I2015J1163D01*
G01Y366272D02*
G03Y367846I-1365J787D01*
G01Y363946D02*
G02Y366272I2015J1163D01*
G01Y362372D02*
G03Y363946I-1365J787D01*
G01Y360046D02*
G02Y362372I2015J1163D01*
G01Y358472D02*
G03Y360046I-1365J787D01*
G01X367105Y358194D02*
G02X367242Y358472I2151J-887D01*
G01X365877Y355360D02*
X367105Y358194D01*
G01X411392Y400301D02*
Y401633D01*
G01X404992Y393901D02*
X411392Y400301D01*
G01X404992Y387300D02*
Y393901D01*
G01X402301Y384609D02*
X404992Y387300D01*
G01X396296Y384609D02*
X402301D01*
G01X409392Y400000D02*
Y401553D01*
G01X403692Y394300D02*
X409392Y400000D01*
G01X401792Y394300D02*
X403692D01*
G01X401392Y393900D02*
X401792Y394300D01*
G01X401392Y392176D02*
Y393900D01*
G01X399676Y390460D02*
X401392Y392176D01*
G01X387892Y389100D02*
X392592Y393800D01*
G01X387892Y387900D02*
Y389100D01*
G01X389537Y386255D02*
X387892Y387900D01*
G01X389537Y384609D02*
Y386255D01*
G01X382392Y401100D02*
Y407240D01*
G01X374418Y393126D02*
X382392Y401100D01*
G01X374418Y388341D02*
Y393126D01*
G01X372637Y386560D02*
X374418Y388341D01*
G01X379892Y402000D02*
Y404662D01*
G01X370892Y393000D02*
X379892Y402000D01*
G01X370892Y392700D02*
Y393000D01*
G01X370622Y391623D02*
G03X370892Y392700I-1753J1012D01*
G01X370622Y389297D02*
G02Y391623I2015J1163D01*
G01X370641Y387756D02*
G03X370622Y389297I-1384J754D01*
G01X370554Y387605D02*
X370641Y387756D01*
G01X369257Y384609D02*
X370554Y387605D01*
G01X359554Y406662D02*
Y407781D01*
G01X356368Y403476D02*
X359554Y406662D01*
G01X383154Y410176D02*
Y411204D01*
G01X381592Y408614D02*
X383154Y410176D01*
G01X379954Y406938D02*
Y410706D01*
G01X380692Y406200D02*
X379954Y406938D01*
G01X357554Y406362D02*
Y407727D01*
G01X355318Y404126D02*
X357554Y406362D01*
G01X355554Y405662D02*
Y407821D01*
G01X385154Y410002D02*
Y411284D01*
G01X382392Y407240D02*
X385154Y410002D01*
G01X377954Y406600D02*
Y410841D01*
G01X379892Y404662D02*
X377954Y406600D01*
G01X465023Y-21392D02*
X649970D01*
G01X462616Y-18985D02*
X465023Y-21392D01*
G01X475458Y203512D02*
X478192Y200778D01*
G01X475458Y211043D02*
Y203512D01*
G01X475213Y211632D02*
X475458Y211043D01*
G01X475307Y213084D02*
G03X475213Y211632I1423J-821D01*
G01X475332Y215367D02*
G02X475307Y213084I-2040J-1119D01*
G01Y215409D02*
X475332Y215367D01*
G01X475288Y215443D02*
X475307Y215409D01*
G01Y216984D02*
G03X475288Y215443I1365J-787D01*
G01X475332Y219267D02*
G02X475307Y216984I-2040J-1119D01*
G01X453724Y186257D02*
X454284Y185697D01*
G01X453724Y187037D02*
Y186257D01*
G01X452938Y187823D02*
X453724Y187037D01*
G01X452938Y209589D02*
Y187823D01*
G01X454068Y210719D02*
X452938Y209589D01*
G01X454068Y213026D02*
Y210719D01*
G01X454210Y213168D02*
X454068Y213026D01*
G01X454378Y213459D02*
X454210Y213168D01*
G01X454397Y215000D02*
G02X454378Y213459I-1384J-754D01*
G01Y215034D02*
X454397Y215000D01*
G01X454353Y215076D02*
X454378Y215034D01*
G01Y217359D02*
G03X454353Y215076I2015J-1164D01*
G01X454397Y218900D02*
G02X454378Y217359I-1384J-754D01*
G01X468322Y187929D02*
X467448Y187055D01*
G01X468322Y189685D02*
Y187929D01*
G01X465134Y192873D02*
X468322Y189685D01*
G01X465134Y201299D02*
Y192873D01*
G01X464009Y202424D02*
X465134Y201299D01*
G01X464009Y214192D02*
Y202424D01*
G01X464729Y214912D02*
X464009Y214192D01*
G01X464729Y216196D02*
Y214912D01*
G01X464518Y216984D02*
G02X464729Y216196I-1366J-788D01*
G01X464493Y219267D02*
G03X464518Y216984I2040J-1119D01*
G01X439328Y187064D02*
X440271Y186121D01*
G01X439328Y189868D02*
Y187064D01*
G01X437306Y191890D02*
X439328Y189868D01*
G01X437306Y205186D02*
Y191890D01*
G01X434538Y207954D02*
X437306Y205186D01*
G01X434538Y212300D02*
Y207954D01*
G01X434748Y213084D02*
G03X434538Y212300I1359J-784D01*
G01X434773Y215367D02*
G02X434748Y213084I-2040J-1119D01*
G01Y215409D02*
X434773Y215367D01*
G01X434729Y215443D02*
X434748Y215409D01*
G01Y216984D02*
G03X434729Y215443I1365J-787D01*
G01X434773Y219267D02*
G02X434748Y216984I-2040J-1119D01*
G01X474657Y217359D02*
G03X474676Y218900I-1365J787D01*
G01X474632Y215076D02*
G02X474657Y217359I2040J1119D01*
G01Y215034D02*
X474632Y215076D01*
G01X474676Y215000D02*
X474657Y215034D01*
G01Y213459D02*
G03X474676Y215000I-1365J787D01*
G01X474389Y211735D02*
G02X474657Y213459I2361J516D01*
G01X474709Y210266D02*
X474389Y211735D01*
G01X477392Y197815D02*
X481592Y193615D01*
G01X477392Y200517D02*
Y197815D01*
G01X474709Y203200D02*
X477392Y200517D01*
G01X474709Y210266D02*
Y203200D01*
G01X472440Y199456D02*
X480344Y191552D01*
G01X472440Y208098D02*
Y199456D01*
G01X472241Y208297D02*
X472440Y208098D01*
G01X472241Y212294D02*
Y208297D01*
G01X471928Y213459D02*
G02X472241Y212294I-2015J-1166D01*
G01X471896Y214978D02*
G03X471928Y213459I1396J-730D01*
G01X471963Y215094D02*
X471896Y214978D01*
G01X471928Y217360D02*
G02X471963Y215094I-2015J-1164D01*
G01X471928Y218934D02*
G03Y217360I1364J-787D01*
G01X425658Y189278D02*
X424957Y188577D01*
G01X425658Y192229D02*
Y189278D01*
G01X426270Y192841D02*
X425658Y192229D01*
G01X426270Y202351D02*
Y192841D01*
G01X423577Y205044D02*
X426270Y202351D01*
G01X423577Y208021D02*
Y205044D01*
G01X423809Y208253D02*
X423577Y208021D01*
G01X423809Y215172D02*
Y208253D01*
G01X424170Y215533D02*
X423809Y215172D01*
G01X424170Y216196D02*
Y215533D01*
G01X423959Y216984D02*
G02X424170Y216196I-1364J-787D01*
G01X423934Y219267D02*
G03X423959Y216984I2040J-1119D01*
G01X453688Y188204D02*
X456492Y185400D01*
G01X453688Y209273D02*
Y188204D01*
G01X454818Y210403D02*
X453688Y209273D01*
G01X454818Y212725D02*
Y210403D01*
G01X455026Y213085D02*
X454818Y212725D01*
G01X455028Y213084D02*
X455026Y213085D01*
G01X455053Y215367D02*
G02X455028Y213084I-2040J-1119D01*
G01Y215409D02*
X455053Y215367D01*
G01X455009Y215443D02*
X455028Y215409D01*
G01Y216984D02*
G03X455009Y215443I1365J-787D01*
G01X455053Y219267D02*
G02X455028Y216984I-2040J-1119D01*
G01X438578Y186686D02*
X437771Y185879D01*
G01X438578Y189557D02*
Y186686D01*
G01X436558Y191577D02*
X438578Y189557D01*
G01X436558Y204876D02*
Y191577D01*
G01X433788Y207646D02*
X436558Y204876D01*
G01X433788Y212303D02*
Y207646D01*
G01X434098Y213459D02*
G03X433788Y212303I2002J-1156D01*
G01X434117Y215000D02*
G02X434098Y213459I-1384J-754D01*
G01Y215034D02*
X434117Y215000D01*
G01X434073Y215076D02*
X434098Y215034D01*
G01Y217359D02*
G03X434073Y215076I2015J-1164D01*
G01X434117Y218900D02*
G02X434098Y217359I-1384J-754D01*
G01X450668Y186593D02*
X451592Y185669D01*
G01X450668Y209366D02*
Y186593D01*
G01X451960Y210658D02*
X450668Y209366D01*
G01X451960Y212294D02*
Y210658D01*
G01X451648Y213459D02*
G02X451960Y212294I-2015J-1164D01*
G01X451629Y215000D02*
G03X451648Y213459I1384J-754D01*
G01Y215034D02*
X451629Y215000D01*
G01X451673Y215076D02*
X451648Y215034D01*
G01Y217359D02*
G02X451673Y215076I-2015J-1164D01*
G01X451629Y218900D02*
G03X451648Y217359I1384J-754D01*
G01X420579D02*
G03X420598Y218900I-1365J787D01*
G01X420554Y215076D02*
G02X420579Y217359I2040J1119D01*
G01Y215034D02*
X420554Y215076D01*
G01X420789Y214649D02*
X420579Y215034D01*
G01X420789Y211302D02*
Y214649D01*
G01X420558Y211071D02*
X420789Y211302D01*
G01X420558Y203801D02*
Y211071D01*
G01X423250Y201109D02*
X420558Y203801D01*
G01X423250Y194093D02*
Y201109D01*
G01X420998Y191841D02*
X423250Y194093D01*
G01X420998Y190618D02*
Y191841D01*
G01X419957Y189577D02*
X420998Y190618D01*
G01X469072Y187931D02*
X469948Y187055D01*
G01X469072Y189996D02*
Y187931D01*
G01X465884Y193184D02*
X469072Y189996D01*
G01X465884Y201619D02*
Y193184D01*
G01X464759Y202744D02*
X465884Y201619D01*
G01X464759Y213879D02*
Y202744D01*
G01X465480Y214600D02*
X464759Y213879D01*
G01X465480Y216196D02*
Y214600D01*
G01X465168Y217359D02*
G02X465480Y216196I-2015J-1164D01*
G01X465149Y218900D02*
G03X465168Y217359I1384J-754D01*
G01X444278Y189570D02*
X445271Y188577D01*
G01X444278Y190690D02*
Y189570D01*
G01X440158Y194810D02*
X444278Y190690D01*
G01X440158Y206608D02*
Y194810D01*
G01X437917Y208849D02*
X440158Y206608D01*
G01X437917Y210346D02*
Y208849D01*
G01X438109Y211099D02*
G03X437917Y210346I1384J-754D01*
G01X438128Y211133D02*
X438109Y211099D01*
G01X438128Y213459D02*
G02Y211133I-2015J-1163D01*
G01X438109Y215000D02*
G03X438128Y213459I1384J-754D01*
G01Y215034D02*
X438109Y215000D01*
G01X438153Y215076D02*
X438128Y215034D01*
G01Y217359D02*
G02X438153Y215076I-2015J-1164D01*
G01X438109Y218900D02*
G03X438128Y217359I1384J-754D01*
G01X471690Y199145D02*
X479592Y191243D01*
G01X471690Y207787D02*
Y199145D01*
G01X471488Y207989D02*
X471690Y207787D01*
G01X471488Y212294D02*
Y207989D01*
G01X471277Y213082D02*
G02X471488Y212294I-1364J-788D01*
G01X471235Y215336D02*
G03X471277Y213082I2057J-1089D01*
G01Y215409D02*
X471235Y215336D01*
G01X471277Y216983D02*
G02Y215409I-1364J-787D01*
G01X471242Y219249D02*
G03X471277Y216983I2050J-1102D01*
G01X473320Y187927D02*
X472448Y187055D01*
G01X473320Y188961D02*
Y187927D01*
G01X468160Y194121D02*
X473320Y188961D01*
G01X468160Y207945D02*
Y194121D01*
G01X467588Y208517D02*
X468160Y207945D01*
G01X467588Y216821D02*
Y208517D01*
G01X467898Y217359D02*
X467588Y216821D01*
G01X467917Y218900D02*
G02X467898Y217359I-1384J-754D01*
G01X426408Y189626D02*
X427457Y188577D01*
G01X426408Y191918D02*
Y189626D01*
G01X427020Y192530D02*
X426408Y191918D01*
G01X427020Y202663D02*
Y192530D01*
G01X427021Y202664D02*
X427020Y202663D01*
G01X424328Y205357D02*
X427021Y202664D01*
G01X424328Y205359D02*
Y205357D01*
G01X424326Y205361D02*
X424328Y205359D01*
G01X424326Y207712D02*
Y205361D01*
G01X424559Y207945D02*
X424326Y207712D01*
G01X424559Y214861D02*
Y207945D01*
G01X424920Y215222D02*
X424559Y214861D01*
G01X424920Y216198D02*
Y215222D01*
G01X424609Y217359D02*
G02X424920Y216198I-2012J-1161D01*
G01X424590Y218900D02*
G03X424609Y217359I1384J-754D01*
G01X474070Y187933D02*
X474948Y187055D01*
G01X474070Y189272D02*
Y187933D01*
G01X468910Y194432D02*
X474070Y189272D01*
G01X468910Y208256D02*
Y194432D01*
G01X468338Y208828D02*
X468910Y208256D01*
G01X468338Y216620D02*
Y208828D01*
G01X468548Y216984D02*
X468338Y216620D01*
G01X468573Y219267D02*
G02X468548Y216984I-2040J-1119D01*
G01X421229D02*
G03X421254Y219267I-2015J1164D01*
G01X421210Y215443D02*
G02X421229Y216984I1384J754D01*
G01X421539Y214870D02*
X421210Y215443D01*
G01X421539Y210994D02*
Y214870D01*
G01X421307Y210762D02*
X421539Y210994D01*
G01X421307Y204112D02*
Y210762D01*
G01X424000Y201419D02*
X421307Y204112D01*
G01X424000Y193782D02*
Y201419D01*
G01X421748Y191530D02*
X424000Y193782D01*
G01X421748Y190286D02*
Y191530D01*
G01X422457Y189577D02*
X421748Y190286D01*
G01X443528Y189334D02*
X442771Y188577D01*
G01X443528Y190378D02*
Y189334D01*
G01X439408Y194498D02*
X443528Y190378D01*
G01X439408Y206295D02*
Y194498D01*
G01X437166Y208537D02*
X439408Y206295D01*
G01X437166Y210346D02*
Y208537D01*
G01X437478Y216984D02*
G02X437453Y219267I2015J1164D01*
G01X437497Y215443D02*
G03X437478Y216984I-1384J754D01*
G01Y215409D02*
X437497Y215443D01*
G01X437453Y215367D02*
X437478Y215409D01*
G01Y213084D02*
G02X437453Y215367I2015J1164D01*
G01X437497Y211543D02*
G03X437478Y213084I-1384J754D01*
G01Y211509D02*
X437497Y211543D01*
G01X437166Y210346D02*
G02X437478Y211509I2327J-1D01*
G01X449918Y186374D02*
X449392Y185848D01*
G01X449918Y209677D02*
Y186374D01*
G01X451209Y210968D02*
X449918Y209677D01*
G01X451209Y212294D02*
Y210968D01*
G01X450998Y213084D02*
G02X451209Y212294I-1365J-788D01*
G01X450973Y215367D02*
G03X450998Y213084I2040J-1119D01*
G01Y215409D02*
X450973Y215367D01*
G01X451017Y215443D02*
X450998Y215409D01*
G01Y216984D02*
G02X451017Y215443I-1365J-787D01*
G01X450973Y219267D02*
G03X450998Y216984I2040J-1119D01*
G01X475307Y219309D02*
X475332Y219267D01*
G01X475288Y219343D02*
X475307Y219309D01*
G01Y220884D02*
G03X475288Y219343I1365J-787D01*
G01X475332Y223167D02*
G02X475307Y220884I-2040J-1119D01*
G01Y223209D02*
X475332Y223167D01*
G01X475288Y223243D02*
X475307Y223209D01*
G01Y224784D02*
G03X475288Y223243I1365J-787D01*
G01X475332Y227067D02*
G02X475307Y224784I-2040J-1119D01*
G01Y227109D02*
X475332Y227067D01*
G01X475288Y227143D02*
X475307Y227109D01*
G01Y228684D02*
G03X475288Y227143I1365J-787D01*
G01X475307Y231010D02*
G02Y228684I-2015J-1163D01*
G01Y232584D02*
G03Y231010I1365J-787D01*
G01X475332Y232626D02*
X475307Y232584D01*
G01Y234909D02*
G02X475332Y232626I-2015J-1164D01*
G01X475288Y234943D02*
X475307Y234909D01*
G01Y236484D02*
G03X475288Y234943I1365J-787D01*
G01X475332Y238767D02*
G02X475307Y236484I-2040J-1119D01*
G01Y238809D02*
X475332Y238767D01*
G01X475288Y238843D02*
X475307Y238809D01*
G01Y240384D02*
G03X475288Y238843I1365J-787D01*
G01X475307Y242710D02*
G02Y240384I-2017J-1163D01*
G01Y244284D02*
G03Y242710I1365J-787D01*
G01X477246Y245930D02*
G03X475307Y244284I1328J-3530D01*
G01X477922Y248356D02*
G02X477246Y245930I-1250J-959D01*
G01X476068Y249842D02*
G02X477922Y248356I-1636J-3940D01*
G01X475307Y252084D02*
G03X476068Y249842I1365J-787D01*
G01X475598Y252749D02*
X475307Y252084D01*
G01X476672Y255196D02*
X475598Y252749D01*
G01X454378Y218934D02*
X454397Y218900D01*
G01X454353Y218976D02*
X454378Y218934D01*
G01Y221259D02*
G03X454353Y218976I2015J-1164D01*
G01X454397Y222800D02*
G02X454378Y221259I-1384J-754D01*
G01Y222834D02*
X454397Y222800D01*
G01X454353Y222876D02*
X454378Y222834D01*
G01Y225159D02*
G03X454353Y222876I2015J-1164D01*
G01X454397Y226700D02*
G02X454378Y225159I-1384J-754D01*
G01Y226734D02*
X454397Y226700D01*
G01X454353Y226776D02*
X454378Y226734D01*
G01Y229059D02*
G03X454353Y226776I2015J-1164D01*
G01X454397Y230600D02*
G02X454378Y229059I-1384J-754D01*
G01Y230634D02*
X454397Y230600D01*
G01X454353Y232917D02*
G03X454378Y230634I2040J-1119D01*
G01Y232959D02*
X454353Y232917D01*
G01X454378Y234533D02*
G02Y232959I-1365J-787D01*
G01Y236859D02*
G03Y234533I2015J-1163D01*
G01X454397Y238400D02*
G02X454378Y236859I-1384J-754D01*
G01Y238434D02*
X454397Y238400D01*
G01X454353Y238476D02*
X454378Y238434D01*
G01Y240759D02*
G03X454353Y238476I2015J-1164D01*
G01X454397Y242300D02*
G02X454378Y240759I-1384J-754D01*
G01Y242334D02*
X454397Y242300D01*
G01X454353Y242376D02*
X454378Y242334D01*
G01Y244659D02*
G03X454353Y242376I2015J-1164D01*
G01X454444Y244775D02*
X454378Y244659D01*
G01X456393Y247396D02*
X454444Y244775D01*
G01X460630Y277370D02*
Y278470D01*
G01X469000Y269000D02*
X460630Y277370D01*
G01X470600Y269000D02*
X469000D01*
G01X471300Y269700D02*
X470600Y269000D01*
G01X471926Y269700D02*
X471300D01*
G01X472642Y270416D02*
X471926Y269700D01*
G01X473942Y270416D02*
X472642D01*
G01X475458Y268900D02*
X473942Y270416D01*
G01X477200Y268900D02*
X475458D01*
G01X479500Y266600D02*
X477200Y268900D01*
G01X464518Y219306D02*
G03X464493Y219267I272J-202D01*
G01X464518Y220882D02*
G02Y219306I-1365J-788D01*
G01Y223208D02*
G03Y220882I2015J-1163D01*
G01Y224784D02*
G02Y223208I-1365J-788D01*
G01Y227110D02*
G03Y224784I2015J-1163D01*
G01X464537Y228651D02*
G02X464518Y227110I-1384J-754D01*
G01Y228685D02*
X464537Y228651D01*
G01X464493Y228727D02*
X464518Y228685D01*
G01Y231010D02*
G03X464493Y228727I2015J-1164D01*
G01X464537Y232551D02*
G02X464518Y231010I-1384J-754D01*
G01Y232585D02*
X464537Y232551D01*
G01X464493Y232627D02*
X464518Y232585D01*
G01Y234910D02*
G03X464493Y232627I2015J-1164D01*
G01X464537Y236451D02*
G02X464518Y234910I-1384J-754D01*
G01Y236485D02*
X464537Y236451D01*
G01X464493Y236527D02*
X464518Y236485D01*
G01Y238810D02*
G03X464493Y236527I2015J-1164D01*
G01X464537Y240351D02*
G02X464518Y238810I-1384J-754D01*
G01Y240385D02*
X464537Y240351D01*
G01X464493Y240427D02*
X464518Y240385D01*
G01Y242710D02*
G03X464493Y240427I2018J-1164D01*
G01X464518Y244284D02*
G02Y242710I-1365J-787D01*
G01X464401Y246380D02*
G03X464518Y244284I2132J-932D01*
G01X464307Y246731D02*
X464401Y246380D01*
G01X463153Y247396D02*
X464307Y246731D01*
G01X434748Y219309D02*
X434773Y219267D01*
G01X434731Y219339D02*
X434748Y219309D01*
G01X434729Y219343D02*
X434731Y219339D01*
G01X434748Y220884D02*
G03X434729Y219343I1365J-787D01*
G01X434773Y223167D02*
G02X434748Y220884I-2040J-1119D01*
G01Y223209D02*
X434773Y223167D01*
G01X434729Y223243D02*
X434748Y223209D01*
G01Y224784D02*
G03X434729Y223243I1365J-787D01*
G01X434773Y227067D02*
G02X434748Y224784I-2040J-1119D01*
G01Y227109D02*
X434773Y227067D01*
G01X434729Y227143D02*
X434748Y227109D01*
G01Y228683D02*
G03X434729Y227143I1363J-787D01*
G01X434748Y231009D02*
G02Y228683I-2015J-1163D01*
G01Y232583D02*
G03Y231009I1365J-787D01*
G01Y234909D02*
G02Y232583I-2015J-1163D01*
G01X434285Y237376D02*
G03X434748Y234909I3741J-575D01*
G01X434098Y238433D02*
G02X434285Y237376I-1365J-787D01*
G01X432733Y241547D02*
X434098Y238433D01*
G01X476506Y247220D02*
X476672Y247396D01*
G01X474673Y244688D02*
G02X476506Y247220I13166J-7602D01*
G01X474657Y244660D02*
X474673Y244688D01*
G01X474657Y242334D02*
G02Y244660I2015J1163D01*
G01Y240759D02*
G03Y242334I-1364J787D01*
G01X474632Y238476D02*
G02X474657Y240759I2040J1119D01*
G01Y238434D02*
X474632Y238476D01*
G01X474676Y238400D02*
X474657Y238434D01*
G01Y236859D02*
G03X474676Y238400I-1365J787D01*
G01X474657Y234533D02*
G02Y236859I2015J1163D01*
G01Y232959D02*
G03Y234533I-1365J787D01*
G01X474632Y232917D02*
X474657Y232959D01*
G01Y230634D02*
G02X474632Y232917I2015J1164D01*
G01X474676Y230600D02*
X474657Y230634D01*
G01Y229059D02*
G03X474676Y230600I-1365J787D01*
G01X474632Y226776D02*
G02X474657Y229059I2040J1119D01*
G01Y226734D02*
X474632Y226776D01*
G01X474676Y226700D02*
X474657Y226734D01*
G01Y225159D02*
G03X474676Y226700I-1365J787D01*
G01X474632Y222876D02*
G02X474657Y225159I2040J1119D01*
G01Y222834D02*
X474632Y222876D01*
G01X474676Y222800D02*
X474657Y222834D01*
G01Y221259D02*
G03X474676Y222800I-1365J787D01*
G01X474632Y218976D02*
G02X474657Y221259I2040J1119D01*
G01Y218934D02*
X474632Y218976D01*
G01X474676Y218900D02*
X474657Y218934D01*
G01X471963Y218994D02*
X471928Y218934D01*
G01Y221260D02*
G02X471963Y218994I-2015J-1164D01*
G01X471928Y222834D02*
G03Y221260I1364J-787D01*
G01X471963Y222894D02*
X471928Y222834D01*
G01Y225160D02*
G02X471963Y222894I-2015J-1164D01*
G01X471928Y226734D02*
G03Y225160I1364J-787D01*
G01X471963Y226794D02*
X471928Y226734D01*
G01Y229060D02*
G02X471963Y226794I-2015J-1164D01*
G01X471928Y230634D02*
G03Y229060I1364J-787D01*
G01X471953Y232917D02*
G02X471928Y230634I-2040J-1119D01*
G01Y232959D02*
X471953Y232917D01*
G01X471928Y234533D02*
G03Y232959I1364J-787D01*
G01X471953Y234575D02*
X471928Y234533D01*
G01Y236860D02*
G02X471953Y234575I-2015J-1165D01*
G01X471928Y238434D02*
G03Y236860I1364J-787D01*
G01X471963Y238494D02*
X471928Y238434D01*
G01Y240760D02*
G02X471963Y238494I-2015J-1164D01*
G01X471928Y242334D02*
G03Y240760I1364J-787D01*
G01Y244660D02*
G02Y242334I-2015J-1163D01*
G01Y246234D02*
G03Y244660I1364J-787D01*
G01X471941Y246257D02*
X471928Y246234D01*
G01X472757Y247116D02*
G03X471941Y246257I1306J-2058D01*
G01X474142Y247995D02*
X472757Y247116D01*
G01X474230Y248081D02*
X474142Y247995D01*
G01X474403Y250465D02*
G02X474230Y248081I-1111J-1118D01*
G01X473950Y251600D02*
X474403Y250465D01*
G01X473292Y253247D02*
X473950Y251600D01*
G01X423959Y219309D02*
X423934Y219267D01*
G01X423978Y219343D02*
X423959Y219309D01*
G01Y220884D02*
G02X423978Y219343I-1365J-787D01*
G01X423934Y223167D02*
G03X423959Y220884I2040J-1119D01*
G01Y223209D02*
X423934Y223167D01*
G01X423978Y223243D02*
X423959Y223209D01*
G01Y224784D02*
G02X423978Y223243I-1365J-787D01*
G01X423934Y227067D02*
G03X423959Y224784I2040J-1119D01*
G01Y227109D02*
X423934Y227067D01*
G01X423978Y227143D02*
X423959Y227109D01*
G01X423958Y228683D02*
G02X423978Y227143I-1365J-788D01*
G01X423958Y231009D02*
G03Y228683I2015J-1163D01*
G01X423974Y231037D02*
X423958Y231009D01*
G01X425807Y233569D02*
G03X423974Y231037I11333J-10134D01*
G01X425974Y233746D02*
X425807Y233569D01*
G01X455028Y219309D02*
X455053Y219267D01*
G01X455009Y219343D02*
X455028Y219309D01*
G01Y220884D02*
G03X455009Y219343I1365J-787D01*
G01X455053Y223167D02*
G02X455028Y220884I-2040J-1119D01*
G01Y223209D02*
X455053Y223167D01*
G01X455009Y223243D02*
X455028Y223209D01*
G01Y224784D02*
G03X455009Y223243I1365J-787D01*
G01X455053Y227067D02*
G02X455028Y224784I-2040J-1119D01*
G01Y227109D02*
X455053Y227067D01*
G01X455009Y227143D02*
X455028Y227109D01*
G01Y228684D02*
G03X455009Y227143I1365J-787D01*
G01X455028Y231010D02*
G02Y228684I-2015J-1163D01*
G01Y232584D02*
G03Y231010I1365J-787D01*
G01X455053Y232626D02*
X455028Y232584D01*
G01Y234909D02*
G02X455053Y232626I-2015J-1164D01*
G01X455009Y234943D02*
X455028Y234909D01*
G01Y236484D02*
G03X455009Y234943I1365J-787D01*
G01X455053Y238767D02*
G02X455028Y236484I-2040J-1119D01*
G01Y238809D02*
X455053Y238767D01*
G01X455009Y238843D02*
X455028Y238809D01*
G01Y240384D02*
G03X455009Y238843I1365J-787D01*
G01X455053Y242667D02*
G02X455028Y240384I-2040J-1119D01*
G01Y242709D02*
X455053Y242667D01*
G01X455009Y242743D02*
X455028Y242709D01*
G01X455754Y244937D02*
G03X455009Y242743I639J-1441D01*
G01X456818Y245640D02*
X455754Y244937D01*
G01X457596Y246328D02*
X456818Y245640D01*
G01X457777Y246643D02*
X457596Y246328D01*
G01X457758Y248184D02*
G02X457777Y246643I-1365J-787D01*
G01X457635Y248397D02*
X457758Y248184D01*
G01X457212Y248819D02*
X457635Y248397D01*
G01X455663Y249899D02*
X457212Y248819D01*
G01X455028Y250509D02*
G03X455663Y249899I1366J786D01*
G01X455009Y250543D02*
X455028Y250509D01*
G01Y252084D02*
G03X455009Y250543I1365J-787D01*
G01X455094Y252197D02*
X455028Y252084D01*
G01X456393Y255196D02*
X455094Y252197D01*
G01X434098Y218934D02*
X434117Y218900D01*
G01X434073Y218976D02*
X434098Y218934D01*
G01Y221259D02*
G03X434073Y218976I2015J-1164D01*
G01X434117Y222800D02*
G02X434098Y221259I-1384J-754D01*
G01Y222834D02*
X434117Y222800D01*
G01X434073Y222876D02*
X434098Y222834D01*
G01Y225159D02*
G03X434073Y222876I2015J-1164D01*
G01X434117Y226700D02*
G02X434098Y225159I-1384J-754D01*
G01Y226734D02*
X434117Y226700D01*
G01X434073Y226776D02*
X434098Y226734D01*
G01Y229059D02*
G03X434073Y226776I2018J-1164D01*
G01X434098Y230633D02*
G02Y229059I-1365J-787D01*
G01Y230634D02*
Y230633D01*
G01X433981Y232730D02*
G03X434098Y230634I2132J-932D01*
G01X433887Y233081D02*
X433981Y232730D01*
G01X432733Y233746D02*
X433887Y233081D01*
G01X454378Y248559D02*
X454166Y248192D01*
G01X454397Y250100D02*
G02X454378Y248559I-1384J-754D01*
G01X454310Y250251D02*
X454397Y250100D01*
G01X454245Y250400D02*
X454310Y250251D01*
G01X453726Y251600D02*
X454245Y250400D01*
G01X453013Y253247D02*
X453726Y251600D01*
G01X451648Y218934D02*
X451629Y218900D01*
G01X451673Y218976D02*
X451648Y218934D01*
G01Y221259D02*
G02X451673Y218976I-2015J-1164D01*
G01X451629Y222800D02*
G03X451648Y221259I1384J-754D01*
G01Y222834D02*
X451629Y222800D01*
G01X451673Y222876D02*
X451648Y222834D01*
G01Y225159D02*
G02X451673Y222876I-2015J-1164D01*
G01X451629Y226700D02*
G03X451648Y225159I1384J-754D01*
G01Y226734D02*
X451629Y226700D01*
G01X451673Y226776D02*
X451648Y226734D01*
G01Y229059D02*
G02X451673Y226776I-2015J-1164D01*
G01X451629Y230600D02*
G03X451648Y229059I1384J-754D01*
G01Y230634D02*
X451629Y230600D01*
G01X451673Y232917D02*
G02X451648Y230634I-2040J-1119D01*
G01Y232959D02*
X451673Y232917D01*
G01X451648Y234533D02*
G03Y232959I1365J-787D01*
G01Y236859D02*
G02Y234533I-2015J-1163D01*
G01X451629Y238400D02*
G03X451648Y236859I1384J-754D01*
G01Y238434D02*
X451629Y238400D01*
G01X451673Y238476D02*
X451648Y238434D01*
G01Y240759D02*
G02X451673Y238476I-2015J-1164D01*
G01X451629Y242300D02*
G03X451648Y240759I1384J-754D01*
G01Y242334D02*
X451629Y242300D01*
G01X451673Y242376D02*
X451648Y242334D01*
G01Y244659D02*
G02X451673Y242376I-2015J-1164D01*
G01X452415Y246905D02*
G03X451648Y244659I598J-1458D01*
G01X454166Y248192D02*
X452415Y246905D01*
G01X421453Y234471D02*
X422594Y235696D01*
G01X421405Y234406D02*
G02X421453Y234471I304J-174D01*
G01X420578Y232959D02*
X421405Y234406D01*
G01X420578Y230633D02*
G02Y232959I2015J1163D01*
G01Y229059D02*
G03Y230633I-1364J787D01*
G01X420554Y226776D02*
G02X420578Y229059I2039J1120D01*
G01X420579Y226734D02*
X420554Y226776D01*
G01X420598Y226700D02*
X420579Y226734D01*
G01Y225159D02*
G03X420598Y226700I-1365J787D01*
G01X420554Y222876D02*
G02X420579Y225159I2040J1119D01*
G01Y222834D02*
X420554Y222876D01*
G01X420598Y222800D02*
X420579Y222834D01*
G01Y221259D02*
G03X420598Y222800I-1365J787D01*
G01X420554Y218976D02*
G02X420579Y221259I2040J1119D01*
G01Y218934D02*
X420554Y218976D01*
G01X420598Y218900D02*
X420579Y218934D01*
G01X464518Y252084D02*
G02X464705Y251027I-1365J-787D01*
G01X463153Y255196D02*
X464518Y252084D01*
G01X465168Y218931D02*
G02X465149Y218900I-597J344D01*
G01X465168Y221257D02*
G02Y218931I-2015J-1163D01*
G01Y222833D02*
G03Y221257I1365J-788D01*
G01Y225159D02*
G02Y222833I-2015J-1163D01*
G01Y226735D02*
G03Y225159I1365J-788D01*
G01X465193Y229018D02*
G02X465168Y226735I-2040J-1119D01*
G01Y229060D02*
X465193Y229018D01*
G01X465149Y229094D02*
X465168Y229060D01*
G01Y230635D02*
G03X465149Y229094I1365J-787D01*
G01X465193Y232918D02*
G02X465168Y230635I-2040J-1119D01*
G01Y232960D02*
X465193Y232918D01*
G01X465149Y232994D02*
X465168Y232960D01*
G01Y234535D02*
G03X465149Y232994I1365J-787D01*
G01X465193Y236818D02*
G02X465168Y234535I-2040J-1119D01*
G01Y236860D02*
X465193Y236818D01*
G01X465149Y236894D02*
X465168Y236860D01*
G01Y238435D02*
G03X465149Y236894I1365J-787D01*
G01X465193Y240718D02*
G02X465168Y238435I-2040J-1119D01*
G01Y240760D02*
X465193Y240718D01*
G01X465149Y240794D02*
X465168Y240760D01*
G01Y242334D02*
G03X465149Y240794I1363J-787D01*
G01X465168Y244660D02*
G02Y242334I-2015J-1163D01*
G01Y246234D02*
G03Y244660I1365J-787D01*
G01Y248560D02*
G02Y246234I-2015J-1163D01*
G01X464705Y251027D02*
G03X465168Y248560I3741J-575D01*
G01X438128Y218934D02*
X438109Y218900D01*
G01X438153Y218976D02*
X438128Y218934D01*
G01Y221259D02*
G02X438153Y218976I-2015J-1164D01*
G01X438109Y222800D02*
G03X438128Y221259I1384J-754D01*
G01Y222834D02*
X438109Y222800D01*
G01X438153Y222876D02*
X438128Y222834D01*
G01Y225159D02*
G02X438153Y222876I-2015J-1164D01*
G01X438109Y226700D02*
G03X438128Y225159I1384J-754D01*
G01Y226734D02*
X438109Y226700D01*
G01X438153Y226776D02*
X438128Y226734D01*
G01Y229059D02*
G02X438153Y226776I-2015J-1164D01*
G01X438109Y230600D02*
G03X438128Y229059I1384J-754D01*
G01Y230634D02*
X438109Y230600D01*
G01X438153Y232917D02*
G02X438128Y230634I-2040J-1119D01*
G01Y232959D02*
X438153Y232917D01*
G01X438128Y234533D02*
G03Y232959I1365J-787D01*
G01Y236859D02*
G02Y234533I-2015J-1163D01*
G01X438062Y236975D02*
X438128Y236859D01*
G01X436113Y239596D02*
X438062Y236975D01*
G01X471277Y219309D02*
X471242Y219249D01*
G01X471277Y220883D02*
G02Y219309I-1364J-787D01*
G01X471242Y223149D02*
G03X471277Y220883I2050J-1102D01*
G01Y223209D02*
X471242Y223149D01*
G01X471277Y224783D02*
G02Y223209I-1364J-787D01*
G01X471242Y227049D02*
G03X471277Y224783I2050J-1102D01*
G01Y227109D02*
X471242Y227049D01*
G01X471277Y228683D02*
G02Y227109I-1364J-787D01*
G01X471252Y230968D02*
G03X471277Y228683I2040J-1120D01*
G01Y231010D02*
X471252Y230968D01*
G01X471277Y232584D02*
G02Y231010I-1364J-787D01*
G01X471252Y232626D02*
X471277Y232584D01*
G01Y234909D02*
G03X471252Y232626I2015J-1164D01*
G01X471277Y236483D02*
G02Y234909I-1364J-787D01*
G01X471242Y238749D02*
G03X471277Y236483I2050J-1102D01*
G01Y238809D02*
X471242Y238749D01*
G01X471277Y240383D02*
G02Y238809I-1364J-787D01*
G01Y242710D02*
G03Y240383I2017J-1163D01*
G01Y244284D02*
G02Y242710I-1364J-787D01*
G01Y246610D02*
G03Y244284I2015J-1163D01*
G01X471293Y246638D02*
X471277Y246610D01*
G01X473061Y249098D02*
G03X471293Y246638I11400J-10059D01*
G01X473292Y249347D02*
X473061Y249098D01*
G01X467898Y218934D02*
X467917Y218900D01*
G01X467873Y218976D02*
X467898Y218934D01*
G01Y221259D02*
G03X467873Y218976I2015J-1164D01*
G01X467917Y222800D02*
G02X467898Y221259I-1384J-754D01*
G01Y222834D02*
X467917Y222800D01*
G01X467873Y222876D02*
X467898Y222834D01*
G01Y225159D02*
G03X467873Y222876I2015J-1164D01*
G01X467917Y226700D02*
G02X467898Y225159I-1384J-754D01*
G01Y226734D02*
X467917Y226700D01*
G01X467873Y226776D02*
X467898Y226734D01*
G01Y229059D02*
G03X467873Y226776I2015J-1164D01*
G01X467917Y230600D02*
G02X467898Y229059I-1384J-754D01*
G01Y230634D02*
X467917Y230600D01*
G01X467873Y232917D02*
G03X467898Y230634I2040J-1119D01*
G01Y232959D02*
X467873Y232917D01*
G01X467898Y234533D02*
G02Y232959I-1365J-787D01*
G01Y236859D02*
G03Y234533I2015J-1163D01*
G01X467917Y238400D02*
G02X467898Y236859I-1384J-754D01*
G01Y238434D02*
X467917Y238400D01*
G01X467873Y238476D02*
X467898Y238434D01*
G01Y240759D02*
G03X467873Y238476I2015J-1164D01*
G01X467917Y242300D02*
G02X467898Y240759I-1384J-754D01*
G01Y242334D02*
X467917Y242300D01*
G01X467873Y242376D02*
X467898Y242334D01*
G01Y244659D02*
G03X467873Y242376I2015J-1164D01*
G01X467917Y246200D02*
G02X467898Y244659I-1384J-754D01*
G01Y246234D02*
G02X467917Y246200I-613J-365D01*
G01X467873Y246276D02*
X467898Y246234D01*
G01X467781Y248329D02*
G03X467873Y246276I2131J-933D01*
G01X467687Y248681D02*
X467781Y248329D01*
G01X466533Y249347D02*
X467687Y248681D01*
G01X424609Y218934D02*
X424590Y218900D01*
G01X424634Y218976D02*
X424609Y218934D01*
G01Y221259D02*
G02X424634Y218976I-2015J-1164D01*
G01X424590Y222800D02*
G03X424609Y221259I1384J-754D01*
G01Y222834D02*
X424590Y222800D01*
G01X424634Y222876D02*
X424609Y222834D01*
G01Y225159D02*
G02X424634Y222876I-2015J-1164D01*
G01X424590Y226700D02*
G03X424609Y225159I1384J-754D01*
G01Y226734D02*
X424590Y226700D01*
G01X424634Y226776D02*
X424609Y226734D01*
G01X424608Y229059D02*
G02X424634Y226776I-2020J-1165D01*
G01X424608Y230633D02*
G03Y229059I1365J-787D01*
G01X426547Y232279D02*
G03X424608Y230633I1328J-3530D01*
G01X427223Y234705D02*
G02X426547Y232279I-1250J-959D01*
G01X425369Y236191D02*
G02X427223Y234705I-1636J-3940D01*
G01X424608Y238433D02*
G03X425369Y236191I1365J-787D01*
G01X425974Y241547D02*
X424608Y238433D01*
G01X468548Y219309D02*
X468573Y219267D01*
G01X468529Y219343D02*
X468548Y219309D01*
G01Y220884D02*
G03X468529Y219343I1365J-787D01*
G01X468573Y223167D02*
G02X468548Y220884I-2040J-1119D01*
G01Y223209D02*
X468573Y223167D01*
G01X468529Y223243D02*
X468548Y223209D01*
G01Y224784D02*
G03X468529Y223243I1365J-787D01*
G01X468573Y227067D02*
G02X468548Y224784I-2040J-1119D01*
G01Y227109D02*
X468573Y227067D01*
G01X468529Y227143D02*
X468548Y227109D01*
G01Y228684D02*
G03X468529Y227143I1365J-787D01*
G01X468548Y231010D02*
G02Y228684I-2015J-1163D01*
G01Y232584D02*
G03Y231010I1365J-787D01*
G01X468573Y232626D02*
X468548Y232584D01*
G01Y234909D02*
G02X468573Y232626I-2015J-1164D01*
G01X468529Y234943D02*
X468548Y234909D01*
G01Y236484D02*
G03X468529Y234943I1365J-787D01*
G01X468573Y238767D02*
G02X468548Y236484I-2040J-1119D01*
G01Y238809D02*
X468573Y238767D01*
G01X468529Y238843D02*
X468548Y238809D01*
G01Y240384D02*
G03X468529Y238843I1365J-787D01*
G01X468573Y242667D02*
G02X468548Y240384I-2040J-1119D01*
G01Y242709D02*
X468573Y242667D01*
G01X468529Y242743D02*
X468548Y242709D01*
G01Y244284D02*
G03X468529Y242743I1365J-787D01*
G01X468573Y246567D02*
G02X468548Y244284I-2040J-1119D01*
G01Y246609D02*
X468573Y246567D01*
G01X468529Y246643D02*
X468548Y246609D01*
G01Y248184D02*
G03X468529Y246643I1365J-787D01*
G01X468426Y250700D02*
G02X468548Y248184I-1893J-1353D01*
G01X467431Y252039D02*
X468426Y250700D01*
G01X466533Y253247D02*
X467431Y252039D01*
G01X423893Y236597D02*
X422594Y239596D01*
G01X423959Y236484D02*
X423893Y236597D01*
G01X423041Y234185D02*
G03X423959Y236484I-447J1511D01*
G01X421392Y232866D02*
X423041Y234185D01*
G01X421229Y232583D02*
X421392Y232866D01*
G01X421229Y231009D02*
G02Y232583I1364J787D01*
G01Y228683D02*
G03Y231009I-2015J1163D01*
G01X421210Y227143D02*
G02X421229Y228683I1382J753D01*
G01Y227109D02*
X421210Y227143D01*
G01X421254Y227067D02*
X421229Y227109D01*
G01Y224784D02*
G03X421254Y227067I-2015J1164D01*
G01X421210Y223243D02*
G02X421229Y224784I1384J754D01*
G01Y223209D02*
X421210Y223243D01*
G01X421254Y223167D02*
X421229Y223209D01*
G01Y220884D02*
G03X421254Y223167I-2015J1164D01*
G01X421210Y219343D02*
G02X421229Y220884I1384J754D01*
G01Y219309D02*
X421210Y219343D01*
G01X421254Y219267D02*
X421229Y219309D01*
G01X437411Y232699D02*
X436113Y235696D01*
G01X437478Y232584D02*
X437411Y232699D01*
G01X437478Y231010D02*
G03Y232584I-1365J787D01*
G01Y228684D02*
G02Y231010I2015J1163D01*
G01X437497Y227143D02*
G03X437478Y228684I-1384J754D01*
G01Y227109D02*
X437497Y227143D01*
G01X437453Y227067D02*
X437478Y227109D01*
G01Y224784D02*
G02X437453Y227067I2015J1164D01*
G01X437497Y223243D02*
G03X437478Y224784I-1384J754D01*
G01Y223209D02*
X437497Y223243D01*
G01X437453Y223167D02*
X437478Y223209D01*
G01Y220884D02*
G02X437453Y223167I2015J1164D01*
G01X437497Y219343D02*
G03X437478Y220884I-1384J754D01*
G01Y219309D02*
X437497Y219343D01*
G01X437453Y219267D02*
X437478Y219309D01*
G01X450998D02*
X450973Y219267D01*
G01X451017Y219343D02*
X450998Y219309D01*
G01Y220884D02*
G02X451017Y219343I-1365J-787D01*
G01X450973Y223167D02*
G03X450998Y220884I2040J-1119D01*
G01Y223209D02*
X450973Y223167D01*
G01X451017Y223243D02*
X450998Y223209D01*
G01Y224784D02*
G02X451017Y223243I-1365J-787D01*
G01X450973Y227067D02*
G03X450998Y224784I2040J-1119D01*
G01Y227109D02*
X450973Y227067D01*
G01X451017Y227143D02*
X450998Y227109D01*
G01Y228684D02*
G02X451017Y227143I-1365J-787D01*
G01X450998Y231010D02*
G03Y228684I2015J-1163D01*
G01Y232584D02*
G02Y231010I-1365J-787D01*
G01X450973Y232626D02*
X450998Y232584D01*
G01Y234909D02*
G03X450973Y232626I2015J-1164D01*
G01X451017Y234943D02*
X450998Y234909D01*
G01Y236484D02*
G02X451017Y234943I-1365J-787D01*
G01X450973Y238767D02*
G03X450998Y236484I2040J-1119D01*
G01Y238809D02*
X450973Y238767D01*
G01X451017Y238843D02*
X450998Y238809D01*
G01Y240384D02*
G02X451017Y238843I-1365J-787D01*
G01X450973Y242667D02*
G03X450998Y240384I2040J-1119D01*
G01Y242709D02*
X450973Y242667D01*
G01X451017Y242743D02*
X450998Y242709D01*
G01Y244284D02*
G02X451017Y242743I-1365J-787D01*
G01X450973Y246567D02*
G03X450998Y244284I2040J-1119D01*
G01Y246609D02*
X450973Y246567D01*
G01X451406Y247128D02*
G03X450998Y246609I1606J-1682D01*
G01X453013Y249347D02*
X451406Y247128D01*
G01X475087Y335500D02*
X472800D01*
G01X476000Y336413D02*
X475087Y335500D01*
G01X476000Y339100D02*
Y336413D01*
G01X476441Y339857D02*
X476000Y339100D01*
G01X477792Y340622D02*
G03X476441Y339857I0J-1575D01*
G01X477877Y340622D02*
X477792D01*
G01X479807Y341784D02*
G02X477877Y340622I-2015J1163D01*
G01X475777Y340209D02*
G02X477722Y341372I2015J-1162D01*
G01X475764Y340186D02*
X475777Y340209D01*
G01X474413Y339421D02*
G03X475764Y340186I0J1575D01*
G01X474328Y339421D02*
X474413D01*
G01X472539Y338476D02*
G02X474328Y339421I1873J-1380D01*
G01X472100Y337800D02*
X472539Y338476D01*
G01X477836Y286022D02*
G02X479157Y285234I-44J-1575D01*
G01X473129Y286022D02*
X477836D01*
G01X471748Y284641D02*
X473129Y286022D01*
G01X466359Y284641D02*
X471748D01*
G01X463900Y287100D02*
X466359Y284641D01*
G01X463900Y289400D02*
Y287100D01*
G01X463800Y289500D02*
X463900Y289400D01*
G01X452537Y358743D02*
X454133Y356596D01*
G01X452418Y360681D02*
G03X452537Y358743I2468J-821D01*
G01X454634Y362902D02*
G03X452418Y360681I1117J-3330D01*
G01X455498Y365184D02*
G02X454634Y362902I-1365J-788D01*
G01X455473Y367467D02*
G03X455498Y365184I2040J-1119D01*
G01Y367509D02*
X455473Y367467D01*
G01X455517Y367543D02*
X455498Y367509D01*
G01Y369084D02*
G02X455517Y367543I-1365J-787D01*
G01X455498Y371410D02*
G03Y369084I2015J-1163D01*
G01Y372984D02*
G02Y371410I-1365J-787D01*
G01X455473Y373026D02*
X455498Y372984D01*
G01X457462Y376472D02*
G03X455473Y373026I51J-2326D01*
G01X457572Y376472D02*
X457462D01*
G01X458878Y377259D02*
G02X457572Y376472I-1365J788D01*
G01X460808Y378421D02*
G03X458878Y377259I85J-2325D01*
G01X460937Y378421D02*
X460808D01*
G01X462258Y379209D02*
G02X460937Y378421I-1365J787D01*
G01X464203Y380372D02*
G03X462258Y379209I70J-2325D01*
G01X464332Y380372D02*
X464203D01*
G01X465638Y381159D02*
G02X464332Y380372I-1365J788D01*
G01X467568Y382321D02*
G03X465638Y381159I85J-2325D01*
G01X467697Y382321D02*
X467568D01*
G01X469018Y383109D02*
G02X467697Y382321I-1365J787D01*
G01X470963Y384272D02*
G03X469018Y383109I70J-2325D01*
G01X471092Y384272D02*
X470963D01*
G01X472417Y386600D02*
G02X471092Y384272I-1384J-753D01*
G01X472398Y386634D02*
X472417Y386600D01*
G01X472373Y386676D02*
X472398Y386634D01*
G01Y388959D02*
G03X472373Y386676I2015J-1164D01*
G01X472417Y390500D02*
G02X472398Y388959I-1384J-754D01*
G01Y390534D02*
X472417Y390500D01*
G01X472373Y390576D02*
X472398Y390534D01*
G01Y392859D02*
G03X472373Y390576I2015J-1164D01*
G01X472417Y394400D02*
G02X472398Y392859I-1384J-754D01*
G01Y394434D02*
X472417Y394400D01*
G01X472373Y394476D02*
X472398Y394434D01*
G01Y396759D02*
G03X472373Y394476I2015J-1164D01*
G01X472417Y398300D02*
G02X472398Y396759I-1384J-754D01*
G01Y398334D02*
X472417Y398300D01*
G01X472373Y398376D02*
X472398Y398334D01*
G01Y400659D02*
G03X472373Y398376I2015J-1164D01*
G01X472417Y402200D02*
G02X472398Y400659I-1384J-754D01*
G01Y402234D02*
X472417Y402200D01*
G01X472373Y402276D02*
X472398Y402234D01*
G01Y404559D02*
G03X472373Y402276I2015J-1164D01*
G01X456082Y363118D02*
X454133Y360496D01*
G01X456148Y363234D02*
X456082Y363118D01*
G01X456173Y363276D02*
X456148Y363234D01*
G01Y365559D02*
G02X456173Y363276I-2015J-1164D01*
G01X456129Y367100D02*
G03X456148Y365559I1384J-754D01*
G01Y367134D02*
X456129Y367100D01*
G01X456173Y367176D02*
X456148Y367134D01*
G01Y369459D02*
G02X456173Y367176I-2015J-1164D01*
G01X456129Y371000D02*
G03X456148Y369459I1384J-754D01*
G01Y371034D02*
X456129Y371000D01*
G01X456173Y373317D02*
G02X456148Y371034I-2040J-1119D01*
G01Y373359D02*
X456173Y373317D01*
G01X457469Y375721D02*
G03X456148Y373359I44J-1575D01*
G01X457564Y375721D02*
X457469D01*
G01X459528Y376884D02*
G02X457564Y375721I-2015J1163D01*
G01X460834Y377671D02*
G03X459528Y376884I59J-1575D01*
G01X460963Y377671D02*
X460834D01*
G01X462908Y378834D02*
G02X460963Y377671I-2015J1162D01*
G01X464229Y379622D02*
G03X462908Y378834I44J-1575D01*
G01X464358Y379622D02*
X464229D01*
G01X466288Y380784D02*
G02X464358Y379622I-2015J1163D01*
G01X467594Y381571D02*
G03X466288Y380784I59J-1575D01*
G01X467723Y381571D02*
X467594D01*
G01X469668Y382734D02*
G02X467723Y381571I-2015J1162D01*
G01X470989Y383522D02*
G03X469668Y382734I44J-1575D01*
G01X471118Y383522D02*
X470989D01*
G01X473073Y386967D02*
G02X471118Y383522I-2040J-1120D01*
G01X473048Y387009D02*
X473073Y386967D01*
G01X473029Y387043D02*
X473048Y387009D01*
G01Y388584D02*
G03X473029Y387043I1365J-787D01*
G01X473073Y390867D02*
G02X473048Y388584I-2040J-1119D01*
G01Y390909D02*
X473073Y390867D01*
G01X473029Y390943D02*
X473048Y390909D01*
G01Y392484D02*
G03X473029Y390943I1365J-787D01*
G01X473073Y394767D02*
G02X473048Y392484I-2040J-1119D01*
G01Y394809D02*
X473073Y394767D01*
G01X473029Y394843D02*
X473048Y394809D01*
G01Y396384D02*
G03X473029Y394843I1365J-787D01*
G01X473073Y398667D02*
G02X473048Y396384I-2040J-1119D01*
G01Y398709D02*
X473073Y398667D01*
G01X473029Y398743D02*
X473048Y398709D01*
G01Y400284D02*
G03X473029Y398743I1365J-787D01*
G01X473073Y402567D02*
G02X473048Y400284I-2040J-1119D01*
G01Y402609D02*
X473073Y402567D01*
G01X473029Y402643D02*
X473048Y402609D01*
G01Y404184D02*
G03X473029Y402643I1365J-787D01*
G01X477851Y384272D02*
G03X479157Y385062I-64J1580D01*
G01X477722Y384272D02*
X477851D01*
G01X475777Y383109D02*
G02X477722Y384272I2015J-1162D01*
G01X475764Y383086D02*
X475777Y383109D01*
G01X474413Y382321D02*
G03X475764Y383086I0J1575D01*
G01X474328Y382321D02*
X474413D01*
G01X472398Y381159D02*
G02X474328Y382321I2015J-1163D01*
G01X471092Y380372D02*
G03X472398Y381159I-59J1575D01*
G01X470963Y380372D02*
X471092D01*
G01X469018Y379209D02*
G02X470963Y380372I2015J-1162D01*
G01X467697Y378421D02*
G03X469018Y379209I-44J1575D01*
G01X467568Y378421D02*
X467697D01*
G01X465638Y377259D02*
G02X467568Y378421I2015J-1163D01*
G01X464332Y376472D02*
G03X465638Y377259I-59J1575D01*
G01X464222Y376472D02*
X464332D01*
G01X462258Y375309D02*
G02X464222Y376472I2015J-1163D01*
G01X460964Y374522D02*
G03X462258Y375309I-71J1574D01*
G01X460823Y374522D02*
X460964D01*
G01X458878Y371034D02*
G02X460823Y374522I2015J1163D01*
G01X458897Y371000D02*
X458878Y371034D01*
G01Y369459D02*
G03X458897Y371000I-1365J787D01*
G01X458853Y367176D02*
G02X458878Y369459I2040J1119D01*
G01Y367134D02*
X458853Y367176D01*
G01X458897Y367100D02*
X458878Y367134D01*
G01Y365559D02*
G03X458897Y367100I-1365J787D01*
G01X458853Y363276D02*
G02X458878Y365559I2040J1119D01*
G01Y363234D02*
X458853Y363276D01*
G01X458897Y363200D02*
X458878Y363234D01*
G01Y361659D02*
G03X458897Y363200I-1365J787D01*
G01X458853Y359376D02*
G02X458878Y361659I2040J1119D01*
G01Y359334D02*
X458853Y359376D01*
G01X458944Y359218D02*
X458878Y359334D01*
G01X460893Y356596D02*
X458944Y359218D01*
G01X456173Y402276D02*
G03X456148Y404559I-2040J1119D01*
G01Y402234D02*
X456173Y402276D01*
G01X456129Y402200D02*
X456148Y402234D01*
G01Y400659D02*
G02X456129Y402200I1365J787D01*
G01X456173Y398376D02*
G03X456148Y400659I-2040J1119D01*
G01Y398334D02*
X456173Y398376D01*
G01X456129Y398300D02*
X456148Y398334D01*
G01Y396759D02*
G02X456129Y398300I1365J787D01*
G01X454203Y393271D02*
G03X456148Y396759I-70J2325D01*
G01X454074Y393271D02*
X454203D01*
G01X452768Y392484D02*
G02X454074Y393271I1365J-788D01*
G01X450838Y391322D02*
G03X452768Y392484I-85J2325D01*
G01X450709Y391322D02*
X450838D01*
G01X449388Y390534D02*
G02X450709Y391322I1365J-787D01*
G01X447443Y389371D02*
G03X449388Y390534I-70J2325D01*
G01X447314Y389371D02*
X447443D01*
G01X446008Y388584D02*
G02X447314Y389371I1365J-788D01*
G01X444078Y387422D02*
G03X446008Y388584I-85J2325D01*
G01X443949Y387422D02*
X444078D01*
G01X442628Y386634D02*
G02X443949Y387422I1365J-787D01*
G01X440683Y385471D02*
G03X442628Y386634I-70J2325D01*
G01X440554Y385471D02*
X440683D01*
G01X439229Y383143D02*
G02X440554Y385471I1384J753D01*
G01X439248Y383109D02*
X439229Y383143D01*
G01X439273Y383067D02*
X439248Y383109D01*
G01Y380784D02*
G03X439273Y383067I-2015J1164D01*
G01X439229Y379243D02*
G02X439248Y380784I1384J754D01*
G01Y379209D02*
X439229Y379243D01*
G01X439273Y379167D02*
X439248Y379209D01*
G01Y376884D02*
G03X439273Y379167I-2015J1164D01*
G01X439229Y375343D02*
G02X439248Y376884I1384J754D01*
G01Y375309D02*
X439229Y375343D01*
G01X439273Y373026D02*
G03X439248Y375309I-2040J1119D01*
G01Y372984D02*
X439273Y373026D01*
G01X439248Y371410D02*
G02Y372984I1365J787D01*
G01Y369084D02*
G03Y371410I-2015J1163D01*
G01X439229Y367543D02*
G02X439248Y369084I1384J754D01*
G01Y367509D02*
X439229Y367543D01*
G01X439273Y367467D02*
X439248Y367509D01*
G01Y365184D02*
G03X439273Y367467I-2015J1164D01*
G01X439229Y363643D02*
G02X439248Y365184I1384J754D01*
G01X439316Y363492D02*
X439229Y363643D01*
G01X440613Y360496D02*
X439316Y363492D01*
G01X477877Y367922D02*
G03X479807Y369084I-85J2325D01*
G01X477792Y367922D02*
X477877D01*
G01X476441Y367157D02*
G02X477792Y367922I1351J-810D01*
G01X476428Y367134D02*
X476441Y367157D01*
G01X474483Y365971D02*
G03X476428Y367134I-70J2325D01*
G01X474354Y365971D02*
X474483D01*
G01X473048Y365184D02*
G02X474354Y365971I1365J-788D01*
G01X472982Y365068D02*
X473048Y365184D01*
G01X471033Y362447D02*
X472982Y365068D01*
G01X425290Y397548D02*
Y408883D01*
G01X423743Y395973D02*
G03X425290Y397548I-28J1575D01*
G01X423715Y395973D02*
X423743D01*
G01X423701Y395974D02*
X423715Y395973D01*
G01X421699Y392484D02*
G02X423701Y395974I2015J1163D01*
G01X421718Y390943D02*
G03X421699Y392484I-1384J754D01*
G01Y390909D02*
X421718Y390943D01*
G01X421674Y390867D02*
X421699Y390909D01*
G01Y388584D02*
G02X421674Y390867I2015J1164D01*
G01X421718Y387043D02*
G03X421699Y388584I-1384J754D01*
G01Y387009D02*
X421718Y387043D01*
G01X421674Y386967D02*
X421699Y387009D01*
G01Y384684D02*
G02X421674Y386967I2015J1164D01*
G01X421718Y383143D02*
G03X421699Y384684I-1384J754D01*
G01Y383109D02*
X421718Y383143D01*
G01X421674Y383067D02*
X421699Y383109D01*
G01Y380784D02*
G02X421674Y383067I2015J1164D01*
G01X421718Y379243D02*
G03X421699Y380784I-1384J754D01*
G01Y379209D02*
X421718Y379243D01*
G01X421674Y379167D02*
X421699Y379209D01*
G01Y376884D02*
G02X421674Y379167I2015J1164D01*
G01X421718Y375343D02*
G03X421699Y376884I-1384J754D01*
G01Y375309D02*
X421718Y375343D01*
G01X421674Y373026D02*
G02X421699Y375309I2040J1119D01*
G01Y372984D02*
X421674Y373026D01*
G01X421699Y371410D02*
G03Y372984I-1365J787D01*
G01X421582Y369314D02*
G02X421699Y371410I2132J932D01*
G01X423714Y367922D02*
G02X421582Y369314I-4J2322D01*
G01X423758Y367922D02*
X423714D01*
G01X425079Y367134D02*
G03X423758Y367922I-1365J-787D01*
G01X425145Y367018D02*
X425079Y367134D01*
G01X427094Y364396D02*
X425145Y367018D01*
G01X442653Y402274D02*
G03X442628Y404559I-2040J1120D01*
G01Y402232D02*
X442653Y402274D01*
G01X442628Y400658D02*
G02Y402232I1365J787D01*
G01Y398332D02*
G03Y400658I-2015J1163D01*
G01X442609Y396791D02*
G02X442628Y398332I1384J754D01*
G01Y396757D02*
X442609Y396791D01*
G01X442653Y396715D02*
X442628Y396757D01*
G01X440698Y393270D02*
G03X442653Y396715I-85J2325D01*
G01X440532Y393270D02*
X440698D01*
G01X439248Y392484D02*
G02X440532Y393270I1365J-788D01*
G01X437318Y391322D02*
G03X439248Y392484I-85J2325D01*
G01X437233Y391322D02*
X437318D01*
G01X435882Y390557D02*
G02X437233Y391322I1351J-810D01*
G01X435869Y390534D02*
X435882Y390557D01*
G01X433924Y389371D02*
G03X435869Y390534I-70J2325D01*
G01X433795Y389371D02*
X433924D01*
G01X432470Y387043D02*
G02X433795Y389371I1384J753D01*
G01X432489Y387009D02*
X432470Y387043D01*
G01X432514Y386967D02*
X432489Y387009D01*
G01Y384684D02*
G03X432514Y386967I-2015J1164D01*
G01X432470Y383143D02*
G02X432489Y384684I1384J754D01*
G01Y383109D02*
X432470Y383143D01*
G01X432514Y383067D02*
X432489Y383109D01*
G01Y380784D02*
G03X432514Y383067I-2015J1164D01*
G01X432470Y379243D02*
G02X432489Y380784I1384J754D01*
G01Y379209D02*
X432470Y379243D01*
G01X432514Y379167D02*
X432489Y379209D01*
G01Y376884D02*
G03X432514Y379167I-2015J1164D01*
G01X432470Y375343D02*
G02X432489Y376884I1384J754D01*
G01Y375309D02*
G02X432470Y375343I1184J684D01*
G01X432514Y373026D02*
G03X432489Y375309I-2040J1119D01*
G01Y372984D02*
X432514Y373026D01*
G01X432401Y372802D02*
G02X432489Y372984I1093J-416D01*
G01X432296Y372424D02*
G02X432401Y372802I1558J-229D01*
G01X432523Y372197D02*
X432296Y372424D01*
G01X433854Y372197D02*
X432523D01*
G01X458843Y402293D02*
G02X458878Y404559I2050J1102D01*
G01X458905Y402185D02*
X458843Y402293D01*
G01X458878Y400659D02*
G03X458905Y402185I-1365J787D01*
G01X458843Y398393D02*
G02X458878Y400659I2050J1102D01*
G01X458905Y398285D02*
X458843Y398393D01*
G01X458878Y396759D02*
G03X458905Y398285I-1365J787D01*
G01X458843Y394493D02*
G02X458878Y396759I2050J1102D01*
G01X458905Y394385D02*
X458843Y394493D01*
G01X457572Y392072D02*
G03X458905Y394385I-59J1575D01*
G01X457443Y392072D02*
X457572D01*
G01X455498Y390909D02*
G02X457443Y392072I2015J-1162D01*
G01X454177Y390121D02*
G03X455498Y390909I-44J1575D01*
G01X454048Y390121D02*
X454177D01*
G01X452118Y388959D02*
G02X454048Y390121I2015J-1163D01*
G01X450812Y388172D02*
G03X452118Y388959I-59J1575D01*
G01X450683Y388172D02*
X450812D01*
G01X448738Y387009D02*
G02X450683Y388172I2015J-1162D01*
G01X447417Y386221D02*
G03X448738Y387009I-44J1575D01*
G01X447288Y386221D02*
X447417D01*
G01X445358Y385059D02*
G02X447288Y386221I2015J-1163D01*
G01X444052Y384272D02*
G03X445358Y385059I-59J1575D01*
G01X443923Y384272D02*
X444052D01*
G01X441978Y380784D02*
G02X443923Y384272I2015J1163D01*
G01X441997Y379243D02*
G03X441978Y380784I-1384J754D01*
G01Y379209D02*
X441997Y379243D01*
G01X441953Y379167D02*
X441978Y379209D01*
G01Y376884D02*
G02X441953Y379167I2015J1164D01*
G01X441997Y375343D02*
G03X441978Y376884I-1384J754D01*
G01Y375309D02*
X441997Y375343D01*
G01X441953Y373026D02*
G02X441978Y375309I2040J1119D01*
G01Y372984D02*
X441953Y373026D01*
G01X441978Y371410D02*
G03Y372984I-1365J787D01*
G01Y369084D02*
G02Y371410I2015J1163D01*
G01X441997Y367543D02*
G03X441978Y369084I-1384J754D01*
G01Y367509D02*
X441997Y367543D01*
G01X441953Y367467D02*
X441978Y367509D01*
G01Y365184D02*
G02X441953Y367467I2015J1164D01*
G01X441997Y363643D02*
G03X441978Y365184I-1384J754D01*
G01Y363609D02*
X441997Y363643D01*
G01X441953Y363567D02*
X441978Y363609D01*
G01Y361284D02*
G02X441953Y363567I2015J1164D01*
G01X441997Y359743D02*
G03X441978Y361284I-1384J754D01*
G01Y359709D02*
X441997Y359743D01*
G01X441953Y359667D02*
X441978Y359709D01*
G01Y357384D02*
G02X441953Y359667I2015J1164D01*
G01X442044Y357268D02*
X441978Y357384D01*
G01X443993Y354647D02*
X442044Y357268D01*
G01X469037Y402643D02*
G03X469018Y404184I-1384J754D01*
G01Y402609D02*
X469037Y402643D01*
G01X468993Y402567D02*
X469018Y402609D01*
G01Y400284D02*
G02X468993Y402567I2015J1164D01*
G01X469037Y398743D02*
G03X469018Y400284I-1384J754D01*
G01Y398709D02*
X469037Y398743D01*
G01X468993Y398667D02*
X469018Y398709D01*
G01Y396384D02*
G02X468993Y398667I2015J1164D01*
G01X469037Y394843D02*
G03X469018Y396384I-1384J754D01*
G01Y394809D02*
X469037Y394843D01*
G01X468993Y394767D02*
X469018Y394809D01*
G01Y392484D02*
G02X468993Y394767I2015J1164D01*
G01X469037Y390943D02*
G03X469018Y392484I-1384J754D01*
G01Y390909D02*
X469037Y390943D01*
G01X468993Y390867D02*
X469018Y390909D01*
G01Y388584D02*
G02X468993Y390867I2015J1164D01*
G01X467697Y386221D02*
G03X469018Y388584I-44J1575D01*
G01X467568Y386221D02*
X467697D01*
G01X465638Y385059D02*
G02X467568Y386221I2015J-1163D01*
G01X464332Y384272D02*
G03X465638Y385059I-59J1575D01*
G01X464203Y384272D02*
X464332D01*
G01X462258Y383109D02*
G02X464203Y384272I2015J-1162D01*
G01X460937Y382321D02*
G03X462258Y383109I-44J1575D01*
G01X460808Y382321D02*
X460937D01*
G01X458878Y381159D02*
G02X460808Y382321I2015J-1163D01*
G01X457572Y380372D02*
G03X458878Y381159I-59J1575D01*
G01X457443Y380372D02*
X457572D01*
G01X455498Y379209D02*
G02X457443Y380372I2015J-1162D01*
G01X454177Y378421D02*
G03X455498Y379209I-44J1575D01*
G01X454048Y378421D02*
X454177D01*
G01X452118Y374933D02*
G02X454048Y378421I2015J1163D01*
G01X452118Y373359D02*
G03Y374933I-1365J787D01*
G01X452093Y373317D02*
X452118Y373359D01*
G01Y371034D02*
G02X452093Y373317I2015J1164D01*
G01X452137Y371000D02*
X452118Y371034D01*
G01Y369459D02*
G03X452137Y371000I-1365J787D01*
G01X452093Y367176D02*
G02X452118Y369459I2040J1119D01*
G01Y367134D02*
X452093Y367176D01*
G01X452137Y367100D02*
X452118Y367134D01*
G01X451384Y364903D02*
G03X452137Y367100I-631J1444D01*
G01X450418Y364181D02*
G02X451384Y364903I2026J-1703D01*
G01X449890Y363765D02*
G03X450418Y364181I-2096J3203D01*
G01X449388Y361659D02*
G02X449890Y363765I1365J787D01*
G01X449413Y359376D02*
G03X449388Y361659I-2040J1119D01*
G01Y359334D02*
X449413Y359376D01*
G01X449369Y359300D02*
X449388Y359334D01*
G01Y357759D02*
G02X449369Y359300I1365J787D01*
G01X449454Y357646D02*
X449388Y357759D01*
G01X450753Y354647D02*
X449454Y357646D01*
G01X477851Y341372D02*
G03X479157Y342159I-59J1575D01*
G01X477722Y341372D02*
X477851D01*
G01X421372Y398499D02*
Y411038D01*
G01X418530Y395657D02*
X421372Y398499D01*
G01X418530Y393647D02*
Y395657D01*
G01X418319Y392859D02*
G03X418530Y393647I-1363J787D01*
G01X418294Y390576D02*
G02X418319Y392859I2040J1119D01*
G01Y390534D02*
X418294Y390576D01*
G01X418338Y390500D02*
X418319Y390534D01*
G01Y388959D02*
G03X418338Y390500I-1365J787D01*
G01X418294Y386676D02*
G02X418319Y388959I2040J1119D01*
G01Y386634D02*
X418294Y386676D01*
G01X418338Y386600D02*
X418319Y386634D01*
G01Y385059D02*
G03X418338Y386600I-1365J787D01*
G01X418294Y382776D02*
G02X418319Y385059I2040J1119D01*
G01Y382734D02*
X418294Y382776D01*
G01X418338Y382700D02*
X418319Y382734D01*
G01Y381159D02*
G03X418338Y382700I-1365J787D01*
G01X418294Y378876D02*
G02X418319Y381159I2040J1119D01*
G01Y378834D02*
X418294Y378876D01*
G01X418338Y378800D02*
X418319Y378834D01*
G01Y377259D02*
G03X418338Y378800I-1365J787D01*
G01X418319Y374933D02*
G02Y377259I2015J1163D01*
G01Y373359D02*
G03Y374933I-1365J787D01*
G01X418294Y373317D02*
X418319Y373359D01*
G01Y371034D02*
G02X418294Y373317I2015J1164D01*
G01X418319Y369460D02*
G03Y371034I-1365J787D01*
G01X420249Y365972D02*
G02X418319Y369460I85J2325D01*
G01X420378Y365972D02*
X420249D01*
G01X421699Y363610D02*
G03X420378Y365972I-1365J787D01*
G01X423458Y360134D02*
G02X421699Y363610I256J2313D01*
G01X423714Y359878D02*
X423458Y360134D01*
G01X423714Y358547D02*
Y359878D01*
G01X477877Y383522D02*
G03X479807Y384686I-89J2329D01*
G01X477792Y383522D02*
X477877D01*
G01X476441Y382757D02*
G02X477792Y383522I1351J-810D01*
G01X476428Y382734D02*
X476441Y382757D01*
G01X474483Y381571D02*
G03X476428Y382734I-70J2325D01*
G01X474354Y381571D02*
X474483D01*
G01X473048Y380784D02*
G02X474354Y381571I1365J-788D01*
G01X471118Y379622D02*
G03X473048Y380784I-85J2325D01*
G01X470989Y379622D02*
X471118D01*
G01X469668Y378834D02*
G02X470989Y379622I1365J-787D01*
G01X467723Y377671D02*
G03X469668Y378834I-70J2325D01*
G01X467594Y377671D02*
X467723D01*
G01X466288Y376884D02*
G02X467594Y377671I1365J-788D01*
G01X464324Y375721D02*
G03X466288Y376884I-51J2326D01*
G01X464229Y375721D02*
X464324D01*
G01X462908Y374933D02*
G02X464229Y375721I1365J-787D01*
G01X460978Y373771D02*
G03X462908Y374933I-85J2325D01*
G01X460822Y373771D02*
X460978D01*
G01X459528Y371410D02*
G02X460822Y373771I1365J787D01*
G01X459528Y369084D02*
G03Y371410I-2015J1163D01*
G01X459509Y367543D02*
G02X459528Y369084I1384J754D01*
G01Y367509D02*
X459509Y367543D01*
G01X459553Y367467D02*
X459528Y367509D01*
G01Y365184D02*
G03X459553Y367467I-2015J1164D01*
G01X459509Y363643D02*
G02X459528Y365184I1384J754D01*
G01X459596Y363492D02*
X459509Y363643D01*
G01X460893Y360496D02*
X459596Y363492D01*
G01X477851Y364772D02*
G03X479157Y365559I-59J1575D01*
G01X477722Y364772D02*
X477851D01*
G01X475777Y363609D02*
G02X477722Y364772I2015J-1162D01*
G01X475764Y363586D02*
X475777Y363609D01*
G01X474413Y362821D02*
G03X475764Y363586I0J1575D01*
G01X474328Y362821D02*
X474413D01*
G01X472373Y359376D02*
G02X474328Y362821I2040J1120D01*
G01X472398Y359334D02*
X472373Y359376D01*
G01X472464Y359218D02*
X472398Y359334D01*
G01X474413Y356596D02*
X472464Y359218D01*
G01X445974Y402666D02*
G02X446008Y404182I1399J727D01*
G01X446033Y402565D02*
X445974Y402666D01*
G01X446008Y400282D02*
G03X446033Y402565I-2015J1164D01*
G01X445989Y398741D02*
G02X446008Y400282I1384J754D01*
G01Y398707D02*
X445989Y398741D01*
G01X446033Y396424D02*
G03X446008Y398707I-2040J1119D01*
G01Y396382D02*
X446033Y396424D01*
G01X446008Y394808D02*
G02Y396382I1365J787D01*
G01X444091Y391321D02*
G03X446008Y394808I-98J2324D01*
G01X443922Y391321D02*
X444091D01*
G01X442628Y390534D02*
G02X443922Y391321I1365J-787D01*
G01X440683Y389371D02*
G03X442628Y390534I-70J2325D01*
G01X440554Y389371D02*
X440683D01*
G01X439248Y388584D02*
G02X440554Y389371I1365J-788D01*
G01X437318Y387422D02*
G03X439248Y388584I-85J2325D01*
G01X437233Y387422D02*
X437318D01*
G01X435869Y385060D02*
G02X437233Y387422I1364J787D01*
G01X435904Y382794D02*
G03X435869Y385060I-2050J1102D01*
G01Y382734D02*
X435904Y382794D01*
G01X435869Y381160D02*
G02Y382734I1364J787D01*
G01X435904Y378894D02*
G03X435869Y381160I-2050J1102D01*
G01Y378834D02*
X435904Y378894D01*
G01X435869Y377260D02*
G02Y378834I1364J787D01*
G01X435894Y374975D02*
G03X435869Y377260I-2040J1120D01*
G01Y374933D02*
X435894Y374975D01*
G01X435869Y373359D02*
G02Y374933I1364J787D01*
G01X435894Y373317D02*
X435869Y373359D01*
G01Y371034D02*
G03X435894Y373317I-2017J1164D01*
G01X437006Y368689D02*
G02X435869Y371034I227J1558D01*
G01X437233Y368916D02*
X437006Y368689D01*
G01X437233Y370247D02*
Y368916D01*
G01X477851Y380372D02*
G03X479157Y381159I-59J1575D01*
G01X477722Y380372D02*
X477851D01*
G01X475777Y379209D02*
G02X477722Y380372I2015J-1162D01*
G01X475764Y379186D02*
X475777Y379209D01*
G01X474413Y378421D02*
G03X475764Y379186I0J1575D01*
G01X474328Y378421D02*
X474413D01*
G01X472398Y377259D02*
G02X474328Y378421I2015J-1163D01*
G01X471092Y376472D02*
G03X472398Y377259I-59J1575D01*
G01X470982Y376472D02*
X471092D01*
G01X469018Y375309D02*
G02X470982Y376472I2015J-1163D01*
G01X467724Y374522D02*
G03X469018Y375309I-71J1574D01*
G01X467583Y374522D02*
X467724D01*
G01X465638Y373359D02*
G02X467583Y374522I2015J-1162D01*
G01X464344Y372572D02*
G03X465638Y373359I-71J1574D01*
G01X464188Y372572D02*
X464344D01*
G01X462258Y369084D02*
G02X464188Y372572I2015J1163D01*
G01X462277Y367543D02*
G03X462258Y369084I-1384J754D01*
G01Y367509D02*
X462277Y367543D01*
G01X462233Y367467D02*
X462258Y367509D01*
G01Y365184D02*
G02X462233Y367467I2015J1164D01*
G01X462277Y363643D02*
G03X462258Y365184I-1384J754D01*
G01Y363609D02*
X462277Y363643D01*
G01X462233Y363567D02*
X462258Y363609D01*
G01Y361284D02*
G02X462233Y363567I2015J1164D01*
G01X462277Y359743D02*
G03X462258Y361284I-1384J754D01*
G01Y359709D02*
X462277Y359743D01*
G01X462233Y359667D02*
X462258Y359709D01*
G01Y357384D02*
G02X462233Y359667I2015J1164D01*
G01X462324Y357268D02*
X462258Y357384D01*
G01X462415Y357146D02*
X462324Y357268D01*
G01X464273Y354647D02*
X462415Y357146D01*
G01X477877Y379622D02*
G03X479807Y380784I-85J2325D01*
G01X477792Y379622D02*
X477877D01*
G01X476441Y378857D02*
G02X477792Y379622I1351J-810D01*
G01X476428Y378834D02*
X476441Y378857D01*
G01X474483Y377671D02*
G03X476428Y378834I-70J2325D01*
G01X474354Y377671D02*
X474483D01*
G01X473048Y376884D02*
G02X474354Y377671I1365J-788D01*
G01X471084Y375721D02*
G03X473048Y376884I-51J2326D01*
G01X470989Y375721D02*
X471084D01*
G01X469668Y374933D02*
G02X470989Y375721I1365J-787D01*
G01X467738Y373771D02*
G03X469668Y374933I-85J2325D01*
G01X467582Y373771D02*
X467738D01*
G01X466288Y372984D02*
G02X467582Y373771I1365J-787D01*
G01X464343Y371821D02*
G03X466288Y372984I-70J2325D01*
G01X464202Y371821D02*
X464343D01*
G01X462908Y369459D02*
G02X464202Y371821I1365J788D01*
G01X462933Y367176D02*
G03X462908Y369459I-2040J1119D01*
G01Y367134D02*
X462933Y367176D01*
G01X462889Y367100D02*
X462908Y367134D01*
G01Y365559D02*
G02X462889Y367100I1365J787D01*
G01X462974Y365446D02*
X462908Y365559D01*
G01X464273Y362447D02*
X462974Y365446D01*
G01X459501Y402657D02*
G02X459528Y404183I1392J739D01*
G01X459563Y402549D02*
X459501Y402657D01*
G01X459528Y400283D02*
G03X459563Y402549I-2015J1164D01*
G01X459501Y398757D02*
G02X459528Y400283I1392J739D01*
G01X459563Y398649D02*
X459501Y398757D01*
G01X459528Y396383D02*
G03X459563Y398649I-2015J1164D01*
G01X459501Y394857D02*
G02X459528Y396383I1392J739D01*
G01Y394809D02*
X459501Y394857D01*
G01X459553Y394767D02*
X459528Y394809D01*
G01X457598Y391322D02*
G03X459553Y394767I-85J2325D01*
G01X457469Y391322D02*
X457598D01*
G01X456148Y390534D02*
G02X457469Y391322I1365J-787D01*
G01X454203Y389371D02*
G03X456148Y390534I-70J2325D01*
G01X454074Y389371D02*
X454203D01*
G01X452768Y388584D02*
G02X454074Y389371I1365J-788D01*
G01X450838Y387422D02*
G03X452768Y388584I-85J2325D01*
G01X450709Y387422D02*
X450838D01*
G01X449388Y386634D02*
G02X450709Y387422I1365J-787D01*
G01X447443Y385471D02*
G03X449388Y386634I-70J2325D01*
G01X447314Y385471D02*
X447443D01*
G01X446008Y384684D02*
G02X447314Y385471I1365J-788D01*
G01X444078Y383522D02*
G03X446008Y384684I-85J2325D01*
G01X443949Y383522D02*
X444078D01*
G01X442628Y381159D02*
G02X443949Y383522I1365J788D01*
G01X442653Y378876D02*
G03X442628Y381159I-2040J1119D01*
G01Y378834D02*
X442653Y378876D01*
G01X442609Y378800D02*
X442628Y378834D01*
G01Y377259D02*
G02X442609Y378800I1365J787D01*
G01X442628Y374933D02*
G03Y377259I-2015J1163D01*
G01Y373359D02*
G02Y374933I1365J787D01*
G01X442653Y373317D02*
X442628Y373359D01*
G01Y371034D02*
G03X442653Y373317I-2015J1164D01*
G01X442609Y371000D02*
X442628Y371034D01*
G01Y369459D02*
G02X442609Y371000I1365J787D01*
G01X442653Y367176D02*
G03X442628Y369459I-2040J1119D01*
G01Y367134D02*
X442653Y367176D01*
G01X442609Y367100D02*
X442628Y367134D01*
G01Y365559D02*
G02X442609Y367100I1365J787D01*
G01X442694Y365446D02*
X442628Y365559D01*
G01X443993Y362447D02*
X442694Y365446D01*
G01X477877Y364022D02*
G03X479807Y365184I-85J2325D01*
G01X477792Y364022D02*
X477877D01*
G01X476441Y363257D02*
G02X477792Y364022I1351J-810D01*
G01X476364Y363121D02*
X476441Y363257D01*
G01X474413Y360496D02*
X476364Y363121D01*
G01X477851Y368672D02*
G03X479157Y369459I-59J1575D01*
G01X477722Y368672D02*
X477851D01*
G01X475777Y367509D02*
G02X477722Y368672I2015J-1162D01*
G01X475764Y367486D02*
X475777Y367509D01*
G01X474413Y366721D02*
G03X475764Y367486I0J1575D01*
G01X474328Y366721D02*
X474413D01*
G01X472398Y365559D02*
G02X474328Y366721I2015J-1163D01*
G01X471520Y364848D02*
G03X472398Y365559I-487J1499D01*
G01X470968Y364571D02*
G02X471520Y364848I1186J-1675D01*
G01X470176Y363769D02*
G03X470968Y364571I-1424J2198D01*
G01X469668Y361659D02*
G02X470176Y363769I1365J787D01*
G01X469693Y359376D02*
G03X469668Y361659I-2040J1119D01*
G01Y359334D02*
X469693Y359376D01*
G01X469649Y359300D02*
X469668Y359334D01*
G01Y357759D02*
G02X469649Y359300I1365J787D01*
G01X469734Y357646D02*
X469668Y357759D01*
G01X471033Y354647D02*
X469734Y357646D01*
G01X416593Y399501D02*
Y401566D01*
G01X426043Y397548D02*
Y408572D01*
G01X423784Y395221D02*
G03X426043Y397548I-69J2327D01*
G01X423714Y395222D02*
X423784Y395221D01*
G01X423670Y395222D02*
X423714D01*
G01X422349Y392859D02*
G02X423670Y395222I1365J788D01*
G01X422374Y390576D02*
G03X422349Y392859I-2040J1119D01*
G01Y390534D02*
X422374Y390576D01*
G01X422330Y390500D02*
X422349Y390534D01*
G01Y388959D02*
G02X422330Y390500I1365J787D01*
G01X422374Y386676D02*
G03X422349Y388959I-2040J1119D01*
G01Y386634D02*
X422374Y386676D01*
G01X422330Y386600D02*
X422349Y386634D01*
G01Y385059D02*
G02X422330Y386600I1365J787D01*
G01X422374Y382776D02*
G03X422349Y385059I-2040J1119D01*
G01Y382734D02*
X422374Y382776D01*
G01X422330Y382700D02*
X422349Y382734D01*
G01Y381159D02*
G02X422330Y382700I1365J787D01*
G01X422374Y378876D02*
G03X422349Y381159I-2040J1119D01*
G01Y378834D02*
X422374Y378876D01*
G01X422330Y378800D02*
X422349Y378834D01*
G01Y377259D02*
G02X422330Y378800I1365J787D01*
G01X422349Y374933D02*
G03Y377259I-2015J1163D01*
G01Y373359D02*
G02Y374933I1365J787D01*
G01X422374Y373317D02*
X422349Y373359D01*
G01Y371034D02*
G03X422374Y373317I-2015J1164D01*
G01X422250Y369666D02*
G02X422349Y371034I1464J582D01*
G01X422560Y369582D02*
X422250Y369666D01*
G01X423714Y370247D02*
X422560Y369582D01*
G01X455517Y402643D02*
G03X455498Y404184I-1384J754D01*
G01Y402609D02*
X455517Y402643D01*
G01X455473Y402567D02*
X455498Y402609D01*
G01Y400284D02*
G02X455473Y402567I2015J1164D01*
G01X455517Y398743D02*
G03X455498Y400284I-1384J754D01*
G01Y398709D02*
X455517Y398743D01*
G01X455473Y398667D02*
X455498Y398709D01*
G01Y396384D02*
G02X455473Y398667I2015J1164D01*
G01X454177Y394021D02*
G03X455498Y396384I-44J1575D01*
G01X454048Y394021D02*
X454177D01*
G01X452118Y392859D02*
G02X454048Y394021I2015J-1163D01*
G01X450812Y392072D02*
G03X452118Y392859I-59J1575D01*
G01X450683Y392072D02*
X450812D01*
G01X448738Y390909D02*
G02X450683Y392072I2015J-1162D01*
G01X447417Y390121D02*
G03X448738Y390909I-44J1575D01*
G01X447288Y390121D02*
X447417D01*
G01X445358Y388959D02*
G02X447288Y390121I2015J-1163D01*
G01X444052Y388172D02*
G03X445358Y388959I-59J1575D01*
G01X443923Y388172D02*
X444052D01*
G01X441978Y387009D02*
G02X443923Y388172I2015J-1162D01*
G01X440657Y386221D02*
G03X441978Y387009I-44J1575D01*
G01X440528Y386221D02*
X440657D01*
G01X438573Y382776D02*
G02X440528Y386221I2040J1120D01*
G01X438598Y382734D02*
X438573Y382776D01*
G01X438617Y382700D02*
X438598Y382734D01*
G01Y381159D02*
G03X438617Y382700I-1365J787D01*
G01X438573Y378876D02*
G02X438598Y381159I2040J1119D01*
G01Y378834D02*
X438573Y378876D01*
G01X438617Y378800D02*
X438598Y378834D01*
G01Y377259D02*
G03X438617Y378800I-1365J787D01*
G01X438598Y374933D02*
G02Y377259I2015J1163D01*
G01Y373359D02*
G03Y374933I-1365J787D01*
G01X438573Y373317D02*
X438598Y373359D01*
G01Y371034D02*
G02X438573Y373317I2015J1164D01*
G01X438617Y371000D02*
X438598Y371034D01*
G01Y369459D02*
G03X438617Y371000I-1365J787D01*
G01X438573Y367176D02*
G02X438598Y369459I2040J1119D01*
G01Y367134D02*
X438573Y367176D01*
G01X438617Y367100D02*
X438598Y367134D01*
G01Y365559D02*
G03X438617Y367100I-1365J787D01*
G01X438573Y363276D02*
G02X438598Y365559I2040J1119D01*
G01Y363234D02*
X438573Y363276D01*
G01X438617Y363200D02*
X438598Y363234D01*
G01Y361659D02*
G03X438617Y363200I-1365J787D01*
G01X438573Y359376D02*
G02X438598Y361659I2040J1119D01*
G01Y359334D02*
X438573Y359376D01*
G01X438664Y359218D02*
X438598Y359334D01*
G01X440613Y356596D02*
X438664Y359218D01*
G01X441997Y402642D02*
G03X441978Y404084I-1293J704D01*
G01Y402608D02*
X441997Y402642D01*
G01X441978Y400282D02*
G02Y402608I2015J1163D01*
G01X441997Y400248D02*
X441978Y400282D01*
G01Y398707D02*
G03X441997Y400248I-1365J787D01*
G01X441953Y396424D02*
G02X441978Y398707I2040J1119D01*
G01Y396382D02*
X441953Y396424D01*
G01X440684Y394021D02*
G03X441978Y396382I-71J1574D01*
G01X440528Y394021D02*
X440684D01*
G01X438598Y392859D02*
G02X440528Y394021I2015J-1163D01*
G01X437292Y392072D02*
G03X438598Y392859I-59J1575D01*
G01X437163Y392072D02*
X437292D01*
G01X435218Y390909D02*
G02X437163Y392072I2015J-1162D01*
G01X435205Y390886D02*
X435218Y390909D01*
G01X433854Y390121D02*
G03X435205Y390886I0J1575D01*
G01X433769Y390121D02*
X433854D01*
G01X431814Y386676D02*
G02X433769Y390121I2040J1120D01*
G01X431839Y386634D02*
X431814Y386676D01*
G01X431858Y386600D02*
X431839Y386634D01*
G01Y385059D02*
G03X431858Y386600I-1365J787D01*
G01X431814Y382776D02*
G02X431839Y385059I2040J1119D01*
G01Y382734D02*
X431814Y382776D01*
G01X431858Y382700D02*
X431839Y382734D01*
G01Y381159D02*
G03X431858Y382700I-1365J787D01*
G01X431814Y378876D02*
G02X431839Y381159I2040J1119D01*
G01Y378834D02*
X431814Y378876D01*
G01X431858Y378800D02*
X431839Y378834D01*
G01Y377259D02*
G03X431858Y378800I-1365J787D01*
G01X431839Y374933D02*
G02Y377259I2015J1163D01*
G01Y373359D02*
G03Y374933I-1365J787D01*
G01X431814Y373317D02*
X431839Y373359D01*
G01Y371034D02*
G02X431814Y373317I2015J1164D01*
G01X431858Y371000D02*
X431839Y371034D01*
G01Y369459D02*
G03X431858Y371000I-1365J787D01*
G01X431814Y367176D02*
G02X431839Y369459I2040J1119D01*
G01Y367134D02*
X431814Y367176D01*
G01X431905Y367018D02*
X431839Y367134D01*
G01X433854Y364396D02*
X431905Y367018D01*
G01X422139Y398205D02*
Y408914D01*
G01X419281Y395347D02*
X422139Y398205D01*
G01X419281Y393647D02*
Y395347D01*
G01X418969Y392484D02*
G03X419281Y393647I-2015J1164D01*
G01X418950Y390943D02*
G02X418969Y392484I1384J754D01*
G01Y390909D02*
X418950Y390943D01*
G01X418994Y390867D02*
X418969Y390909D01*
G01Y388584D02*
G03X418994Y390867I-2015J1164D01*
G01X418950Y387043D02*
G02X418969Y388584I1384J754D01*
G01Y387009D02*
X418950Y387043D01*
G01X418994Y386967D02*
X418969Y387009D01*
G01Y384684D02*
G03X418994Y386967I-2015J1164D01*
G01X418950Y383143D02*
G02X418969Y384684I1384J754D01*
G01Y383109D02*
X418950Y383143D01*
G01X418994Y383067D02*
X418969Y383109D01*
G01Y380784D02*
G03X418994Y383067I-2015J1164D01*
G01X418950Y379243D02*
G02X418969Y380784I1384J754D01*
G01Y379209D02*
X418950Y379243D01*
G01X418994Y379167D02*
X418969Y379209D01*
G01Y376884D02*
G03X418994Y379167I-2015J1164D01*
G01X418950Y375343D02*
G02X418969Y376884I1384J754D01*
G01Y375309D02*
X418950Y375343D01*
G01X418994Y373026D02*
G03X418969Y375309I-2040J1119D01*
G01Y372984D02*
X418994Y373026D01*
G01X418969Y371410D02*
G02Y372984I1365J787D01*
G01Y369084D02*
G03Y371410I-2015J1163D01*
G01X420290Y366722D02*
G02X418969Y369084I44J1575D01*
G01X420419Y366722D02*
X420290D01*
G01X423714Y366347D02*
G03X420419Y366722I-3295J-14289D01*
G01X445316Y402304D02*
G02X445358Y404558I2057J1089D01*
G01X445385Y402183D02*
X445316Y402304D01*
G01X445358Y400657D02*
G03X445385Y402183I-1365J787D01*
G01X445358Y398331D02*
G02Y400657I2015J1163D01*
G01Y396757D02*
G03Y398331I-1365J787D01*
G01X445333Y396715D02*
X445358Y396757D01*
G01Y394432D02*
G02X445333Y396715I2015J1164D01*
G01X444064Y392071D02*
G03X445358Y394432I-71J1574D01*
G01X443895Y392071D02*
X444064D01*
G01X441978Y390909D02*
G02X443895Y392071I2015J-1162D01*
G01X440657Y390121D02*
G03X441978Y390909I-44J1575D01*
G01X440528Y390121D02*
X440657D01*
G01X438598Y388959D02*
G02X440528Y390121I2015J-1163D01*
G01X437292Y388172D02*
G03X438598Y388959I-59J1575D01*
G01X437163Y388172D02*
X437292D01*
G01X435218Y384683D02*
G02X437163Y388172I2015J1163D01*
G01X435218Y383109D02*
G03Y384683I-1364J787D01*
G01X435183Y383049D02*
X435218Y383109D01*
G01Y380783D02*
G02X435183Y383049I2015J1164D01*
G01X435218Y379209D02*
G03Y380783I-1364J787D01*
G01X435183Y379149D02*
X435218Y379209D01*
G01Y376883D02*
G02X435183Y379149I2015J1164D01*
G01X435218Y375309D02*
G03Y376883I-1364J787D01*
G01X435193Y373026D02*
G02X435218Y375309I2040J1119D01*
G01Y372984D02*
X435193Y373026D01*
G01X435218Y371410D02*
G03Y372984I-1364J787D01*
G01X435193Y371368D02*
X435218Y371410D01*
G01X436977Y367934D02*
G02X435193Y371368I256J2313D01*
G01X437233Y367678D02*
X436977Y367934D01*
G01X437233Y366347D02*
Y367678D01*
G01X452702Y365068D02*
X450753Y362447D01*
G01X452768Y365184D02*
X452702Y365068D01*
G01X452793Y367467D02*
G02X452768Y365184I-2040J-1119D01*
G01Y367509D02*
X452793Y367467D01*
G01X452749Y367543D02*
X452768Y367509D01*
G01Y369084D02*
G03X452749Y367543I1365J-787D01*
G01X452768Y371410D02*
G02Y369084I-2015J-1163D01*
G01Y372984D02*
G03Y371410I1365J-787D01*
G01X452793Y373026D02*
X452768Y372984D01*
G01Y375309D02*
G02X452793Y373026I-2015J-1164D01*
G01X452749Y375343D02*
X452768Y375309D01*
G01X454074Y377671D02*
G03X452749Y375343I59J-1575D01*
G01X454203Y377671D02*
X454074D01*
G01X456148Y378834D02*
G02X454203Y377671I-2015J1162D01*
G01X457469Y379622D02*
G03X456148Y378834I44J-1575D01*
G01X457598Y379622D02*
X457469D01*
G01X459528Y380784D02*
G02X457598Y379622I-2015J1163D01*
G01X460834Y381571D02*
G03X459528Y380784I59J-1575D01*
G01X460963Y381571D02*
X460834D01*
G01X462908Y382734D02*
G02X460963Y381571I-2015J1162D01*
G01X464229Y383522D02*
G03X462908Y382734I44J-1575D01*
G01X464358Y383522D02*
X464229D01*
G01X466288Y384684D02*
G02X464358Y383522I-2015J1163D01*
G01X467594Y385471D02*
G03X466288Y384684I59J-1575D01*
G01X467723Y385471D02*
X467594D01*
G01X469668Y388959D02*
G02X467723Y385471I-2015J-1163D01*
G01X469649Y390500D02*
G03X469668Y388959I1384J-754D01*
G01Y390534D02*
X469649Y390500D01*
G01X469693Y390576D02*
X469668Y390534D01*
G01Y392859D02*
G02X469693Y390576I-2015J-1164D01*
G01X469649Y394400D02*
G03X469668Y392859I1384J-754D01*
G01Y394434D02*
X469649Y394400D01*
G01X469693Y394476D02*
X469668Y394434D01*
G01Y396759D02*
G02X469693Y394476I-2015J-1164D01*
G01X469649Y398300D02*
G03X469668Y396759I1384J-754D01*
G01Y398334D02*
X469649Y398300D01*
G01X469693Y398376D02*
X469668Y398334D01*
G01Y400659D02*
G02X469693Y398376I-2015J-1164D01*
G01X469649Y402200D02*
G03X469668Y400659I1384J-754D01*
G01Y402234D02*
X469649Y402200D01*
G01X469693Y402276D02*
X469668Y402234D01*
G01Y404559D02*
G02X469693Y402276I-2015J-1164D01*
G01X472417Y406100D02*
G02X472398Y404559I-1384J-754D01*
G01Y406134D02*
X472417Y406100D01*
G01X472373Y406176D02*
X472398Y406134D01*
G01Y408459D02*
G03X472373Y406176I2015J-1164D01*
G01X472417Y410000D02*
G02X472398Y408459I-1384J-754D01*
G01Y410034D02*
X472417Y410000D01*
G01X472373Y410076D02*
X472398Y410034D01*
G01Y412359D02*
G03X472373Y410076I2015J-1164D01*
G01X472417Y413900D02*
G02X472398Y412359I-1384J-754D01*
G01Y413934D02*
X472417Y413900D01*
G01X472373Y413976D02*
X472398Y413934D01*
G01X472767Y416738D02*
G03X472373Y413976I1644J-1644D01*
G01X474846Y418817D02*
X472767Y416738D01*
G01X474846Y419174D02*
Y418817D01*
G01X474079Y419941D02*
X474846Y419174D01*
G01X473073Y406467D02*
G02X473048Y404184I-2040J-1119D01*
G01Y406509D02*
X473073Y406467D01*
G01X473029Y406543D02*
X473048Y406509D01*
G01Y408084D02*
G03X473029Y406543I1365J-787D01*
G01X473073Y410367D02*
G02X473048Y408084I-2040J-1119D01*
G01Y410409D02*
X473073Y410367D01*
G01X473029Y410443D02*
X473048Y410409D01*
G01Y411984D02*
G03X473029Y410443I1365J-787D01*
G01X473073Y414267D02*
G02X473048Y411984I-2040J-1119D01*
G01Y414309D02*
X473073Y414267D01*
G01X473029Y414343D02*
X473048Y414309D01*
G01X473299Y416210D02*
G03X473029Y414343I1113J-1114D01*
G01X475596Y418507D02*
X473299Y416210D01*
G01X475596Y418958D02*
Y418507D01*
G01X476579Y419941D02*
X475596Y418958D01*
G01X453279Y419247D02*
X454192Y420160D01*
G01X453279Y417073D02*
Y419247D01*
G01X455937Y414415D02*
X453279Y417073D01*
G01X455937Y413147D02*
Y414415D01*
G01X456148Y412359D02*
G02X455937Y413147I1365J788D01*
G01X456173Y410076D02*
G03X456148Y412359I-2040J1119D01*
G01Y410034D02*
X456173Y410076D01*
G01X456129Y410000D02*
X456148Y410034D01*
G01Y408459D02*
G02X456129Y410000I1365J787D01*
G01X456173Y406176D02*
G03X456148Y408459I-2040J1119D01*
G01Y406134D02*
X456173Y406176D01*
G01X456129Y406100D02*
X456148Y406134D01*
G01Y404559D02*
G02X456129Y406100I1365J787D01*
G01X427248Y412357D02*
X426372Y413233D01*
G01X427248Y410841D02*
Y412357D01*
G01X425290Y408883D02*
X427248Y410841D01*
G01X442381Y404977D02*
Y406641D01*
G01X442392Y404966D02*
X442381Y404977D01*
G01X442628Y404559D02*
X442392Y404966D01*
G01X457398Y419480D02*
X456473Y420405D01*
G01X458384Y418360D02*
X457398Y419480D01*
G01X458878Y416259D02*
G03X458384Y418360I-1365J788D01*
G01X458843Y413993D02*
G02X458878Y416259I2050J1102D01*
G01X458905Y413885D02*
X458843Y413993D01*
G01X458878Y412359D02*
G03X458905Y413885I-1365J787D01*
G01X458843Y410093D02*
G02X458878Y412359I2050J1102D01*
G01X458905Y409985D02*
X458843Y410093D01*
G01X458878Y408459D02*
G03X458905Y409985I-1365J787D01*
G01X458843Y406193D02*
G02X458878Y408459I2050J1102D01*
G01X458905Y406085D02*
X458843Y406193D01*
G01X458878Y404559D02*
G03X458905Y406085I-1365J787D01*
G01X469018Y415884D02*
G02X468706Y417047I2015J1164D01*
G01X469037Y414343D02*
G03X469018Y415884I-1384J754D01*
G01Y414309D02*
X469037Y414343D01*
G01X468993Y414267D02*
X469018Y414309D01*
G01Y411984D02*
G02X468993Y414267I2015J1164D01*
G01X469037Y410443D02*
G03X469018Y411984I-1384J754D01*
G01Y410409D02*
X469037Y410443D01*
G01X468993Y410367D02*
X469018Y410409D01*
G01Y408084D02*
G02X468993Y410367I2015J1164D01*
G01X469037Y406543D02*
G03X469018Y408084I-1384J754D01*
G01Y406509D02*
X469037Y406543D01*
G01X468993Y406467D02*
X469018Y406509D01*
G01Y404184D02*
G02X468993Y406467I2015J1164D01*
G01X469948Y420156D02*
X469079Y421025D01*
G01X469948Y419441D02*
Y420156D01*
G01X468706Y418199D02*
X469948Y419441D01*
G01X468706Y417047D02*
Y418199D01*
G01X448248Y405716D02*
X449023Y406491D01*
G01X447015Y405716D02*
X448248D01*
G01X446730Y405431D02*
X447015Y405716D01*
G01X446008Y404182D02*
X446730Y405431D01*
G01X458973Y419509D02*
Y420405D01*
G01X459261Y418582D02*
X458973Y419509D01*
G01X459528Y418209D02*
G03X459261Y418582I-2015J-1160D01*
G01X459563Y418149D02*
X459528Y418209D01*
G01Y415883D02*
G03X459563Y418149I-2015J1164D01*
G01X459501Y414357D02*
G02X459528Y415883I1392J739D01*
G01Y414309D02*
X459501Y414357D01*
G01X459563Y414249D02*
X459528Y414309D01*
G01Y411983D02*
G03X459563Y414249I-2015J1164D01*
G01X459501Y410457D02*
G02X459528Y411983I1392J739D01*
G01X459563Y410349D02*
X459501Y410457D01*
G01X459528Y408083D02*
G03X459563Y410349I-2015J1164D01*
G01X459501Y406557D02*
G02X459528Y408083I1392J739D01*
G01X459563Y406449D02*
X459501Y406557D01*
G01X459528Y404183D02*
G03X459563Y406449I-2015J1164D01*
G01X427996Y412357D02*
X428872Y413233D01*
G01X427996Y410525D02*
Y412357D01*
G01X426043Y408572D02*
X427996Y410525D01*
G01X452529Y418885D02*
X451473Y419941D01*
G01X452529Y416760D02*
Y418885D01*
G01X455186Y414103D02*
X452529Y416760D01*
G01X455186Y413147D02*
Y414103D01*
G01X455498Y411984D02*
G02X455186Y413147I2015J1164D01*
G01X455517Y410443D02*
G03X455498Y411984I-1384J754D01*
G01Y410409D02*
X455517Y410443D01*
G01X455473Y410367D02*
X455498Y410409D01*
G01Y408084D02*
G02X455473Y410367I2015J1164D01*
G01X455517Y406543D02*
G03X455498Y408084I-1384J754D01*
G01Y406509D02*
X455517Y406543D01*
G01X455473Y406467D02*
X455498Y406509D01*
G01Y404184D02*
G02X455473Y406467I2015J1164D01*
G01X441289Y405273D02*
X439921Y406641D01*
G01X441978Y404084D02*
X441289Y405273D01*
G01X422139Y408914D02*
X423872Y410647D01*
G01X445673Y406200D02*
X444881Y406992D01*
G01X445673Y405102D02*
Y406200D01*
G01X445358Y404558D02*
X445673Y405102D01*
G01X469649Y406100D02*
G03X469668Y404559I1384J-754D01*
G01Y406134D02*
X469649Y406100D01*
G01X469693Y406176D02*
X469668Y406134D01*
G01Y408459D02*
G02X469693Y406176I-2015J-1164D01*
G01X469649Y410000D02*
G03X469668Y408459I1384J-754D01*
G01Y410034D02*
X469649Y410000D01*
G01X469693Y410076D02*
X469668Y410034D01*
G01Y412359D02*
G02X469693Y410076I-2015J-1164D01*
G01X469649Y413900D02*
G03X469668Y412359I1384J-754D01*
G01Y413934D02*
X469649Y413900D01*
G01X469693Y413976D02*
X469668Y413934D01*
G01Y416259D02*
G02X469693Y413976I-2015J-1164D01*
G01X469457Y417047D02*
G03X469668Y416259I1576J0D01*
G01X469457Y417887D02*
Y417047D01*
G01X470698Y419128D02*
X469457Y417887D01*
G01X470698Y420144D02*
Y419128D01*
G01X471579Y421025D02*
X470698Y420144D01*
G01X493692Y205215D02*
Y204500D01*
G01X488818Y210089D02*
X493692Y205215D01*
G01X488818Y210780D02*
Y210089D01*
G01X487960Y211638D02*
X488818Y210780D01*
G01X488177Y213459D02*
G03X487960Y211638I2015J-1164D01*
G01X488196Y215000D02*
G02X488177Y213459I-1384J-754D01*
G01Y215034D02*
X488196Y215000D01*
G01X488152Y215076D02*
X488177Y215034D01*
G01Y217359D02*
G03X488152Y215076I2015J-1164D01*
G01X488196Y218900D02*
G02X488177Y217359I-1384J-754D01*
G01X482072Y194200D02*
X483492D01*
G01X478142Y198130D02*
X482072Y194200D01*
G01X478142Y198646D02*
Y198130D01*
G01X478192Y198696D02*
X478142Y198646D01*
G01X478192Y200778D02*
Y198696D01*
G01X481592Y193615D02*
Y193300D01*
G01X494468Y205500D02*
X495392D01*
G01X489568Y210400D02*
X494468Y205500D01*
G01X489568Y211155D02*
Y210400D01*
G01X488629Y212094D02*
X489568Y211155D01*
G01X488827Y213084D02*
G03X488629Y212094I1365J-788D01*
G01X488852Y215367D02*
G02X488827Y213084I-2040J-1119D01*
G01Y215409D02*
X488852Y215367D01*
G01X488808Y215443D02*
X488827Y215409D01*
G01Y216984D02*
G03X488808Y215443I1365J-787D01*
G01X488852Y219267D02*
G02X488827Y216984I-2040J-1119D01*
G01X480344Y191548D02*
X481142Y190750D01*
G01X480344Y191552D02*
Y191548D01*
G01X511533Y216572D02*
G02X510208Y218900I59J1575D01*
G01X511662Y216572D02*
X511533D01*
G01X513607Y215409D02*
G03X511662Y216572I-2015J-1162D01*
G01X514928Y214621D02*
G02X513607Y215409I44J1575D01*
G01X515057Y214621D02*
X514928D01*
G01X516987Y213459D02*
G03X515057Y214621I-2015J-1163D01*
G01X518293Y212672D02*
G02X516987Y213459I59J1575D01*
G01X518403Y212672D02*
X518293D01*
G01X520367Y211509D02*
G03X518403Y212672I-2015J-1163D01*
G01X521683Y210722D02*
G02X520367Y211509I48J1574D01*
G01X521801Y210722D02*
X521683D01*
G01X523746Y209559D02*
G03X521801Y210722I-2015J-1162D01*
G01X525040Y208772D02*
G02X523746Y209559I71J1574D01*
G01X525196Y208772D02*
X525040D01*
G01X527126Y207610D02*
G03X525196Y208772I-2015J-1163D01*
G01X529856Y207610D02*
G02X527126I-1365J787D01*
G01X531786Y208772D02*
G03X529856Y207610I85J-2325D01*
G01X531956Y208772D02*
X531786D01*
G01X533886Y207610D02*
G03X531956Y208772I-2015J-1163D01*
G01X536616Y207610D02*
G02X533886I-1365J787D01*
G01X538546Y208772D02*
G03X536616Y207610I85J-2325D01*
G01X538716Y208772D02*
X538546D01*
G01X540646Y207610D02*
G03X538716Y208772I-2015J-1163D01*
G01X514902Y217771D02*
G02X512957Y221259I70J2325D01*
G01X515031Y217771D02*
X514902D01*
G01X516337Y216984D02*
G03X515031Y217771I-1365J-788D01*
G01X518267Y215822D02*
G02X516337Y216984I85J2325D01*
G01X518352Y215822D02*
X518267D01*
G01X519703Y215057D02*
G03X518352Y215822I-1351J-810D01*
G01X519716Y215034D02*
X519703Y215057D01*
G01X521661Y213871D02*
G02X519716Y215034I70J2325D01*
G01X521790Y213871D02*
X521661D01*
G01X523096Y213084D02*
G03X521790Y213871I-1365J-788D01*
G01X525060Y211921D02*
G02X523096Y213084I51J2326D01*
G01X525155Y211921D02*
X525060D01*
G01X526476Y211133D02*
G03X525155Y211921I-1365J-787D01*
G01X528406Y209971D02*
G02X526476Y211133I85J2325D01*
G01X528576Y209971D02*
X528406D01*
G01X530506Y211133D02*
G02X528576Y209971I-2015J1163D01*
G01X533236Y211133D02*
G03X530506I-1365J-787D01*
G01X535166Y209971D02*
G02X533236Y211133I85J2325D01*
G01X535336Y209971D02*
X535166D01*
G01X537266Y211133D02*
G02X535336Y209971I-2015J1163D01*
G01X539996Y211133D02*
G03X537266I-1365J-787D01*
G01X479592Y189700D02*
X479792Y189500D01*
G01X479592Y191243D02*
Y189700D01*
G01X491801Y200450D02*
X491842D01*
G01X485964Y206287D02*
X491801Y200450D01*
G01X485964Y207311D02*
Y206287D01*
G01X485377Y208516D02*
G02X485964Y207311I-936J-1202D01*
G01X484797Y209183D02*
G03X485377Y208516I1996J1150D01*
G01X484816Y211543D02*
G03X484797Y209183I2000J-1196D01*
G01Y213084D02*
G02X484816Y211543I-1365J-787D01*
G01X484772Y215367D02*
G03X484797Y213084I2040J-1119D01*
G01Y215409D02*
X484772Y215367D01*
G01X484816Y215443D02*
X484797Y215409D01*
G01Y216984D02*
G02X484816Y215443I-1365J-787D01*
G01X484772Y219267D02*
G03X484797Y216984I2040J-1119D01*
G01X511507Y215822D02*
G02X509552Y219267I85J2325D01*
G01X511636Y215822D02*
X511507D01*
G01X512957Y215034D02*
G03X511636Y215822I-1365J-787D01*
G01X514902Y213871D02*
G02X512957Y215034I70J2325D01*
G01X515031Y213871D02*
X514902D01*
G01X516337Y213084D02*
G03X515031Y213871I-1365J-788D01*
G01X518301Y211921D02*
G02X516337Y213084I51J2326D01*
G01X518352Y211921D02*
X518301D01*
G01X519703Y211156D02*
G03X518352Y211921I-1351J-810D01*
G01X519716Y211133D02*
X519703Y211156D01*
G01X521646Y209971D02*
G02X519716Y211133I85J2325D01*
G01X521802Y209971D02*
X521646D01*
G01X523096Y209184D02*
G03X521802Y209971I-1365J-787D01*
G01X525041Y208021D02*
G02X523096Y209184I70J2325D01*
G01X525182Y208021D02*
X525041D01*
G01X526476Y207234D02*
G03X525182Y208021I-1365J-787D01*
G01X530506Y207234D02*
G02X526476I-2015J1163D01*
G01X531800Y208021D02*
G03X530506Y207234I71J-1574D01*
G01X531942Y208021D02*
X531800D01*
G01X533236Y207234D02*
G03X531942Y208021I-1365J-787D01*
G01X537266Y207234D02*
G02X533236I-2015J1163D01*
G01X538560Y208021D02*
G03X537266Y207234I71J-1574D01*
G01X538702Y208021D02*
X538560D01*
G01X539996Y207234D02*
G03X538702Y208021I-1365J-787D01*
G01X490518Y202800D02*
X492592D01*
G01X486718Y206600D02*
X490518Y202800D01*
G01X486718Y207311D02*
Y206600D01*
G01X485842Y209103D02*
G02X486718Y207311I-1374J-1782D01*
G01X485445Y209557D02*
G03X485842Y209103I1347J778D01*
G01X485447Y209558D02*
X485445Y209557D01*
G01X485447Y211133D02*
G03Y209558I1364J-788D01*
G01Y213459D02*
G02Y211133I-2015J-1163D01*
G01X485428Y215000D02*
G03X485447Y213459I1384J-754D01*
G01Y215034D02*
X485428Y215000D01*
G01X485472Y215076D02*
X485447Y215034D01*
G01Y217359D02*
G02X485472Y215076I-2015J-1164D01*
G01X485428Y218900D02*
G03X485447Y217359I1384J-754D01*
G01X488177Y218934D02*
X488196Y218900D01*
G01X488152Y218976D02*
X488177Y218934D01*
G01Y221259D02*
G03X488152Y218976I2015J-1164D01*
G01X488196Y222800D02*
G02X488177Y221259I-1384J-754D01*
G01Y222834D02*
X488196Y222800D01*
G01X488152Y222876D02*
X488177Y222834D01*
G01Y225159D02*
G03X488152Y222876I2015J-1164D01*
G01X488196Y226700D02*
G02X488177Y225159I-1384J-754D01*
G01Y226734D02*
X488196Y226700D01*
G01X488152Y226776D02*
X488177Y226734D01*
G01Y229059D02*
G03X488152Y226776I2015J-1164D01*
G01X488196Y230600D02*
G02X488177Y229059I-1384J-754D01*
G01Y230634D02*
X488196Y230600D01*
G01X488152Y232917D02*
G03X488177Y230634I2040J-1119D01*
G01Y232959D02*
X488152Y232917D01*
G01X488177Y234533D02*
G02Y232959I-1365J-787D01*
G01Y236859D02*
G03Y234533I2015J-1163D01*
G01X488196Y238400D02*
G02X488177Y236859I-1384J-754D01*
G01Y238434D02*
X488196Y238400D01*
G01X488152Y238476D02*
X488177Y238434D01*
G01X488249Y240739D02*
G03X488152Y238476I1818J-1211D01*
G01X488269Y240768D02*
X488249Y240739D01*
G01X488268Y242230D02*
G02X488269Y240768I-1268J-732D01*
G01X488177Y242388D02*
X488268Y242230D01*
G01X488177Y244603D02*
G03Y242388I1919J-1108D01*
G01X488362Y245844D02*
G02X488177Y244603I-1667J-386D01*
G01Y246234D02*
G02X488362Y245844I-799J-618D01*
G01X488152Y246276D02*
X488177Y246234D01*
G01X488060Y248329D02*
G03X488152Y246276I2131J-933D01*
G01X487966Y248681D02*
X488060Y248329D01*
G01X486812Y249347D02*
X487966Y248681D01*
G01X538690Y251672D02*
G03X539996Y252459I-59J1575D01*
G01X538561Y251672D02*
X538690D01*
G01X536616Y250509D02*
G02X538561Y251672I2015J-1162D01*
G01X535295Y249721D02*
G03X536616Y250509I-44J1575D01*
G01X535166Y249721D02*
X535295D01*
G01X533236Y248559D02*
G02X535166Y249721I2015J-1163D01*
G01X531930Y247772D02*
G03X533236Y248559I-59J1575D01*
G01X531812Y247772D02*
X531930D01*
G01X530506Y248559D02*
G03X531812Y247772I1365J788D01*
G01X528576Y249721D02*
G02X530506Y248559I-85J-2325D01*
G01X528447Y249721D02*
X528576D01*
G01X527126Y250509D02*
G03X528447Y249721I1365J787D01*
G01X525181Y251672D02*
G02X527126Y250509I-70J-2325D01*
G01X525041Y251672D02*
X525181D01*
G01X523096Y250509D02*
G02X525041Y251672I2015J-1162D01*
G01X521775Y249721D02*
G03X523096Y250509I-44J1575D01*
G01X521731Y249721D02*
X521775D01*
G01X520380Y250486D02*
G03X521731Y249721I1351J810D01*
G01X520367Y250509D02*
X520380Y250486D01*
G01X518422Y251672D02*
G02X520367Y250509I-70J-2325D01*
G01X518282Y251672D02*
X518422D01*
G01X517529Y251523D02*
G02X518282Y251672I822J-2176D01*
G01X515199Y251523D02*
X517529D01*
G01X514972Y251296D02*
X515199Y251523D01*
G01X528406Y269221D02*
G03X525111Y268847I0J-14702D01*
G01X528535Y269221D02*
X528406D01*
G01X529856Y270009D02*
G02X528535Y269221I-1365J787D01*
G01X531801Y271172D02*
G03X529856Y270009I70J-2325D01*
G01X531930Y271172D02*
X531801D01*
G01X533236Y271959D02*
G02X531930Y271172I-1365J788D01*
G01X535166Y273121D02*
G03X533236Y271959I85J-2325D01*
G01X535295Y273121D02*
X535166D01*
G01X536616Y273909D02*
G02X535295Y273121I-1365J787D01*
G01X538561Y275072D02*
G03X536616Y273909I70J-2325D01*
G01X538702Y275072D02*
X538561D01*
G01X539996Y275859D02*
G02X538702Y275072I-1365J787D01*
G01X538690Y259472D02*
G03X539996Y260259I-59J1575D01*
G01X538561Y259472D02*
X538690D01*
G01X536616Y258309D02*
G02X538561Y259472I2015J-1162D01*
G01X535295Y257521D02*
G03X536616Y258309I-44J1575D01*
G01X535166Y257521D02*
X535295D01*
G01X531871Y257147D02*
G02X535166Y257521I3295J-14328D01*
G01X483108Y266600D02*
X479500D01*
G01X485908Y263800D02*
X483108Y266600D01*
G01X489700Y263800D02*
X485908D01*
G01X490792Y262708D02*
X489700Y263800D01*
G01X493899Y261421D02*
X490792Y262708D01*
G01X494777Y261421D02*
X493899D01*
G01X496707Y260259D02*
G03X494777Y261421I-2015J-1163D01*
G01X498013Y259472D02*
G02X496707Y260259I59J1575D01*
G01X498142Y259472D02*
X498013D01*
G01X498697Y259388D02*
G03X498142Y259472I-623J-2241D01*
G01X499288Y259388D02*
X498697D01*
G01X500590Y260690D02*
X499288Y259388D01*
G01X502632Y261536D02*
X500590Y260690D01*
G01X503243Y262147D02*
X502632Y261536D01*
G01X504377Y262616D02*
X503243Y262147D01*
G01X505482Y262616D02*
X504377D01*
G01X506187Y261911D02*
X505482Y262616D01*
G01X506734Y260591D02*
X506187Y261911D01*
G01X506734Y259117D02*
Y260591D01*
G01X507461Y257362D02*
X506734Y259117D01*
G01X509074Y255749D02*
X507461Y257362D01*
G01X511611Y255749D02*
X509074D01*
G01X513607Y254409D02*
G03X511611Y255749I-2363J-1364D01*
G01X516337Y254409D02*
G02X513607I-1365J787D01*
G01X518282Y255572D02*
G03X516337Y254409I70J-2325D01*
G01X519721Y255558D02*
G03X518282Y255572I-895J-18049D01*
G01X521731Y255196D02*
G03X519721Y255558I-2404J-7588D01*
G01X526476Y238434D02*
G02X526809Y237803I-8262J-4763D01*
G01X525155Y239222D02*
G02X526476Y238434I-44J-1575D01*
G01X525026Y239222D02*
X525155D01*
G01X523096Y240384D02*
G03X525026Y239222I2015J1163D01*
G01X521959Y241155D02*
G02X523096Y240384I-228J-1560D01*
G01X518352Y241547D02*
G02X521959Y241155I-3510J-49084D01*
G01X538716Y258722D02*
G03X540646Y259884I-85J2325D01*
G01X538587Y258722D02*
X538716D01*
G01X537266Y257934D02*
G02X538587Y258722I1365J-787D01*
G01X535321Y256771D02*
G03X537266Y257934I-70J2325D01*
G01X535192Y256771D02*
X535321D01*
G01X533156Y255671D02*
G02X535192Y256771I2036J-1334D01*
G01X531652Y255024D02*
G03X533156Y255671I263J1460D01*
G01X528491Y255196D02*
G02X531652Y255024I890J-12780D01*
G01X528421Y245071D02*
G02X525111Y245447I0J14757D01*
G01X528550Y245071D02*
X528421D01*
G01X529856Y244284D02*
G03X528550Y245071I-1365J-788D01*
G01X531786Y243122D02*
G02X529856Y244284I85J2325D01*
G01X531956Y243122D02*
X531786D01*
G01X533886Y244284D02*
G02X531956Y243122I-2015J1163D01*
G01X534417Y244833D02*
G03X533886Y244284I834J-1338D01*
G01X535192Y245071D02*
G03X534417Y244833I60J-1575D01*
G01X535929Y245071D02*
X535192D01*
G01X537600Y243400D02*
X535929Y245071D01*
G01X528447Y238021D02*
X528576D01*
G01X527126Y238809D02*
G03X528447Y238021I1365J787D01*
G01X525181Y239972D02*
G02X527126Y238809I-70J-2325D01*
G01X525052Y239972D02*
X525181D01*
G01X523746Y240759D02*
G03X525052Y239972I1365J788D01*
G01X521987Y241909D02*
G02X523746Y240759I-256J-2312D01*
G01X521731Y242165D02*
X521987Y241909D01*
G01X521731Y243496D02*
Y242165D01*
G01X488827Y219309D02*
X488852Y219267D01*
G01X488808Y219343D02*
X488827Y219309D01*
G01Y220884D02*
G03X488808Y219343I1365J-787D01*
G01X488852Y223167D02*
G02X488827Y220884I-2040J-1119D01*
G01Y223209D02*
X488852Y223167D01*
G01X488808Y223243D02*
X488827Y223209D01*
G01Y224784D02*
G03X488808Y223243I1365J-787D01*
G01X488852Y227067D02*
G02X488827Y224784I-2040J-1119D01*
G01Y227109D02*
X488852Y227067D01*
G01X488808Y227143D02*
X488827Y227109D01*
G01Y228684D02*
G03X488808Y227143I1365J-787D01*
G01X488827Y231010D02*
G02Y228684I-2015J-1163D01*
G01Y232584D02*
G03Y231010I1365J-787D01*
G01X488852Y232626D02*
X488827Y232584D01*
G01Y234909D02*
G02X488852Y232626I-2015J-1164D01*
G01X488808Y234943D02*
X488827Y234909D01*
G01Y236484D02*
G03X488808Y234943I1365J-787D01*
G01X488852Y238767D02*
G02X488827Y236484I-2040J-1119D01*
G01Y238809D02*
X488852Y238767D01*
G01X488835Y240172D02*
G03X488827Y238809I1199J-689D01*
G01X488870Y240233D02*
X488835Y240172D01*
G01X488943Y242781D02*
G02X488870Y240233I-2423J-1206D01*
G01X488792Y243085D02*
X488943Y242781D01*
G01X488827Y244227D02*
G03X488792Y243085I1048J-604D01*
G01X488868Y244298D02*
X488827Y244227D01*
G01X488868Y246618D02*
G02Y244298I-2010J-1160D01*
G01X488840Y246665D02*
X488868Y246618D01*
G01X488827Y248127D02*
G03X488840Y246665I1249J-720D01*
G01X488645Y250723D02*
G02X488827Y248127I-1833J-1433D01*
G01X488387Y250981D02*
X488645Y250723D01*
G01X487957Y251600D02*
X488387Y250981D01*
G01X486812Y253247D02*
X487957Y251600D01*
G01X519716Y254034D02*
G03X521731Y251296I12362J6987D01*
G01X519703Y254057D02*
X519716Y254034D01*
G01X516987D02*
G02X519703Y254057I1365J-787D01*
G01X512957Y254034D02*
G03X516987I2015J1162D01*
G01X511556Y254999D02*
G02X512957Y254034I-313J-1954D01*
G01X508763Y254999D02*
X511556D01*
G01X506691Y257071D02*
X508763Y254999D01*
G01X506261Y258109D02*
X506691Y257071D01*
G01X505506Y258864D02*
X506261Y258109D01*
G01X503564Y258864D02*
X505506D01*
G01X502204Y257504D02*
X503564Y258864D01*
G01X500181Y257504D02*
X502204D01*
G01X499437Y257934D02*
G03X500181Y257504I744J429D01*
G01X498116Y258722D02*
G02X499437Y257934I-44J-1575D01*
G01X497987Y258722D02*
X498116D01*
G01X496057Y259884D02*
G03X497987Y258722I2015J1163D01*
G01X494751Y260671D02*
G02X496057Y259884I-59J-1575D01*
G01X491429Y260671D02*
X494751D01*
G01X489484Y262616D02*
X491429Y260671D01*
G01X486031Y262616D02*
X489484D01*
G01X484082Y264565D02*
X486031Y262616D01*
G01X482265Y264565D02*
X484082D01*
G01X509844Y250679D02*
G03X508979Y253000I-2445J410D01*
G01X510227Y248559D02*
G02X509844Y250679I2757J1593D01*
G01X510252Y246276D02*
G03X510227Y248559I-2040J1119D01*
G01Y246234D02*
X510252Y246276D01*
G01X510208Y246200D02*
X510227Y246234D01*
G01Y244659D02*
G02X510208Y246200I1365J787D01*
G01X510252Y242376D02*
G03X510227Y244659I-2040J1119D01*
G01Y242334D02*
X510252Y242376D01*
G01X510208Y242300D02*
X510227Y242334D01*
G01Y240759D02*
G02X510208Y242300I1365J787D01*
G01X510252Y238476D02*
G03X510227Y240759I-2040J1119D01*
G01Y238434D02*
X510252Y238476D01*
G01X510208Y238400D02*
X510227Y238434D01*
G01Y236859D02*
G02X510208Y238400I1365J787D01*
G01X510227Y234533D02*
G03Y236859I-2015J1163D01*
G01Y232959D02*
G02Y234533I1365J787D01*
G01X510252Y232917D02*
X510227Y232959D01*
G01Y230634D02*
G03X510252Y232917I-2015J1164D01*
G01X510208Y230600D02*
X510227Y230634D01*
G01Y229059D02*
G02X510208Y230600I1365J787D01*
G01X510252Y226776D02*
G03X510227Y229059I-2040J1119D01*
G01Y226734D02*
X510252Y226776D01*
G01X510208Y226700D02*
X510227Y226734D01*
G01Y225159D02*
G02X510208Y226700I1365J787D01*
G01X510252Y222876D02*
G03X510227Y225159I-2040J1119D01*
G01Y222834D02*
X510252Y222876D01*
G01X510208Y222800D02*
X510227Y222834D01*
G01Y221259D02*
G02X510208Y222800I1365J787D01*
G01X510252Y218976D02*
G03X510227Y221259I-2040J1119D01*
G01Y218934D02*
X510252Y218976D01*
G01X510208Y218900D02*
X510227Y218934D01*
G01X525026Y266522D02*
X524202Y266502D01*
G01X525196Y266522D02*
X525026D01*
G01X527126Y267684D02*
G02X525196Y266522I-2015J1163D01*
G01X528432Y268471D02*
G03X527126Y267684I59J-1575D01*
G01X528561Y268471D02*
X528432D01*
G01X530506Y269634D02*
G02X528561Y268471I-2015J1162D01*
G01X531827Y270422D02*
G03X530506Y269634I44J-1575D01*
G01X531956Y270422D02*
X531827D01*
G01X533886Y271584D02*
G02X531956Y270422I-2015J1163D01*
G01X535192Y272371D02*
G03X533886Y271584I59J-1575D01*
G01X535321Y272371D02*
X535192D01*
G01X537266Y273534D02*
G02X535321Y272371I-2015J1162D01*
G01X538560Y274321D02*
G03X537266Y273534I71J-1574D01*
G01X538716Y274321D02*
X538560D01*
G01X540646Y275483D02*
G02X538716Y274321I-2015J1163D01*
G01X538690Y247772D02*
G03X539996Y248559I-59J1575D01*
G01X538561Y247772D02*
X538690D01*
G01X536616Y246609D02*
G02X538561Y247772I2015J-1162D01*
G01X535295Y245821D02*
G03X536616Y246609I-44J1575D01*
G01X535166Y245821D02*
X535295D01*
G01X533236Y244659D02*
G02X535166Y245821I2015J-1163D01*
G01X531930Y243872D02*
G03X533236Y244659I-59J1575D01*
G01X531812Y243872D02*
X531930D01*
G01X530506Y244659D02*
G03X531812Y243872I1365J788D01*
G01X528576Y245821D02*
G02X530506Y244659I-85J-2325D01*
G01X528447Y245821D02*
X528576D01*
G01X527126Y246609D02*
G03X528447Y245821I1365J787D01*
G01X525111Y249347D02*
G02X527126Y246609I-11227J-10372D01*
G01X512932Y242376D02*
G02X511592Y245447I11503J6847D01*
G01X512957Y242334D02*
X512932Y242376D01*
G01X512976Y242300D02*
X512957Y242334D01*
G01Y240759D02*
G03X512976Y242300I-1365J787D01*
G01X512932Y238476D02*
G02X512957Y240759I2040J1119D01*
G01Y238434D02*
X512932Y238476D01*
G01X512976Y238400D02*
X512957Y238434D01*
G01Y236859D02*
G03X512976Y238400I-1365J787D01*
G01X512957Y234533D02*
G02Y236859I2015J1163D01*
G01Y232959D02*
G03Y234533I-1365J787D01*
G01X512932Y232917D02*
X512957Y232959D01*
G01Y230634D02*
G02X512932Y232917I2015J1164D01*
G01X512976Y230600D02*
X512957Y230634D01*
G01Y229059D02*
G03X512976Y230600I-1365J787D01*
G01X512932Y226776D02*
G02X512957Y229059I2040J1119D01*
G01Y226734D02*
X512932Y226776D01*
G01X512976Y226700D02*
X512957Y226734D01*
G01Y225159D02*
G03X512976Y226700I-1365J787D01*
G01X512932Y222876D02*
G02X512957Y225159I2040J1119D01*
G01Y222834D02*
X512932Y222876D01*
G01X512976Y222800D02*
X512957Y222834D01*
G01Y221259D02*
G03X512976Y222800I-1365J787D01*
G01X520367Y246609D02*
G03X518352Y249347I-12362J-6987D01*
G01X520380Y246586D02*
X520367Y246609D01*
G01X521731Y245821D02*
G02X520380Y246586I0J1575D01*
G01X521816Y245821D02*
X521731D01*
G01X523746Y244659D02*
G03X521816Y245821I-2015J-1163D01*
G01X525052Y243872D02*
G02X523746Y244659I59J1575D01*
G01X525181Y243872D02*
X525052D01*
G01X527126Y242709D02*
G03X525181Y243872I-2015J-1162D01*
G01X528447Y241921D02*
G02X527126Y242709I44J1575D01*
G01X528576Y241921D02*
X528447D01*
G01X530506Y240759D02*
G03X528576Y241921I-2015J-1163D01*
G01X531812Y239972D02*
G02X530506Y240759I59J1575D01*
G01X531930Y239972D02*
X531812D01*
G01X533236Y240759D02*
G02X531930Y239972I-1365J788D01*
G01X533470Y241093D02*
G03X533236Y240759I1781J-1497D01*
G01X484797Y219309D02*
X484772Y219267D01*
G01X484816Y219343D02*
X484797Y219309D01*
G01Y220884D02*
G02X484816Y219343I-1365J-787D01*
G01X484772Y223167D02*
G03X484797Y220884I2040J-1119D01*
G01Y223209D02*
X484772Y223167D01*
G01X484816Y223243D02*
X484797Y223209D01*
G01Y224784D02*
G02X484816Y223243I-1365J-787D01*
G01X484772Y227067D02*
G03X484797Y224784I2040J-1119D01*
G01Y227109D02*
X484772Y227067D01*
G01X484816Y227143D02*
X484797Y227109D01*
G01Y228684D02*
G02X484816Y227143I-1365J-787D01*
G01X484797Y231010D02*
G03Y228684I2015J-1163D01*
G01Y232584D02*
G02Y231010I-1365J-787D01*
G01X484772Y232626D02*
X484797Y232584D01*
G01Y234909D02*
G03X484772Y232626I2015J-1164D01*
G01X484816Y234943D02*
X484797Y234909D01*
G01Y236484D02*
G02X484816Y234943I-1365J-787D01*
G01X484772Y238767D02*
G03X484797Y236484I2040J-1119D01*
G01Y238809D02*
X484772Y238767D01*
G01X484816Y238843D02*
X484797Y238809D01*
G01Y240384D02*
G02X484816Y238843I-1365J-787D01*
G01X484797Y242710D02*
G03Y240384I2017J-1163D01*
G01Y244284D02*
G02Y242710I-1365J-787D01*
G01X484680Y246380D02*
G03X484797Y244284I2132J-932D01*
G01X484586Y246731D02*
X484680Y246380D01*
G01X483432Y247396D02*
X484586Y246731D01*
G01X509577Y248184D02*
G02X508212Y251296I13451J7755D01*
G01X509596Y246643D02*
G03X509577Y248184I-1384J754D01*
G01Y246609D02*
X509596Y246643D01*
G01X509552Y246567D02*
X509577Y246609D01*
G01Y244284D02*
G02X509552Y246567I2015J1164D01*
G01X509596Y242743D02*
G03X509577Y244284I-1384J754D01*
G01Y242709D02*
X509596Y242743D01*
G01X509552Y242667D02*
X509577Y242709D01*
G01Y240384D02*
G02X509552Y242667I2015J1164D01*
G01X509596Y238843D02*
G03X509577Y240384I-1384J754D01*
G01Y238809D02*
X509596Y238843D01*
G01X509552Y238767D02*
X509577Y238809D01*
G01Y236484D02*
G02X509552Y238767I2015J1164D01*
G01X509596Y234943D02*
G03X509577Y236484I-1384J754D01*
G01Y234909D02*
X509596Y234943D01*
G01X509552Y232626D02*
G02X509577Y234909I2040J1119D01*
G01Y232584D02*
X509552Y232626D01*
G01X509577Y231010D02*
G03Y232584I-1365J787D01*
G01Y228684D02*
G02Y231010I2015J1163D01*
G01X509596Y227143D02*
G03X509577Y228684I-1384J754D01*
G01Y227109D02*
X509596Y227143D01*
G01X509552Y227067D02*
X509577Y227109D01*
G01Y224784D02*
G02X509552Y227067I2015J1164D01*
G01X509596Y223243D02*
G03X509577Y224784I-1384J754D01*
G01Y223209D02*
X509596Y223243D01*
G01X509552Y223167D02*
X509577Y223209D01*
G01Y220884D02*
G02X509552Y223167I2015J1164D01*
G01X509596Y219343D02*
G03X509577Y220884I-1384J754D01*
G01Y219309D02*
X509596Y219343D01*
G01X509552Y219267D02*
X509577Y219309D01*
G01X521661Y245071D02*
G02X518352Y245447I0J14748D01*
G01X521790Y245071D02*
X521661D01*
G01X523096Y244284D02*
G03X521790Y245071I-1365J-788D01*
G01X525026Y243122D02*
G02X523096Y244284I85J2325D01*
G01X525155Y243122D02*
X525026D01*
G01X526476Y242334D02*
G03X525155Y243122I-1365J-787D01*
G01X528421Y241171D02*
G02X526476Y242334I70J2325D01*
G01X528550Y241171D02*
X528421D01*
G01X529856Y240384D02*
G03X528550Y241171I-1365J-788D01*
G01X531786Y239222D02*
G02X529856Y240384I85J2325D01*
G01X531956Y239222D02*
X531786D01*
G01X532450Y239294D02*
G02X531956Y239222I-581J2253D01*
G01X533006Y239294D02*
X532450D01*
G01X485447Y218934D02*
X485428Y218900D01*
G01X485472Y218976D02*
X485447Y218934D01*
G01Y221259D02*
G02X485472Y218976I-2015J-1164D01*
G01X485428Y222800D02*
G03X485447Y221259I1384J-754D01*
G01Y222834D02*
X485428Y222800D01*
G01X485472Y222876D02*
X485447Y222834D01*
G01Y225159D02*
G02X485472Y222876I-2015J-1164D01*
G01X485428Y226700D02*
G03X485447Y225159I1384J-754D01*
G01Y226734D02*
X485428Y226700D01*
G01X485472Y226776D02*
X485447Y226734D01*
G01Y229059D02*
G02X485472Y226776I-2015J-1164D01*
G01X485428Y230600D02*
G03X485447Y229059I1384J-754D01*
G01Y230634D02*
X485428Y230600D01*
G01X485472Y232917D02*
G02X485447Y230634I-2040J-1119D01*
G01Y232959D02*
X485472Y232917D01*
G01X485447Y234533D02*
G03Y232959I1365J-787D01*
G01Y236859D02*
G02Y234533I-2015J-1163D01*
G01X485428Y238400D02*
G03X485447Y236859I1384J-754D01*
G01Y238434D02*
X485428Y238400D01*
G01X485472Y238476D02*
X485447Y238434D01*
G01Y240759D02*
G02X485472Y238476I-2015J-1164D01*
G01X485447Y242334D02*
G03Y240759I1364J-787D01*
G01Y244660D02*
G02Y242334I-2015J-1163D01*
G01Y246234D02*
G03Y244660I1365J-787D01*
G01Y248560D02*
G02Y246234I-2015J-1163D01*
G01X484984Y251027D02*
G03X485447Y248560I3741J-575D01*
G01X484797Y252084D02*
G02X484984Y251027I-1365J-787D01*
G01X483432Y255196D02*
X484797Y252084D01*
G01X538716Y266522D02*
G03X540646Y267684I-85J2325D01*
G01X538587Y266522D02*
X538716D01*
G01X537266Y265734D02*
G02X538587Y266522I1365J-787D01*
G01X535321Y264571D02*
G03X537266Y265734I-70J2325D01*
G01X535192Y264571D02*
X535321D01*
G01X533886Y263784D02*
G02X535192Y264571I1365J-788D01*
G01X531956Y262622D02*
G03X533886Y263784I-85J2325D01*
G01X531827Y262622D02*
X531956D01*
G01X530506Y261834D02*
G02X531827Y262622I1365J-787D01*
G01X528561Y260671D02*
G03X530506Y261834I-70J2325D01*
G01X528432Y260671D02*
X528561D01*
G01X527126Y259884D02*
G02X528432Y260671I1365J-788D01*
G01X525196Y258722D02*
G03X527126Y259884I-85J2325D01*
G01X525026Y258722D02*
X525196D01*
G01X523096Y259884D02*
G03X525026Y258722I2015J1163D01*
G01X521790Y260671D02*
G02X523096Y259884I-59J-1575D01*
G01X521661Y260671D02*
X521790D01*
G01X519716Y261834D02*
G03X521661Y260671I2015J1162D01*
G01X519703Y261857D02*
X519716Y261834D01*
G01X518352Y262622D02*
G02X519703Y261857I0J-1575D01*
G01X517122Y262622D02*
X518352D01*
G01X515381Y260881D02*
X517122Y262622D01*
G01X513857Y260881D02*
X515381D01*
G01X538716Y250922D02*
G03X540646Y252084I-85J2325D01*
G01X538587Y250922D02*
X538716D01*
G01X537266Y250134D02*
G02X538587Y250922I1365J-787D01*
G01X535321Y248971D02*
G03X537266Y250134I-70J2325D01*
G01X535192Y248971D02*
X535321D01*
G01X533886Y248184D02*
G02X535192Y248971I1365J-788D01*
G01X531956Y247022D02*
G03X533886Y248184I-85J2325D01*
G01X531786Y247022D02*
X531956D01*
G01X529856Y248184D02*
G03X531786Y247022I2015J1163D01*
G01X528550Y248971D02*
G02X529856Y248184I-59J-1575D01*
G01X528421Y248971D02*
X528550D01*
G01X526476Y250134D02*
G03X528421Y248971I2015J1162D01*
G01X525155Y250922D02*
G02X526476Y250134I-44J-1575D01*
G01X525067Y250922D02*
X525155D01*
G01X523746Y250134D02*
G02X525067Y250922I1365J-787D01*
G01X521801Y248971D02*
G03X523746Y250134I-70J2325D01*
G01X521661Y248971D02*
X521801D01*
G01X519716Y250134D02*
G03X521661Y248971I2015J1162D01*
G01X519703Y250157D02*
X519716Y250134D01*
G01X518352Y250922D02*
G02X519703Y250157I0J-1575D01*
G01X518308Y250922D02*
X518352D01*
G01X516987Y250134D02*
G02X518308Y250922I1365J-787D01*
G01X486356Y329300D02*
X484552Y327347D01*
G01X487873Y330871D02*
G03X486356Y329300I59J-1575D01*
G01X488002Y330871D02*
X487873D01*
G01X489947Y332034D02*
G02X488002Y330871I-2015J1162D01*
G01X491268Y332822D02*
G03X489947Y332034I44J-1575D01*
G01X491397Y332822D02*
X491268D01*
G01X493327Y333984D02*
G02X491397Y332822I-2015J1163D01*
G01X494633Y334771D02*
G03X493327Y333984I59J-1575D01*
G01X494762Y334771D02*
X494633D01*
G01X496707Y335934D02*
G02X494762Y334771I-2015J1162D01*
G01X498028Y336722D02*
G03X496707Y335934I44J-1575D01*
G01X498157Y336722D02*
X498028D01*
G01X500087Y337884D02*
G02X498157Y336722I-2015J1163D01*
G01X501393Y338671D02*
G03X500087Y337884I59J-1575D01*
G01X501522Y338671D02*
X501393D01*
G01X503467Y339834D02*
G02X501522Y338671I-2015J1162D01*
G01X504788Y340622D02*
G03X503467Y339834I44J-1575D01*
G01X504917Y340622D02*
X504788D01*
G01X506847Y341784D02*
G02X504917Y340622I-2015J1163D01*
G01X482800Y336400D02*
X483600Y337200D01*
G01X482800Y332859D02*
Y336400D01*
G01X482512Y332367D02*
X482800Y332859D01*
G01X482537Y330084D02*
G02X482512Y332367I2015J1164D01*
G01X482636Y328715D02*
G03X482537Y330084I-1465J582D01*
G01X482420Y328280D02*
X482636Y328715D01*
G01X484501Y325021D02*
G02X482420Y328280I51J2326D01*
G01X484596Y325021D02*
X484501D01*
G01X485917Y324233D02*
G03X484596Y325021I-1365J-787D01*
G01X486200Y323700D02*
X485917Y324233D01*
G01X487932Y321496D02*
X486200Y323700D01*
G01X491312Y325021D02*
G02X487932Y325396I0J15420D01*
G01X491363Y325021D02*
X491312D01*
G01X493327Y326184D02*
G02X491363Y325021I-2015J1163D01*
G01X494633Y326971D02*
G03X493327Y326184I59J-1575D01*
G01X494762Y326971D02*
X494633D01*
G01X496707Y328134D02*
G02X494762Y326971I-2015J1162D01*
G01X498028Y328922D02*
G03X496707Y328134I44J-1575D01*
G01X498157Y328922D02*
X498028D01*
G01X500087Y330084D02*
G02X498157Y328922I-2015J1163D01*
G01X501393Y330871D02*
G03X500087Y330084I59J-1575D01*
G01X501522Y330871D02*
X501393D01*
G01X503467Y332034D02*
G02X501522Y330871I-2015J1162D01*
G01X504788Y332822D02*
G03X503467Y332034I44J-1575D01*
G01X504917Y332822D02*
X504788D01*
G01X506847Y333984D02*
G02X504917Y332822I-2015J1163D01*
G01X508153Y334771D02*
G03X506847Y333984I59J-1575D01*
G01X508282Y334771D02*
X508153D01*
G01X510227Y335934D02*
G02X508282Y334771I-2015J1162D01*
G01X511548Y336722D02*
G03X510227Y335934I44J-1575D01*
G01X511677Y336722D02*
X511548D01*
G01X513607Y337884D02*
G02X511677Y336722I-2015J1163D01*
G01X514913Y338671D02*
G03X513607Y337884I59J-1575D01*
G01X515042Y338671D02*
X514913D01*
G01X516987Y339834D02*
G02X515042Y338671I-2015J1162D01*
G01X518308Y340622D02*
G03X516987Y339834I44J-1575D01*
G01X518450Y340622D02*
X518308D01*
G01X520367Y341783D02*
G02X518450Y340622I-2015J1164D01*
G01X481314Y284071D02*
X484552Y284447D01*
G01X481102Y284071D02*
X481314D01*
G01X479157Y285234D02*
G03X481102Y284071I2015J1162D01*
G01X511677Y340622D02*
G03X513607Y341784I-85J2325D01*
G01X511548Y340622D02*
X511677D01*
G01X510227Y339834D02*
G02X511548Y340622I1365J-787D01*
G01X508282Y338671D02*
G03X510227Y339834I-70J2325D01*
G01X508153Y338671D02*
X508282D01*
G01X506847Y337884D02*
G02X508153Y338671I1365J-788D01*
G01X504917Y336722D02*
G03X506847Y337884I-85J2325D01*
G01X504788Y336722D02*
X504917D01*
G01X503467Y335934D02*
G02X504788Y336722I1365J-787D01*
G01X501522Y334771D02*
G03X503467Y335934I-70J2325D01*
G01X501393Y334771D02*
X501522D01*
G01X500087Y333984D02*
G02X501393Y334771I1365J-788D01*
G01X498157Y332822D02*
G03X500087Y333984I-85J2325D01*
G01X498028Y332822D02*
X498157D01*
G01X496707Y332034D02*
G02X498028Y332822I1365J-787D01*
G01X494762Y330871D02*
G03X496707Y332034I-70J2325D01*
G01X494633Y330871D02*
X494762D01*
G01X493327Y330084D02*
G02X494633Y330871I1365J-788D01*
G01X491397Y328922D02*
G03X493327Y330084I-85J2325D01*
G01X491268Y328922D02*
X491397D01*
G01X489947Y328134D02*
G02X491268Y328922I1365J-787D01*
G01X488002Y326971D02*
G03X489947Y328134I-70J2325D01*
G01X487873Y326971D02*
X488002D01*
G01X486567Y326184D02*
G02X487873Y326971I1365J-788D01*
G01X486548Y324643D02*
G02X486567Y326184I1384J754D01*
G01Y324609D02*
X486548Y324643D01*
G01X487888Y323821D02*
G02X486567Y324609I44J1575D01*
G01X491312Y323446D02*
G03X487888Y323821I-3424J-15444D01*
G01X479132Y402276D02*
G02X479157Y404559I2040J1119D01*
G01Y402234D02*
X479132Y402276D01*
G01X479176Y402200D02*
X479157Y402234D01*
G01Y400659D02*
G03X479176Y402200I-1365J787D01*
G01X479132Y398376D02*
G02X479157Y400659I2040J1119D01*
G01Y398334D02*
X479132Y398376D01*
G01X479176Y398300D02*
X479157Y398334D01*
G01Y396759D02*
G03X479176Y398300I-1365J787D01*
G01X479132Y394476D02*
G02X479157Y396759I2040J1119D01*
G01Y394434D02*
X479132Y394476D01*
G01X479176Y394400D02*
X479157Y394434D01*
G01Y392859D02*
G03X479176Y394400I-1365J787D01*
G01X479132Y390576D02*
G02X479157Y392859I2040J1119D01*
G01Y390534D02*
X479132Y390576D01*
G01X479176Y390500D02*
X479157Y390534D01*
G01X479261Y389175D02*
G03X479176Y390500I-1469J571D01*
G01X479157Y388962D02*
G03X479261Y389175I-1221J728D01*
G01X479157Y386636D02*
G02Y388962I2015J1163D01*
G01Y385062D02*
G03Y386636I-1365J787D01*
G01X481113Y342571D02*
G03X479807Y341784I59J-1575D01*
G01X481242Y342571D02*
X481113D01*
G01X483187Y343734D02*
G02X481242Y342571I-2015J1162D01*
G01X484508Y344522D02*
G03X483187Y343734I44J-1575D01*
G01X484637Y344522D02*
X484508D01*
G01X486567Y345684D02*
G02X484637Y344522I-2015J1163D01*
G01X487873Y346471D02*
G03X486567Y345684I59J-1575D01*
G01X488002Y346471D02*
X487873D01*
G01X489947Y347634D02*
G02X488002Y346471I-2015J1162D01*
G01X491268Y348422D02*
G03X489947Y347634I44J-1575D01*
G01X491397Y348422D02*
X491268D01*
G01X493327Y349584D02*
G02X491397Y348422I-2015J1163D01*
G01X494633Y350371D02*
G03X493327Y349584I59J-1575D01*
G01X494762Y350371D02*
X494633D01*
G01X496707Y351534D02*
G02X494762Y350371I-2015J1162D01*
G01X498028Y352322D02*
G03X496707Y351534I44J-1575D01*
G01X498157Y352322D02*
X498028D01*
G01X500087Y353484D02*
G02X498157Y352322I-2015J1163D01*
G01X501393Y354271D02*
G03X500087Y353484I59J-1575D01*
G01X501522Y354271D02*
X501393D01*
G01X503467Y355434D02*
G02X501522Y354271I-2015J1162D01*
G01X504788Y356222D02*
G03X503467Y355434I44J-1575D01*
G01X504917Y356222D02*
X504788D01*
G01X506847Y357384D02*
G02X504917Y356222I-2015J1163D01*
G01X508153Y358171D02*
G03X506847Y357384I59J-1575D01*
G01X508282Y358171D02*
X508153D01*
G01X510227Y359334D02*
G02X508282Y358171I-2015J1162D01*
G01X511548Y360122D02*
G03X510227Y359334I44J-1575D01*
G01X511677Y360122D02*
X511548D01*
G01X513607Y361284D02*
G02X511677Y360122I-2015J1163D01*
G01X514913Y362071D02*
G03X513607Y361284I59J-1575D01*
G01X515042Y362071D02*
X514913D01*
G01X516987Y363234D02*
G02X515042Y362071I-2015J1162D01*
G01X518308Y364022D02*
G03X516987Y363234I44J-1575D01*
G01X518450Y364022D02*
X518308D01*
G01X520367Y365183D02*
G02X518450Y364022I-2015J1164D01*
G01X520380Y365206D02*
X520367Y365183D01*
G01X521731Y365971D02*
G03X520380Y365206I0J-1575D01*
G01X521801Y365971D02*
X521731D01*
G01X523746Y367134D02*
G02X521801Y365971I-2015J1162D01*
G01X525067Y367922D02*
G03X523746Y367134I44J-1575D01*
G01X525196Y367922D02*
X525067D01*
G01X527126Y369084D02*
G02X525196Y367922I-2015J1163D01*
G01X528432Y369871D02*
G03X527126Y369084I59J-1575D01*
G01X528542Y369871D02*
X528432D01*
G01X530506Y371034D02*
G02X528542Y369871I-2015J1163D01*
G01X531800Y371821D02*
G03X530506Y371034I71J-1574D01*
G01X531941Y371821D02*
X531800D01*
G01X533886Y372984D02*
G02X531941Y371821I-2015J1162D01*
G01X535180Y373771D02*
G03X533886Y372984I71J-1574D01*
G01X535336Y373771D02*
X535180D01*
G01X537266Y374933D02*
G02X535336Y373771I-2015J1163D01*
G01X538587Y375721D02*
G03X537266Y374933I44J-1575D01*
G01X538682Y375721D02*
X538587D01*
G01X540646Y376884D02*
G02X538682Y375721I-2015J1163D01*
G01X496707Y402233D02*
G02X497665Y402968I1365J-787D01*
G01X494777Y401071D02*
G03X496707Y402233I-85J2325D01*
G01X494633Y401071D02*
X494777D01*
G01X493308Y398743D02*
G02X494633Y401071I1384J753D01*
G01X493327Y398709D02*
X493308Y398743D01*
G01X493352Y396426D02*
G03X493327Y398709I-2040J1119D01*
G01Y396384D02*
X493352Y396426D01*
G01X493327Y394810D02*
G02Y396384I1365J787D01*
G01Y392484D02*
G03Y394810I-2015J1163D01*
G01X493308Y390943D02*
G02X493327Y392484I1384J754D01*
G01Y390909D02*
X493308Y390943D01*
G01X493352Y390867D02*
X493327Y390909D01*
G01Y388584D02*
G03X493352Y390867I-2015J1164D01*
G01X493308Y387043D02*
G02X493327Y388584I1384J754D01*
G01Y387009D02*
X493308Y387043D01*
G01X493327Y384686D02*
G03Y387009I-2015J1161D01*
G01Y383112D02*
G02Y384686I1365J787D01*
G01X493352Y380827D02*
G03X493327Y383112I-2045J1120D01*
G01Y380785D02*
X493352Y380827D01*
G01X493308Y380751D02*
X493327Y380785D01*
G01Y379210D02*
G02X493308Y380751I1365J787D01*
G01X491397Y375722D02*
G03X493327Y379210I-85J2325D01*
G01X491268Y375721D02*
G03X491397Y375722I47J2240D01*
G01X489947Y374933D02*
G02X491268Y375721I1365J-787D01*
G01X488017Y373771D02*
G03X489947Y374933I-85J2325D01*
G01X487861Y373771D02*
X488017D01*
G01X486567Y372984D02*
G02X487861Y373771I1365J-787D01*
G01X484622Y371821D02*
G03X486567Y372984I-70J2325D01*
G01X484481Y371821D02*
X484622D01*
G01X483187Y371034D02*
G02X484481Y371821I1365J-787D01*
G01X481223Y369871D02*
G03X483187Y371034I-51J2326D01*
G01X481113Y369871D02*
X481223D01*
G01X479807Y369084D02*
G02X481113Y369871I1365J-788D01*
G01X508153Y342571D02*
G03X506847Y341784I59J-1575D01*
G01X508282Y342571D02*
X508153D01*
G01X510227Y343734D02*
G02X508282Y342571I-2015J1162D01*
G01X511548Y344522D02*
G03X510227Y343734I44J-1575D01*
G01X511677Y344522D02*
X511548D01*
G01X513607Y345684D02*
G02X511677Y344522I-2015J1163D01*
G01X514913Y346471D02*
G03X513607Y345684I59J-1575D01*
G01X515042Y346471D02*
X514913D01*
G01X516987Y347634D02*
G02X515042Y346471I-2015J1162D01*
G01X518308Y348422D02*
G03X516987Y347634I44J-1575D01*
G01X518450Y348422D02*
X518308D01*
G01X520367Y349583D02*
G02X518450Y348422I-2015J1164D01*
G01X520380Y349606D02*
X520367Y349583D01*
G01X521731Y350371D02*
G03X520380Y349606I0J-1575D01*
G01X521801Y350371D02*
X521731D01*
G01X523746Y351534D02*
G02X521801Y350371I-2015J1162D01*
G01X525067Y352322D02*
G03X523746Y351534I44J-1575D01*
G01X525196Y352322D02*
X525067D01*
G01X527126Y353484D02*
G02X525196Y352322I-2015J1163D01*
G01X528432Y354271D02*
G03X527126Y353484I59J-1575D01*
G01X528561Y354271D02*
X528432D01*
G01X530506Y355434D02*
G02X528561Y354271I-2015J1162D01*
G01X531827Y356222D02*
G03X530506Y355434I44J-1575D01*
G01X531956Y356222D02*
X531827D01*
G01X533886Y357384D02*
G02X531956Y356222I-2015J1163D01*
G01X535192Y358171D02*
G03X533886Y357384I59J-1575D01*
G01X535321Y358171D02*
X535192D01*
G01X537266Y359334D02*
G02X535321Y358171I-2015J1162D01*
G01X538587Y360122D02*
G03X537266Y359334I44J-1575D01*
G01X538716Y360122D02*
X538587D01*
G01X540646Y361284D02*
G02X538716Y360122I-2015J1163D01*
G01X538690Y376472D02*
G03X539996Y377259I-59J1575D01*
G01X538580Y376472D02*
X538690D01*
G01X536616Y375309D02*
G02X538580Y376472I2015J-1163D01*
G01X535322Y374522D02*
G03X536616Y375309I-71J1574D01*
G01X535181Y374522D02*
X535322D01*
G01X533236Y373359D02*
G02X535181Y374522I2015J-1162D01*
G01X531942Y372572D02*
G03X533236Y373359I-71J1574D01*
G01X531786Y372572D02*
X531942D01*
G01X529856Y371410D02*
G02X531786Y372572I2015J-1163D01*
G01X528535Y370622D02*
G03X529856Y371410I-44J1575D01*
G01X528440Y370622D02*
X528535D01*
G01X526476Y369459D02*
G02X528440Y370622I2015J-1163D01*
G01X525170Y368672D02*
G03X526476Y369459I-59J1575D01*
G01X525041Y368672D02*
X525170D01*
G01X523096Y367509D02*
G02X525041Y368672I2015J-1162D01*
G01X521775Y366721D02*
G03X523096Y367509I-44J1575D01*
G01X521633Y366721D02*
X521775D01*
G01X519716Y365560D02*
G02X521633Y366721I2015J-1164D01*
G01X519703Y365537D02*
X519716Y365560D01*
G01X518352Y364772D02*
G03X519703Y365537I0J1575D01*
G01X518282Y364772D02*
X518352D01*
G01X516337Y363609D02*
G02X518282Y364772I2015J-1162D01*
G01X515016Y362821D02*
G03X516337Y363609I-44J1575D01*
G01X514887Y362821D02*
X515016D01*
G01X512957Y361659D02*
G02X514887Y362821I2015J-1163D01*
G01X511651Y360872D02*
G03X512957Y361659I-59J1575D01*
G01X511522Y360872D02*
X511651D01*
G01X509577Y359709D02*
G02X511522Y360872I2015J-1162D01*
G01X508256Y358921D02*
G03X509577Y359709I-44J1575D01*
G01X508127Y358921D02*
X508256D01*
G01X506197Y357759D02*
G02X508127Y358921I2015J-1163D01*
G01X504891Y356972D02*
G03X506197Y357759I-59J1575D01*
G01X504762Y356972D02*
X504891D01*
G01X502817Y355809D02*
G02X504762Y356972I2015J-1162D01*
G01X501496Y355021D02*
G03X502817Y355809I-44J1575D01*
G01X501367Y355021D02*
X501496D01*
G01X499437Y353859D02*
G02X501367Y355021I2015J-1163D01*
G01X498131Y353072D02*
G03X499437Y353859I-59J1575D01*
G01X498002Y353072D02*
X498131D01*
G01X496057Y351909D02*
G02X498002Y353072I2015J-1162D01*
G01X494736Y351121D02*
G03X496057Y351909I-44J1575D01*
G01X494607Y351121D02*
X494736D01*
G01X492677Y349959D02*
G02X494607Y351121I2015J-1163D01*
G01X491371Y349172D02*
G03X492677Y349959I-59J1575D01*
G01X491242Y349172D02*
X491371D01*
G01X489297Y348009D02*
G02X491242Y349172I2015J-1162D01*
G01X487976Y347221D02*
G03X489297Y348009I-44J1575D01*
G01X487847Y347221D02*
X487976D01*
G01X485917Y346059D02*
G02X487847Y347221I2015J-1163D01*
G01X484611Y345272D02*
G03X485917Y346059I-59J1575D01*
G01X484482Y345272D02*
X484611D01*
G01X482537Y344109D02*
G02X484482Y345272I2015J-1162D01*
G01X481216Y343321D02*
G03X482537Y344109I-44J1575D01*
G01X481087Y343321D02*
X481216D01*
G01X479157Y342159D02*
G02X481087Y343321I2015J-1163D01*
G01X479788Y402643D02*
G02X479807Y404184I1384J754D01*
G01Y402609D02*
X479788Y402643D01*
G01X479832Y402567D02*
X479807Y402609D01*
G01Y400284D02*
G03X479832Y402567I-2015J1164D01*
G01X479788Y398743D02*
G02X479807Y400284I1384J754D01*
G01Y398709D02*
X479788Y398743D01*
G01X479832Y398667D02*
X479807Y398709D01*
G01Y396384D02*
G03X479832Y398667I-2015J1164D01*
G01X479788Y394843D02*
G02X479807Y396384I1384J754D01*
G01Y394809D02*
X479788Y394843D01*
G01X479832Y394767D02*
X479807Y394809D01*
G01Y392484D02*
G03X479832Y394767I-2015J1164D01*
G01X479788Y390943D02*
G02X479807Y392484I1384J754D01*
G01Y390909D02*
X479788Y390943D01*
G01X479832Y390867D02*
X479807Y390909D01*
G01X479881Y388723D02*
G03X479832Y390867I-2089J1025D01*
G01X479807Y388586D02*
G03X479881Y388723I-2430J1401D01*
G01X479807Y387012D02*
G02Y388586I1365J787D01*
G01Y384686D02*
G03Y387012I-2015J1163D01*
G01X502363Y402308D02*
Y404889D01*
G01X501877Y401822D02*
X502363Y402308D01*
G01X501382Y401822D02*
X501877D01*
G01X499437Y400659D02*
G02X501382Y401822I2015J-1162D01*
G01X498116Y399871D02*
G03X499437Y400659I-44J1575D01*
G01X497987Y399871D02*
X498116D01*
G01X496032Y396426D02*
G02X497987Y399871I2040J1120D01*
G01X496057Y396384D02*
X496032Y396426D01*
G01X496057Y394810D02*
G03Y396384I-1365J787D01*
G01Y392484D02*
G02Y394810I2015J1163D01*
G01X496076Y390943D02*
G03X496057Y392484I-1384J754D01*
G01Y388586D02*
G02X496076Y390943I2016J1162D01*
G01X496057Y387012D02*
G03Y388586I-1365J787D01*
G01Y384686D02*
G02Y387012I2015J1163D01*
G01Y383112D02*
G03Y384686I-1365J787D01*
G01Y380786D02*
G02Y383112I2015J1163D01*
G01Y379209D02*
G03Y380786I-1366J788D01*
G01X496032Y379167D02*
X496057Y379209D01*
G01Y376884D02*
G02X496032Y379167I2015J1164D01*
G01X494763Y374522D02*
G03X496057Y376884I-71J1574D01*
G01X494622Y374522D02*
X494763D01*
G01X492677Y373359D02*
G02X494622Y374522I2015J-1162D01*
G01X491383Y372572D02*
G03X492677Y373359I-71J1574D01*
G01X491227Y372572D02*
X491383D01*
G01X489297Y371410D02*
G02X491227Y372572I2015J-1163D01*
G01X487976Y370622D02*
G03X489297Y371410I-44J1575D01*
G01X487881Y370622D02*
X487976D01*
G01X485917Y369459D02*
G02X487881Y370622I2015J-1163D01*
G01X484611Y368672D02*
G03X485917Y369459I-59J1575D01*
G01X484482Y368672D02*
X484611D01*
G01X482537Y367509D02*
G02X484482Y368672I2015J-1162D01*
G01X481216Y366721D02*
G03X482537Y367509I-44J1575D01*
G01X481087Y366721D02*
X481216D01*
G01X479157Y365559D02*
G02X481087Y366721I2015J-1163D01*
G01X520380Y341806D02*
X520367Y341783D01*
G01X521731Y342571D02*
G03X520380Y341806I0J-1575D01*
G01X521801Y342571D02*
X521731D01*
G01X523746Y343734D02*
G02X521801Y342571I-2015J1162D01*
G01X525067Y344522D02*
G03X523746Y343734I44J-1575D01*
G01X525196Y344522D02*
X525067D01*
G01X527126Y345684D02*
G02X525196Y344522I-2015J1163D01*
G01X528432Y346471D02*
G03X527126Y345684I59J-1575D01*
G01X528561Y346471D02*
X528432D01*
G01X530506Y347634D02*
G02X528561Y346471I-2015J1162D01*
G01X531827Y348422D02*
G03X530506Y347634I44J-1575D01*
G01X531956Y348422D02*
X531827D01*
G01X533886Y349584D02*
G02X531956Y348422I-2015J1163D01*
G01X535192Y350371D02*
G03X533886Y349584I59J-1575D01*
G01X535321Y350371D02*
X535192D01*
G01X537266Y351534D02*
G02X535321Y350371I-2015J1162D01*
G01X538587Y352322D02*
G03X537266Y351534I44J-1575D01*
G01X538716Y352322D02*
X538587D01*
G01X540646Y353484D02*
G02X538716Y352322I-2015J1163D01*
G01X482556Y402643D02*
G03X482537Y404184I-1384J754D01*
G01Y402609D02*
X482556Y402643D01*
G01X482512Y402567D02*
X482537Y402609D01*
G01Y400284D02*
G02X482512Y402567I2015J1164D01*
G01X482556Y398743D02*
G03X482537Y400284I-1384J754D01*
G01Y398709D02*
X482556Y398743D01*
G01X482512Y398667D02*
X482537Y398709D01*
G01Y396384D02*
G02X482512Y398667I2015J1164D01*
G01X482556Y394843D02*
G03X482537Y396384I-1384J754D01*
G01Y394809D02*
X482556Y394843D01*
G01X482512Y394767D02*
X482537Y394809D01*
G01Y392484D02*
G02X482512Y394767I2015J1164D01*
G01X482556Y390943D02*
G03X482537Y392484I-1384J754D01*
G01Y390909D02*
X482556Y390943D01*
G01X482512Y390867D02*
X482537Y390909D01*
G01Y388584D02*
G02X482512Y390867I2015J1164D01*
G01X482537Y387012D02*
G03Y388584I-1362J786D01*
G01Y384684D02*
G02Y387012I2017J1164D01*
G01X481216Y382321D02*
G03X482537Y384684I-44J1575D01*
G01X481087Y382321D02*
X481216D01*
G01X479157Y381159D02*
G02X481087Y382321I2015J-1163D01*
G01X483212Y402276D02*
G03X483187Y404559I-2040J1119D01*
G01Y402234D02*
X483212Y402276D01*
G01X483168Y402200D02*
X483187Y402234D01*
G01Y400659D02*
G02X483168Y402200I1365J787D01*
G01X483212Y398376D02*
G03X483187Y400659I-2040J1119D01*
G01Y398334D02*
X483212Y398376D01*
G01X483168Y398300D02*
X483187Y398334D01*
G01Y396759D02*
G02X483168Y398300I1365J787D01*
G01X483212Y394476D02*
G03X483187Y396759I-2040J1119D01*
G01Y394434D02*
X483212Y394476D01*
G01X483168Y394400D02*
X483187Y394434D01*
G01Y392859D02*
G02X483168Y394400I1365J787D01*
G01X483212Y390576D02*
G03X483187Y392859I-2040J1119D01*
G01Y390534D02*
X483212Y390576D01*
G01X483168Y390500D02*
X483187Y390534D01*
G01Y388959D02*
G02X483168Y390500I1365J787D01*
G01X483187Y386636D02*
G03Y388959I-2015J1161D01*
G01Y385059D02*
G02Y386636I1368J788D01*
G01X481242Y381571D02*
G03X483187Y385059I-70J2325D01*
G01X481113Y381571D02*
X481242D01*
G01X479807Y380784D02*
G02X481113Y381571I1365J-788D01*
G01X503113Y401997D02*
Y404578D01*
G01X502188Y401072D02*
X503113Y401997D01*
G01X501408Y401072D02*
X502188D01*
G01X500087Y400284D02*
G02X501408Y401072I1365J-787D01*
G01X498142Y399121D02*
G03X500087Y400284I-70J2325D01*
G01X498028Y399121D02*
X498142D01*
G01X496707Y396759D02*
G02X498028Y399121I1365J787D01*
G01X496732Y396717D02*
X496707Y396759D01*
G01Y394434D02*
G03X496732Y396717I-2015J1164D01*
G01X496688Y394400D02*
X496707Y394434D01*
G01Y392859D02*
G02X496688Y394400I1365J787D01*
G01X496732Y390576D02*
G03X496707Y392859I-2040J1119D01*
G01Y390534D02*
X496732Y390576D01*
G01X496707Y388962D02*
G02Y390534I1362J786D01*
G01Y386636D02*
G03Y388962I-2015J1163D01*
G01Y385062D02*
G02Y386636I1365J787D01*
G01Y382736D02*
G03Y385062I-2015J1163D01*
G01Y381162D02*
G02Y382736I1365J787D01*
G01X496732Y378876D02*
G03X496707Y381162I-2046J1121D01*
G01Y378834D02*
X496732Y378876D01*
G01X496688Y378800D02*
X496707Y378834D01*
G01Y377259D02*
G02X496688Y378800I1365J787D01*
G01X494777Y373771D02*
G03X496707Y377259I-85J2325D01*
G01X494621Y373771D02*
X494777D01*
G01X493327Y372984D02*
G02X494621Y373771I1365J-787D01*
G01X491382Y371821D02*
G03X493327Y372984I-70J2325D01*
G01X491241Y371821D02*
X491382D01*
G01X489947Y371034D02*
G02X491241Y371821I1365J-787D01*
G01X487983Y369871D02*
G03X489947Y371034I-51J2326D01*
G01X487873Y369871D02*
X487983D01*
G01X486567Y369084D02*
G02X487873Y369871I1365J-788D01*
G01X484637Y367922D02*
G03X486567Y369084I-85J2325D01*
G01X484508Y367922D02*
X484637D01*
G01X483187Y367134D02*
G02X484508Y367922I1365J-787D01*
G01X481242Y365971D02*
G03X483187Y367134I-70J2325D01*
G01X481113Y365971D02*
X481242D01*
G01X479807Y365184D02*
G02X481113Y365971I1365J-788D01*
G01X496057Y402609D02*
G02X497987Y403771I2015J-1163D01*
G01X494736Y401821D02*
G03X496057Y402609I-44J1575D01*
G01X494607Y401821D02*
X494736D01*
G01X492677Y398333D02*
G02X494607Y401821I2015J1163D01*
G01X492677Y396759D02*
G03Y398333I-1365J787D01*
G01X492652Y396717D02*
X492677Y396759D01*
G01Y394434D02*
G02X492652Y396717I2015J1164D01*
G01X492696Y394400D02*
X492677Y394434D01*
G01Y392859D02*
G03X492696Y394400I-1365J787D01*
G01X492652Y390576D02*
G02X492677Y392859I2040J1119D01*
G01Y390534D02*
X492652Y390576D01*
G01X492696Y390500D02*
X492677Y390534D01*
G01Y388959D02*
G03X492696Y390500I-1365J787D01*
G01X492652Y386676D02*
G02X492677Y388959I2040J1119D01*
G01Y385062D02*
G03X492652Y386676I-1362J786D01*
G01X492677Y382736D02*
G02Y385062I2015J1163D01*
G01X492696Y381194D02*
G03X492677Y382736I-1384J754D01*
G01Y381160D02*
X492696Y381194D01*
G01X492652Y381118D02*
X492677Y381160D01*
G01Y378835D02*
G02X492652Y381118I2015J1164D01*
G01X491383Y376473D02*
G03X492677Y378835I-71J1574D01*
G01X491242Y376473D02*
G03X491383I70J1563D01*
G01X489297Y375309D02*
G02X491242Y376473I2017J-1163D01*
G01X488003Y374522D02*
G03X489297Y375309I-71J1574D01*
G01X487862Y374522D02*
X488003D01*
G01X485917Y373359D02*
G02X487862Y374522I2015J-1162D01*
G01X484623Y372572D02*
G03X485917Y373359I-71J1574D01*
G01X484467Y372572D02*
X484623D01*
G01X482537Y371410D02*
G02X484467Y372572I2015J-1163D01*
G01X481216Y370622D02*
G03X482537Y371410I-44J1575D01*
G01X481121Y370622D02*
X481216D01*
G01X479157Y369459D02*
G02X481121Y370622I2015J-1163D01*
G01X538716Y356222D02*
G03X540646Y357384I-85J2325D01*
G01X538587Y356222D02*
X538716D01*
G01X537266Y355434D02*
G02X538587Y356222I1365J-787D01*
G01X535321Y354271D02*
G03X537266Y355434I-70J2325D01*
G01X535192Y354271D02*
X535321D01*
G01X533886Y353484D02*
G02X535192Y354271I1365J-788D01*
G01X531956Y352322D02*
G03X533886Y353484I-85J2325D01*
G01X531827Y352322D02*
X531956D01*
G01X530506Y351534D02*
G02X531827Y352322I1365J-787D01*
G01X528561Y350371D02*
G03X530506Y351534I-70J2325D01*
G01X528432Y350371D02*
X528561D01*
G01X527126Y349584D02*
G02X528432Y350371I1365J-788D01*
G01X525196Y348422D02*
G03X527126Y349584I-85J2325D01*
G01X525067Y348422D02*
X525196D01*
G01X523746Y347634D02*
G02X525067Y348422I1365J-787D01*
G01X521801Y346471D02*
G03X523746Y347634I-70J2325D01*
G01X521731Y346471D02*
X521801D01*
G01X520380Y345706D02*
G02X521731Y346471I1351J-810D01*
G01X520367Y345683D02*
X520380Y345706D01*
G01X518450Y344522D02*
G03X520367Y345683I-98J2325D01*
G01X518308Y344522D02*
X518450D01*
G01X516987Y343734D02*
G02X518308Y344522I1365J-787D01*
G01X515042Y342571D02*
G03X516987Y343734I-70J2325D01*
G01X514913Y342571D02*
X515042D01*
G01X513607Y341784D02*
G02X514913Y342571I1365J-788D01*
G01X482092Y413643D02*
X481148Y414587D01*
G01X482092Y412429D02*
Y413643D01*
G01X482537Y411984D02*
X482092Y412429D01*
G01X481216Y409621D02*
G03X482537Y411984I-44J1575D01*
G01X481087Y409621D02*
X481216D01*
G01X479132Y406176D02*
G02X481087Y409621I2040J1120D01*
G01X479157Y406134D02*
X479132Y406176D01*
G01X479176Y406100D02*
X479157Y406134D01*
G01Y404559D02*
G03X479176Y406100I-1365J787D01*
G01X499845Y408568D02*
X501126D01*
G01X499481Y408204D02*
X499845Y408568D01*
G01X499481Y404204D02*
Y408204D01*
G01X498309Y403032D02*
X499481Y404204D01*
G01X498014Y403021D02*
X498309Y403032D01*
G01X497664Y402968D02*
G02X498014Y403021I409J-1522D01*
G01X497665Y402968D02*
X497664D01*
G01X482880Y413819D02*
X483992Y414931D01*
G01X482880Y412891D02*
Y413819D01*
G01X483187Y412359D02*
X482880Y412891D01*
G01X481242Y408871D02*
G03X483187Y412359I-70J2325D01*
G01X481113Y408871D02*
X481242D01*
G01X479788Y406543D02*
G02X481113Y408871I1384J753D01*
G01X479807Y406509D02*
X479788Y406543D01*
G01X479832Y406467D02*
X479807Y406509D01*
G01Y404184D02*
G03X479832Y406467I-2015J1164D01*
G01X502951Y405477D02*
Y406743D01*
G01X502363Y404889D02*
X502951Y405477D01*
G01X487057Y411732D02*
X486148Y412641D01*
G01X487057Y409545D02*
Y411732D01*
G01X485628Y408116D02*
X487057Y409545D01*
G01X484611Y407672D02*
G03X485628Y408116I-57J1517D01*
G01X484482Y407672D02*
X484611D01*
G01X482537Y404184D02*
G02X484482Y407672I2015J1163D01*
G01X487814Y413499D02*
X488648Y414333D01*
G01X487814Y409242D02*
Y413499D01*
G01X485989Y407417D02*
X487814Y409242D01*
G01X484637Y406922D02*
G03X485989Y407417I-85J2325D01*
G01X484508Y406922D02*
X484637D01*
G01X483187Y404559D02*
G02X484508Y406922I1365J788D01*
G01X503438Y404903D02*
X504791D01*
G01X503113Y404578D02*
X503438Y404903D01*
G01X499351Y409135D02*
Y410343D01*
G01X498731Y408515D02*
X499351Y409135D01*
G01X498731Y404515D02*
Y408515D01*
G01X497987Y403771D02*
X498731Y404515D01*
G01X541967Y206822D02*
G02X540646Y207610I44J1575D01*
G01X543100Y206822D02*
X541967D01*
G01X541926Y209971D02*
G02X539996Y211133I85J2325D01*
G01X542082Y209971D02*
X541926D01*
G01X543376Y209184D02*
G03X542082Y209971I-1365J-787D01*
G01X545273Y208089D02*
X543376Y209184D01*
G01X542031Y206059D02*
G02X539996Y207234I0J2349D01*
G01X542341Y206059D02*
X542031D01*
G01X560051Y261821D02*
X560451Y261421D01*
G01X556669Y261821D02*
X560051D01*
G01X556269Y261421D02*
X556669Y261821D01*
G01X555446Y261421D02*
X556269D01*
G01X553516Y260259D02*
G02X555446Y261421I2015J-1163D01*
G01X552210Y259472D02*
G03X553516Y260259I-59J1575D01*
G01X552081Y259472D02*
X552210D01*
G01X550136Y258309D02*
G02X552081Y259472I2015J-1162D01*
G01X548815Y257521D02*
G03X550136Y258309I-44J1575D01*
G01X548686Y257521D02*
X548815D01*
G01X546756Y256359D02*
G02X548686Y257521I2015J-1163D01*
G01X545450Y255572D02*
G03X546756Y256359I-59J1575D01*
G01X545321Y255572D02*
X545450D01*
G01X543376Y254409D02*
G02X545321Y255572I2015J-1162D01*
G01X542055Y253621D02*
G03X543376Y254409I-44J1575D01*
G01X541926Y253621D02*
X542055D01*
G01X539996Y252459D02*
G02X541926Y253621I2015J-1163D01*
G01Y277021D02*
G03X539996Y275859I85J-2325D01*
G01X542055Y277021D02*
X541926D01*
G01X543376Y277809D02*
G02X542055Y277021I-1365J787D01*
G01X545340Y278972D02*
G03X543376Y277809I51J-2326D01*
G01X545450Y278972D02*
X545340D01*
G01X546756Y279759D02*
G02X545450Y278972I-1365J788D01*
G01X563099Y271800D02*
X569625D01*
G01X562471Y271172D02*
X563099Y271800D01*
G01X558841Y271172D02*
X562471D01*
G01X556896Y270009D02*
G02X558841Y271172I2015J-1162D01*
G01X555575Y269221D02*
G03X556896Y270009I-44J1575D01*
G01X555446Y269221D02*
X555575D01*
G01X553516Y268059D02*
G02X555446Y269221I2015J-1163D01*
G01X552210Y267272D02*
G03X553516Y268059I-59J1575D01*
G01X552081Y267272D02*
X552210D01*
G01X550136Y266109D02*
G02X552081Y267272I2015J-1162D01*
G01X548815Y265321D02*
G03X550136Y266109I-44J1575D01*
G01X548686Y265321D02*
X548815D01*
G01X546756Y264159D02*
G02X548686Y265321I2015J-1163D01*
G01X545450Y263372D02*
G03X546756Y264159I-59J1575D01*
G01X545321Y263372D02*
X545450D01*
G01X543376Y262209D02*
G02X545321Y263372I2015J-1162D01*
G01X542055Y261421D02*
G03X543376Y262209I-44J1575D01*
G01X541926Y261421D02*
X542055D01*
G01X539996Y260259D02*
G02X541926Y261421I2015J-1163D01*
G01X563275Y270475D02*
X569500D01*
G01X563222Y270422D02*
X563275Y270475D01*
G01X558867Y270422D02*
X563222D01*
G01X557546Y269634D02*
G02X558867Y270422I1365J-787D01*
G01X555601Y268471D02*
G03X557546Y269634I-70J2325D01*
G01X555472Y268471D02*
X555601D01*
G01X554166Y267684D02*
G02X555472Y268471I1365J-788D01*
G01X552236Y266522D02*
G03X554166Y267684I-85J2325D01*
G01X552107Y266522D02*
X552236D01*
G01X550786Y265734D02*
G02X552107Y266522I1365J-787D01*
G01X548841Y264571D02*
G03X550786Y265734I-70J2325D01*
G01X548712Y264571D02*
X548841D01*
G01X547406Y263784D02*
G02X548712Y264571I1365J-788D01*
G01X545476Y262622D02*
G03X547406Y263784I-85J2325D01*
G01X545347Y262622D02*
X545476D01*
G01X544026Y261834D02*
G02X545347Y262622I1365J-787D01*
G01X542081Y260671D02*
G03X544026Y261834I-70J2325D01*
G01X541952Y260671D02*
X542081D01*
G01X540646Y259884D02*
G02X541952Y260671I1365J-788D01*
G01X541967Y276271D02*
G03X540646Y275483I44J-1575D01*
G01X542096Y276271D02*
X541967D01*
G01X544026Y277433D02*
G02X542096Y276271I-2015J1163D01*
G01X545347Y278221D02*
G03X544026Y277433I44J-1575D01*
G01X545442Y278221D02*
X545347D01*
G01X547406Y279384D02*
G02X545442Y278221I-2015J1163D01*
G01X548712Y280171D02*
G03X547406Y279384I59J-1575D01*
G01X563300Y253100D02*
X568300Y248100D01*
G01X561500Y253100D02*
X563300D01*
G01X559500Y255100D02*
X561500Y253100D01*
G01X558100Y255100D02*
X559500D01*
G01X556374Y256826D02*
X558100Y255100D01*
G01X553871Y256826D02*
X556374D01*
G01X553516Y256359D02*
G02X553871Y256826I2015J-1163D01*
G01X552210Y255572D02*
G03X553516Y256359I-59J1575D01*
G01X552081Y255572D02*
X552210D01*
G01X550136Y254409D02*
G02X552081Y255572I2015J-1162D01*
G01X548815Y253621D02*
G03X550136Y254409I-44J1575D01*
G01X548686Y253621D02*
X548815D01*
G01X546756Y252459D02*
G02X548686Y253621I2015J-1163D01*
G01X545450Y251672D02*
G03X546756Y252459I-59J1575D01*
G01X545321Y251672D02*
X545450D01*
G01X543376Y250509D02*
G02X545321Y251672I2015J-1162D01*
G01X542055Y249721D02*
G03X543376Y250509I-44J1575D01*
G01X541926Y249721D02*
X542055D01*
G01X539996Y248559D02*
G02X541926Y249721I2015J-1163D01*
G01X555487Y276271D02*
X561001D01*
G01X554166Y275483D02*
G02X555487Y276271I1365J-787D01*
G01X552236Y274321D02*
G03X554166Y275483I-85J2325D01*
G01X552080Y274321D02*
X552236D01*
G01X550786Y273534D02*
G02X552080Y274321I1365J-787D01*
G01X548841Y272371D02*
G03X550786Y273534I-70J2325D01*
G01X548712Y272371D02*
X548841D01*
G01X547406Y271584D02*
G02X548712Y272371I1365J-788D01*
G01X545476Y270422D02*
G03X547406Y271584I-85J2325D01*
G01X545347Y270422D02*
X545476D01*
G01X544026Y269634D02*
G02X545347Y270422I1365J-787D01*
G01X542081Y268471D02*
G03X544026Y269634I-70J2325D01*
G01X541952Y268471D02*
X542081D01*
G01X540646Y267684D02*
G02X541952Y268471I1365J-788D01*
G01X559429Y260671D02*
X570700Y249400D01*
G01X555472Y260671D02*
X559429D01*
G01X554166Y259884D02*
G02X555472Y260671I1365J-788D01*
G01X552236Y258722D02*
G03X554166Y259884I-85J2325D01*
G01X552107Y258722D02*
X552236D01*
G01X550786Y257934D02*
G02X552107Y258722I1365J-787D01*
G01X548841Y256771D02*
G03X550786Y257934I-70J2325D01*
G01X548712Y256771D02*
X548841D01*
G01X547406Y255984D02*
G02X548712Y256771I1365J-788D01*
G01X545476Y254822D02*
G03X547406Y255984I-85J2325D01*
G01X545347Y254822D02*
X545476D01*
G01X544026Y254034D02*
G02X545347Y254822I1365J-787D01*
G01X542081Y252871D02*
G03X544026Y254034I-70J2325D01*
G01X541952Y252871D02*
X542081D01*
G01X540646Y252084D02*
G02X541952Y252871I1365J-788D01*
G01X548686Y280921D02*
G03X546756Y279759I85J-2325D01*
G01X548815Y280921D02*
X548686D01*
G01X550136Y281709D02*
G02X548815Y280921I-1365J787D01*
G01X552081Y282872D02*
G03X550136Y281709I70J-2325D01*
G01X552210Y282872D02*
X552081D01*
G01X553516Y283659D02*
G02X552210Y282872I-1365J788D01*
G01X554645Y285615D02*
X553516Y283659D01*
G01X548841Y280171D02*
X548712D01*
G01X550786Y281334D02*
G02X548841Y280171I-2015J1162D01*
G01X552107Y282122D02*
G03X550786Y281334I44J-1575D01*
G01X552236Y282122D02*
X552107D01*
G01X554166Y283284D02*
G02X552236Y282122I-2015J1163D01*
G01X554470Y283809D02*
X554166Y283284D01*
G01X554963Y284094D02*
X554470Y283809D01*
G01X541952Y377671D02*
G03X540646Y376884I59J-1575D01*
G01X542081Y377671D02*
X541952D01*
G01X544026Y378834D02*
G02X542081Y377671I-2015J1162D01*
G01X545347Y379622D02*
G03X544026Y378834I44J-1575D01*
G01X545476Y379622D02*
X545347D01*
G01X547406Y380784D02*
G02X545476Y379622I-2015J1163D01*
G01X548712Y381571D02*
G03X547406Y380784I59J-1575D01*
G01X549171Y381571D02*
X548712D01*
G01X550500Y382900D02*
X549171Y381571D01*
G01X550500Y389400D02*
Y382900D01*
G01X541952Y362071D02*
G03X540646Y361284I59J-1575D01*
G01X542081Y362071D02*
X541952D01*
G01X544026Y363234D02*
G02X542081Y362071I-2015J1162D01*
G01X545347Y364022D02*
G03X544026Y363234I44J-1575D01*
G01X545476Y364022D02*
X545347D01*
G01X547406Y365184D02*
G02X545476Y364022I-2015J1163D01*
G01X548712Y365971D02*
G03X547406Y365184I59J-1575D01*
G01X548841Y365971D02*
X548712D01*
G01X550786Y367134D02*
G02X548841Y365971I-2015J1162D01*
G01X552107Y367922D02*
G03X550786Y367134I44J-1575D01*
G01X553593Y367922D02*
X552107D01*
G01X554400Y368410D02*
X553593Y367922D01*
G01X557207Y370109D02*
X554400Y368410D01*
G01X557703Y371046D02*
X557207Y370109D01*
G01X557941Y371712D02*
G02X557703Y371046I-2410J486D01*
G01X558429Y372200D02*
X557941Y371712D01*
G01X560100Y372200D02*
X558429D01*
G01X547093Y381607D02*
Y393493D01*
G01X546756Y381159D02*
G02X547093Y381607I2014J-1164D01*
G01X545450Y380372D02*
G03X546756Y381159I-59J1575D01*
G01X545321Y380372D02*
X545450D01*
G01X543376Y379209D02*
G02X545321Y380372I2015J-1162D01*
G01X542055Y378421D02*
G03X543376Y379209I-44J1575D01*
G01X541926Y378421D02*
X542055D01*
G01X539996Y377259D02*
G02X541926Y378421I2015J-1163D01*
G01X541952Y354271D02*
G03X540646Y353484I59J-1575D01*
G01X542081Y354271D02*
X541952D01*
G01X544026Y355434D02*
G02X542081Y354271I-2015J1162D01*
G01X545347Y356222D02*
G03X544026Y355434I44J-1575D01*
G01X545476Y356222D02*
X545347D01*
G01X547406Y357384D02*
G02X545476Y356222I-2015J1163D01*
G01X548712Y358171D02*
G03X547406Y357384I59J-1575D01*
G01X548841Y358171D02*
X548712D01*
G01X550786Y359334D02*
G02X548841Y358171I-2015J1162D01*
G01X552107Y360122D02*
G03X550786Y359334I44J-1575D01*
G01X557822Y360122D02*
X552107D01*
G01X567100Y369400D02*
X557822Y360122D01*
G01X552107Y364022D02*
X554400D01*
G01X550786Y363234D02*
G02X552107Y364022I1365J-787D01*
G01X548841Y362071D02*
G03X550786Y363234I-70J2325D01*
G01X548712Y362071D02*
X548841D01*
G01X547406Y361284D02*
G02X548712Y362071I1365J-788D01*
G01X545476Y360122D02*
G03X547406Y361284I-85J2325D01*
G01X545347Y360122D02*
X545476D01*
G01X544026Y359334D02*
G02X545347Y360122I1365J-787D01*
G01X542081Y358171D02*
G03X544026Y359334I-70J2325D01*
G01X541952Y358171D02*
X542081D01*
G01X540646Y357384D02*
G02X541952Y358171I1365J-788D01*
G01X655023Y-1766D02*
X663309Y6520D01*
G01X655023Y-16339D02*
Y-1766D01*
G01X649970Y-21392D02*
X655023Y-16339D01*
G01X703696Y10154D02*
X705250Y8600D01*
G01X683156Y10154D02*
X703696D01*
G01X679522Y6520D02*
X683156Y10154D01*
G01X663309Y6520D02*
X679522D01*
G01X669596Y87990D02*
X667900D01*
G01X670795Y89189D02*
X669596Y87990D01*
G01X756176Y4724D02*
X753924Y6976D01*
G01X756176Y-4300D02*
Y-2567D01*
G01X907557Y230721D02*
X915918D01*
G01X906736Y231542D02*
X907557Y230721D01*
G01X908114Y248485D02*
X914157D01*
G01X909599Y241884D02*
X911084D01*
G01X908695Y240980D02*
X909599Y241884D01*
G01X907955Y235341D02*
X916041D01*
G01X907056Y234442D02*
X907955Y235341D01*
G01X907665Y229971D02*
X916229D01*
G01X906736Y229042D02*
X907665Y229971D01*
G01X907711Y236089D02*
X915647D01*
G01X906858Y236942D02*
X907711Y236089D01*
G01X909694Y259130D02*
X911626D01*
G01X908929Y266630D02*
X910813D01*
G01X909135Y247735D02*
X914131D01*
G01X907380Y245980D02*
X909135Y247735D01*
G01X909462Y242635D02*
X910408D01*
G01X908617Y243480D02*
X909462Y242635D01*
G01X908075Y338789D02*
X906364Y340500D01*
G01X910609Y338789D02*
X908075D01*
G01X906567Y338039D02*
X906006Y338600D01*
G01X910954Y338039D02*
X906567D01*
G01X910042Y394888D02*
X909107Y395823D01*
G01X906085Y389489D02*
X905285Y390289D01*
G01X914066Y389489D02*
X906085D01*
G01X909955Y394140D02*
X909107Y393292D01*
G01X917755Y394140D02*
X909955D01*
G01X899970Y356641D02*
X899065Y355736D01*
G01X912274Y356641D02*
X899970D01*
G01X903409Y343341D02*
X902496Y342428D01*
G01X910406Y343341D02*
X903409D01*
G01X906557Y388741D02*
X905605Y387789D01*
G01X913756Y388741D02*
X906557D01*
G01X900056Y361683D02*
X899229Y360856D01*
G01X910356Y361683D02*
X900056D01*
G01X904508Y368589D02*
X903166Y369931D01*
G01X909066Y368589D02*
X904508D01*
G01X913766Y363889D02*
X909066Y368589D01*
G01X904470Y367841D02*
X904056Y367427D01*
G01X908756Y367841D02*
X904470D01*
G01X913456Y363141D02*
X908756Y367841D01*
G01X903436Y344089D02*
X902597Y344928D01*
G01X910096Y344089D02*
X903436D01*
G01X899891Y357389D02*
X899044Y358236D01*
G01X911964Y357389D02*
X899891D01*
G01X903883Y374141D02*
X902856Y375168D01*
G01X907856Y374141D02*
X903883D01*
G01X915256Y366741D02*
X907856Y374141D01*
G01X899755Y362431D02*
X898813Y363373D01*
G01X910666Y362431D02*
X899755D01*
G01X907546Y373393D02*
X914946Y365993D01*
G01X903648Y373393D02*
X907546D01*
G01X902856Y372601D02*
X903648Y373393D01*
G01X963421Y217697D02*
G02X964727Y218484I1365J-788D01*
G01X961491Y216535D02*
G03X963421Y217697I-85J2325D01*
G01X961362Y216535D02*
X961491D01*
G01X960041Y215747D02*
G02X961362Y216535I1365J-787D01*
G01X958096Y214584D02*
G03X960041Y215747I-70J2325D01*
G01X958026Y214584D02*
X958096D01*
G01X956675Y213819D02*
G02X958026Y214584I1351J-810D01*
G01X956662Y213796D02*
X956675Y213819D01*
G01X954745Y212635D02*
G03X956662Y213796I-98J2325D01*
G01X954588Y212635D02*
X954745D01*
G01X953282Y211847D02*
G02X954588Y212635I1365J-786D01*
G01X951337Y210684D02*
G03X953282Y211847I-70J2325D01*
G01X951208Y210684D02*
X951337D01*
G01X949902Y209897D02*
G02X951208Y210684I1365J-788D01*
G01X947938Y208734D02*
G03X949902Y209897I-51J2326D01*
G01X947843Y208734D02*
X947938D01*
G01X946522Y207946D02*
G02X947843Y208734I1365J-787D01*
G01X944592Y206784D02*
G03X946522Y207946I-85J2325D01*
G01X944436Y206784D02*
X944592D01*
G01X943142Y205997D02*
G02X944436Y206784I1365J-787D01*
G01X941197Y204834D02*
G03X943142Y205997I-70J2325D01*
G01X941056Y204834D02*
X941197D01*
G01X939762Y202472D02*
G02X941056Y204834I1365J788D01*
G01X939787Y200189D02*
G03X939762Y202472I-2040J1119D01*
G01Y200147D02*
X939787Y200189D01*
G01X939743Y200113D02*
X939762Y200147D01*
G01Y198572D02*
G02X939743Y200113I1365J787D01*
G01X940933Y196547D02*
X939762Y198572D01*
G01X940933Y190050D02*
Y196547D01*
G01X939920Y189037D02*
X940933Y190050D01*
G01X939920Y186920D02*
Y189037D01*
G01X968197Y213979D02*
X973147Y218929D01*
G01X968197Y212602D02*
Y213979D01*
G01X966279Y210684D02*
X968197Y212602D01*
G01X964727Y210684D02*
X966279D01*
G01X963421Y209897D02*
G02X964727Y210684I1365J-788D01*
G01X961406Y208735D02*
G03X963421Y209897I2J2324D01*
G01X960720Y208735D02*
X961406D01*
G01X956000Y204015D02*
X960720Y208735D01*
G01X956000Y202936D02*
Y204015D01*
G01X915225Y215861D02*
X921748Y222384D01*
G01X913464Y215861D02*
X915225D01*
G01X912436Y214833D02*
X913464Y215861D01*
G01X914394Y210761D02*
X922117Y218484D01*
G01X913364Y210761D02*
X914394D01*
G01X912436Y209833D02*
X913364Y210761D01*
G01X934426Y217285D02*
G03X935732Y218072I-59J1575D01*
G01X934297Y217285D02*
X934426D01*
G01X932352Y216122D02*
G02X934297Y217285I2015J-1162D01*
G01X931031Y215334D02*
G03X932352Y216122I-44J1575D01*
G01X930902Y215334D02*
X931031D01*
G01X928972Y214172D02*
G02X930902Y215334I2015J-1163D01*
G01X927666Y213385D02*
G03X928972Y214172I-59J1575D01*
G01X927537Y213385D02*
X927666D01*
G01X925592Y209897D02*
G02X927537Y213385I2015J1163D01*
G01X924298Y207535D02*
G03X925592Y209897I-71J1574D01*
G01X924157Y207535D02*
X924298D01*
G01X922212Y204047D02*
G02X924157Y207535I2015J1163D01*
G01X922231Y204013D02*
X922212Y204047D01*
G01X920928Y201686D02*
G03X922231Y204013I-81J1574D01*
G01X920151Y201686D02*
X920928D01*
G01X918296Y199831D02*
X920151Y201686D01*
G01X929622Y217697D02*
G02X930928Y218484I1365J-788D01*
G01X927692Y216535D02*
G03X929622Y217697I-85J2325D01*
G01X927563Y216535D02*
X927692D01*
G01X926242Y215747D02*
G02X927563Y216535I1365J-787D01*
G01X924297Y214584D02*
G03X926242Y215747I-70J2325D01*
G01X924183Y214584D02*
X924297D01*
G01X922862Y212222D02*
G02X924183Y214584I1365J787D01*
G01X920932Y208734D02*
G03X922862Y212222I-85J2325D01*
G01X920803Y208734D02*
X920932D01*
G01X919482Y207946D02*
G02X920803Y208734I1365J-787D01*
G01X919300Y207623D02*
X919482Y207946D01*
G01X919266Y207563D02*
X919300Y207623D01*
G01X919266Y206751D02*
Y207563D01*
G01X918756Y206241D02*
X919266Y206751D01*
G01X918756Y205141D02*
Y206241D01*
G01X918556Y204941D02*
X918756Y205141D01*
G01X927666Y217285D02*
G03X928972Y218072I-59J1575D01*
G01X927537Y217285D02*
X927666D01*
G01X925592Y216122D02*
G02X927537Y217285I2015J-1162D01*
G01X924271Y215334D02*
G03X925592Y216122I-44J1575D01*
G01X924142Y215334D02*
X924271D01*
G01X922212Y211846D02*
G02X924142Y215334I2015J1163D01*
G01X920891Y209484D02*
G03X922212Y211846I-44J1575D01*
G01X920762Y209484D02*
X920891D01*
G01X918832Y208322D02*
G02X920762Y209484I2015J-1163D01*
G01X918700Y208093D02*
X918832Y208322D01*
G01X918332Y207455D02*
X918700Y208093D01*
G01X917687Y206810D02*
X918332Y207455D01*
G01X916688Y206810D02*
X917687D01*
G01X914914Y216611D02*
X921437Y223134D01*
G01X913158Y216611D02*
X914914D01*
G01X912436Y217333D02*
X913158Y216611D01*
G01X936382Y217697D02*
G02X937688Y218484I1365J-788D01*
G01X934452Y216535D02*
G03X936382Y217697I-85J2325D01*
G01X934323Y216535D02*
X934452D01*
G01X933002Y215747D02*
G02X934323Y216535I1365J-787D01*
G01X931057Y214584D02*
G03X933002Y215747I-70J2325D01*
G01X930928Y214584D02*
X931057D01*
G01X929622Y213797D02*
G02X930928Y214584I1365J-788D01*
G01X927692Y212635D02*
G03X929622Y213797I-85J2325D01*
G01X927563Y212635D02*
X927692D01*
G01X926242Y210272D02*
G02X927563Y212635I1365J788D01*
G01X924312Y206784D02*
G03X926242Y210272I-85J2325D01*
G01X924156Y206784D02*
X924312D01*
G01X922862Y204423D02*
G02X924156Y206784I1365J787D01*
G01X922862Y202097D02*
G03Y204423I-2015J1163D01*
G01X922106Y200787D02*
X922862Y202097D01*
G01X922106Y199492D02*
Y200787D01*
G01X919945Y197331D02*
X922106Y199492D01*
G01X954647Y217285D02*
G03X955998Y218050I0J1575D01*
G01X954577Y217285D02*
X954647D01*
G01X952632Y216122D02*
G02X954577Y217285I2015J-1162D01*
G01X951311Y215334D02*
G03X952632Y216122I-44J1575D01*
G01X951182Y215334D02*
X951311D01*
G01X949252Y214172D02*
G02X951182Y215334I2015J-1163D01*
G01X947946Y213385D02*
G03X949252Y214172I-59J1575D01*
G01X947817Y213385D02*
X947946D01*
G01X945872Y212222D02*
G02X947817Y213385I2015J-1162D01*
G01X944551Y211434D02*
G03X945872Y212222I-44J1575D01*
G01X944422Y211434D02*
X944551D01*
G01X942492Y210272D02*
G02X944422Y211434I2015J-1163D01*
G01X941186Y209485D02*
G03X942492Y210272I-59J1575D01*
G01X941076Y209485D02*
X941186D01*
G01X939112Y208322D02*
G02X941076Y209485I2015J-1163D01*
G01X937818Y207535D02*
G03X939112Y208322I-71J1574D01*
G01X937677Y207535D02*
X937818D01*
G01X935732Y204047D02*
G02X937677Y207535I2015J1163D01*
G01X935751Y204013D02*
X935732Y204047D01*
G01Y202472D02*
G03X935751Y204013I-1365J787D01*
G01X935707Y200189D02*
G02X935732Y202472I2040J1119D01*
G01Y200147D02*
X935707Y200189D01*
G01X935942Y199360D02*
G03X935732Y200147I-1575J1D01*
G01X935944Y199358D02*
X935942Y199360D01*
G01X935944Y193129D02*
Y199358D01*
G01X934255Y191440D02*
X935944Y193129D01*
G01X933097Y191440D02*
X934255D01*
G01X967447Y214293D02*
X972550Y219396D01*
G01X967447Y212916D02*
Y214293D01*
G01X965965Y211434D02*
X967447Y212916D01*
G01X964701Y211434D02*
X965965D01*
G01X962771Y210272D02*
G02X964701Y211434I2015J-1163D01*
G01X961406Y209485D02*
G03X962771Y210272I2J1574D01*
G01X960396Y209485D02*
X961406D01*
G01X955511Y204600D02*
X960396Y209485D01*
G01X954120Y204600D02*
X955511D01*
G01X965732Y203059D02*
X973066Y210393D01*
G01X965732Y201765D02*
Y203059D01*
G01X914086Y211511D02*
X921809Y219234D01*
G01X913258Y211511D02*
X914086D01*
G01X912436Y212333D02*
X913258Y211511D01*
G01X956675Y217719D02*
G02X958026Y218484I1351J-810D01*
G01X956662Y217696D02*
X956675Y217719D01*
G01X954745Y216535D02*
G03X956662Y217696I-98J2325D01*
G01X954603Y216535D02*
X954745D01*
G01X953282Y215747D02*
G02X954603Y216535I1365J-787D01*
G01X951337Y214584D02*
G03X953282Y215747I-70J2325D01*
G01X951208Y214584D02*
X951337D01*
G01X949902Y213797D02*
G02X951208Y214584I1365J-788D01*
G01X947972Y212635D02*
G03X949902Y213797I-85J2325D01*
G01X947843Y212635D02*
X947972D01*
G01X946522Y211847D02*
G02X947843Y212635I1365J-787D01*
G01X944577Y210684D02*
G03X946522Y211847I-70J2325D01*
G01X944448Y210684D02*
X944577D01*
G01X943142Y209897D02*
G02X944448Y210684I1365J-788D01*
G01X941178Y208734D02*
G03X943142Y209897I-51J2326D01*
G01X941083Y208734D02*
X941178D01*
G01X939762Y207946D02*
G02X941083Y208734I1365J-787D01*
G01X937832Y206784D02*
G03X939762Y207946I-85J2325D01*
G01X937676Y206784D02*
X937832D01*
G01X936382Y204423D02*
G02X937676Y206784I1365J787D01*
G01X936382Y202097D02*
G03Y204423I-2015J1163D01*
G01X936363Y200556D02*
G02X936382Y202097I1384J754D01*
G01Y200522D02*
X936363Y200556D01*
G01X936693Y199360D02*
G03X936382Y200522I-2326J0D01*
G01X936693Y192674D02*
Y199360D01*
G01X934570Y190551D02*
X936693Y192674D01*
G01X934570Y189437D02*
Y190551D01*
G01X961465Y217285D02*
G03X962771Y218072I-59J1575D01*
G01X961336Y217285D02*
X961465D01*
G01X959391Y216122D02*
G02X961336Y217285I2015J-1162D01*
G01X958070Y215334D02*
G03X959391Y216122I-44J1575D01*
G01X957928Y215334D02*
X958070D01*
G01X956011Y214173D02*
G02X957928Y215334I2015J-1164D01*
G01X954695Y213386D02*
G03X956011Y214173I-48J1574D01*
G01X954577Y213386D02*
X954695D01*
G01X952632Y212223D02*
G02X954577Y213386I2015J-1162D01*
G01X951286Y211434D02*
G03X952632Y212223I-19J1575D01*
G01X951182Y211434D02*
X951286D01*
G01X949252Y210272D02*
G02X951182Y211434I2015J-1163D01*
G01X947946Y209485D02*
G03X949252Y210272I-59J1575D01*
G01X947836Y209485D02*
X947946D01*
G01X945872Y208322D02*
G02X947836Y209485I2015J-1163D01*
G01X944578Y207535D02*
G03X945872Y208322I-71J1574D01*
G01X944437Y207535D02*
X944578D01*
G01X942492Y206372D02*
G02X944437Y207535I2015J-1162D01*
G01X941198Y205585D02*
G03X942492Y206372I-71J1574D01*
G01X941042Y205585D02*
X941198D01*
G01X939112Y202097D02*
G02X941042Y205585I2015J1163D01*
G01X939131Y200556D02*
G03X939112Y202097I-1384J754D01*
G01Y200522D02*
X939131Y200556D01*
G01X939077Y200462D02*
X939112Y200522D01*
G01Y198196D02*
G02X939077Y200462I2015J1164D01*
G01X940183Y196345D02*
X939112Y198196D01*
G01X940183Y190368D02*
Y196345D01*
G01X939285Y189470D02*
X940183Y190368D01*
G01X938139Y189470D02*
X939285D01*
G01X965015Y203400D02*
X972316Y210701D01*
G01X963497Y203400D02*
X965015D01*
G01X947909Y261817D02*
X947887Y261760D01*
G01X946771Y264445D02*
X947909Y261817D01*
G01X946522Y264872D02*
X946771Y264445D01*
G01X944592Y266034D02*
G02X946522Y264872I-85J-2325D01*
G01X944463Y266034D02*
X944592D01*
G01X943142Y266822D02*
G03X944463Y266034I1365J787D01*
G01X941197Y267985D02*
G02X943142Y266822I-70J-2325D01*
G01X941057Y267985D02*
X941197D01*
G01X939112Y266822D02*
G02X941057Y267985I2015J-1162D01*
G01X937791Y266034D02*
G03X939112Y266822I-44J1575D01*
G01X937662Y266034D02*
X937791D01*
G01X935732Y264872D02*
G02X937662Y266034I2015J-1163D01*
G01X934426Y264085D02*
G03X935732Y264872I-59J1575D01*
G01X934297Y264085D02*
X934426D01*
G01X932352Y262922D02*
G02X934297Y264085I2015J-1162D01*
G01X931031Y262134D02*
G03X932352Y262922I-44J1575D01*
G01X930902Y262134D02*
X931031D01*
G01X928972Y260972D02*
G02X930902Y262134I2015J-1163D01*
G01X927666Y260185D02*
G03X928972Y260972I-59J1575D01*
G01X927537Y260185D02*
X927666D01*
G01X925592Y259022D02*
G02X927537Y260185I2015J-1162D01*
G01X922862Y259022D02*
G03X925592I1365J787D01*
G01X920917Y260185D02*
G02X922862Y259022I-70J-2325D01*
G01X920777Y260185D02*
X920917D01*
G01X918832Y259022D02*
G02X920777Y260185I2015J-1162D01*
G01X916102Y259022D02*
G03X918832I1365J787D01*
G01X914157Y260185D02*
G02X916102Y259022I-70J-2325D01*
G01X912176Y260185D02*
X914157D01*
G01X910731Y261630D02*
X912176Y260185D01*
G01X909977Y261630D02*
X910731D01*
G01X945938Y244881D02*
X947887Y242260D01*
G01X945872Y244997D02*
X945938Y244881D01*
G01X944566Y245784D02*
G02X945872Y244997I-59J-1575D01*
G01X944448Y245784D02*
X944566D01*
G01X943567Y245474D02*
G02X944448Y245784I940J-1265D01*
G01X941776Y244585D02*
X943567Y245474D01*
G01X941057Y244585D02*
X941776D01*
G01X939112Y243422D02*
G02X941057Y244585I2015J-1162D01*
G01X937791Y242634D02*
G03X939112Y243422I-44J1575D01*
G01X937662Y242634D02*
X937791D01*
G01X935732Y241472D02*
G02X937662Y242634I2015J-1163D01*
G01X934426Y240685D02*
G03X935732Y241472I-59J1575D01*
G01X934297Y240685D02*
X934426D01*
G01X932352Y239522D02*
G02X934297Y240685I2015J-1162D01*
G01X931031Y238734D02*
G03X932352Y239522I-44J1575D01*
G01X930902Y238734D02*
X931031D01*
G01X928972Y237572D02*
G02X930902Y238734I2015J-1163D01*
G01X927666Y236785D02*
G03X928972Y237572I-59J1575D01*
G01X927537Y236785D02*
X927666D01*
G01X925592Y235622D02*
G02X927537Y236785I2015J-1162D01*
G01X924271Y234834D02*
G03X925592Y235622I-44J1575D01*
G01X920031Y234834D02*
X924271D01*
G01X915918Y230721D02*
X920031Y234834D01*
G01X970295Y221822D02*
X971546Y224709D01*
G01X968251Y220435D02*
G03X970295Y221822I-85J2325D01*
G01X968122Y220435D02*
X968251D01*
G01X966801Y219647D02*
G02X968122Y220435I1365J-787D01*
G01X964856Y218484D02*
G03X966801Y219647I-70J2325D01*
G01X964727Y218484D02*
X964856D01*
G01X941269Y256285D02*
X944507Y255909D01*
G01X941057Y256285D02*
X941269D01*
G01X939112Y255122D02*
G02X941057Y256285I2015J-1162D01*
G01X937791Y254334D02*
G03X939112Y255122I-44J1575D01*
G01X937662Y254334D02*
X937791D01*
G01X935732Y253172D02*
G02X937662Y254334I2015J-1163D01*
G01X934426Y252385D02*
G03X935732Y253172I-59J1575D01*
G01X934297Y252385D02*
X934426D01*
G01X932352Y251222D02*
G02X934297Y252385I2015J-1162D01*
G01X931031Y250434D02*
G03X932352Y251222I-44J1575D01*
G01X930902Y250434D02*
X931031D01*
G01X928972Y249272D02*
G02X930902Y250434I2015J-1163D01*
G01X927666Y248485D02*
G03X928972Y249272I-59J1575D01*
G01X927537Y248485D02*
X927666D01*
G01X925592Y247322D02*
G02X927537Y248485I2015J-1162D01*
G01X922862Y247322D02*
G03X925592I1365J787D01*
G01X920917Y248485D02*
G02X922862Y247322I-70J-2325D01*
G01X920777Y248485D02*
X920917D01*
G01X918832Y247322D02*
G02X920777Y248485I2015J-1162D01*
G01X916102Y247322D02*
G03X918832I1365J787D01*
G01X914157Y248485D02*
G02X916102Y247322I-70J-2325D01*
G01X944653Y250434D02*
X947887Y250060D01*
G01X944463Y250434D02*
X944653D01*
G01X943568Y250744D02*
G03X944463Y250434I939J1265D01*
G01X941608Y251635D02*
X943568Y250744D01*
G01X941083Y251635D02*
X941608D01*
G01X939762Y250847D02*
G02X941083Y251635I1365J-787D01*
G01X937817Y249684D02*
G03X939762Y250847I-70J2325D01*
G01X937688Y249684D02*
X937817D01*
G01X936382Y248897D02*
G02X937688Y249684I1365J-788D01*
G01X934452Y247735D02*
G03X936382Y248897I-85J2325D01*
G01X934323Y247735D02*
X934452D01*
G01X933002Y246947D02*
G02X934323Y247735I1365J-787D01*
G01X931057Y245784D02*
G03X933002Y246947I-70J2325D01*
G01X930928Y245784D02*
X931057D01*
G01X929622Y244997D02*
G02X930928Y245784I1365J-788D01*
G01X927692Y243835D02*
G03X929622Y244997I-85J2325D01*
G01X927563Y243835D02*
X927692D01*
G01X926242Y243047D02*
G02X927563Y243835I1365J-787D01*
G01X924297Y241884D02*
G03X926242Y243047I-70J2325D01*
G01X924157Y241884D02*
X924297D01*
G01X922212Y243047D02*
G03X924157Y241884I2015J1162D01*
G01X919482Y243047D02*
G02X922212I1365J-787D01*
G01X917537Y241884D02*
G03X919482Y243047I-70J2325D01*
G01X916669Y241884D02*
X917537D01*
G01X915295Y243058D02*
G03X916669Y241884I2172J1151D01*
G01X914442Y243835D02*
G02X915295Y243058I-655J-1575D01*
G01X913035Y243835D02*
X914442D01*
G01X911084Y241884D02*
X913035Y243835D01*
G01X924297Y222384D02*
X921748D01*
G01X926242Y223547D02*
G02X924297Y222384I-2015J1162D01*
G01X927563Y224335D02*
G03X926242Y223547I44J-1575D01*
G01X927692Y224335D02*
X927563D01*
G01X929622Y225497D02*
G02X927692Y224335I-2015J1163D01*
G01X930928Y226284D02*
G03X929622Y225497I59J-1575D01*
G01X931038Y226284D02*
X930928D01*
G01X933002Y227447D02*
G02X931038Y226284I-2015J1163D01*
G01X934296Y228234D02*
G03X933002Y227447I71J-1574D01*
G01X934437Y228234D02*
X934296D01*
G01X936382Y229397D02*
G02X934437Y228234I-2015J1162D01*
G01X937676Y230184D02*
G03X936382Y229397I71J-1574D01*
G01X937832Y230184D02*
X937676D01*
G01X939762Y231346D02*
G02X937832Y230184I-2015J1163D01*
G01X941083Y232134D02*
G03X939762Y231346I44J-1575D01*
G01X941178Y232134D02*
X941083D01*
G01X943142Y233297D02*
G02X941178Y232134I-2015J1163D01*
G01X944448Y234084D02*
G03X943142Y233297I59J-1575D01*
G01X945013Y234084D02*
X944448D01*
G01X945823Y233812D02*
X945013Y234084D01*
G01X946861Y233263D02*
X945823Y233812D01*
G01X947828Y232885D02*
G02X946861Y233263I58J1575D01*
G01X948023Y232885D02*
X947828D01*
G01X951267Y232509D02*
X948023Y232885D01*
G01X951413Y242634D02*
X954647Y242260D01*
G01X951223Y242634D02*
X951413D01*
G01X949902Y243422D02*
G03X951223Y242634I1365J787D01*
G01X947957Y244585D02*
G02X949902Y243422I-70J-2325D01*
G01X947828Y244585D02*
X947957D01*
G01X946522Y245372D02*
G03X947828Y244585I1365J788D01*
G01X944592Y246534D02*
G02X946522Y245372I-85J-2325D01*
G01X944463Y246534D02*
X944592D01*
G01X943531Y246872D02*
G03X944463Y246534I976J1237D01*
G01X941776Y247735D02*
X943531Y246872D01*
G01X941083Y247735D02*
X941776D01*
G01X939762Y246947D02*
G02X941083Y247735I1365J-787D01*
G01X937817Y245784D02*
G03X939762Y246947I-70J2325D01*
G01X937688Y245784D02*
X937817D01*
G01X936382Y244997D02*
G02X937688Y245784I1365J-788D01*
G01X934452Y243835D02*
G03X936382Y244997I-85J2325D01*
G01X934323Y243835D02*
X934452D01*
G01X933002Y243047D02*
G02X934323Y243835I1365J-787D01*
G01X931057Y241884D02*
G03X933002Y243047I-70J2325D01*
G01X930928Y241884D02*
X931057D01*
G01X929622Y241097D02*
G02X930928Y241884I1365J-788D01*
G01X927692Y239935D02*
G03X929622Y241097I-85J2325D01*
G01X927563Y239935D02*
X927692D01*
G01X926242Y239147D02*
G02X927563Y239935I1365J-787D01*
G01X924297Y237984D02*
G03X926242Y239147I-70J2325D01*
G01X924157Y237984D02*
X924297D01*
G01X922212Y239147D02*
G03X924157Y237984I2015J1162D01*
G01X919482Y239147D02*
G02X922212I1365J-787D01*
G01X918984Y238284D02*
X919482Y239147D01*
G01X916041Y235341D02*
X918984Y238284D01*
G01X944651Y230184D02*
X947887Y230559D01*
G01X944436Y230184D02*
X944651D01*
G01X943142Y229397D02*
G02X944436Y230184I1365J-787D01*
G01X941197Y228234D02*
G03X943142Y229397I-70J2325D01*
G01X941056Y228234D02*
X941197D01*
G01X939762Y227447D02*
G02X941056Y228234I1365J-787D01*
G01X937798Y226284D02*
G03X939762Y227447I-51J2326D01*
G01X937688Y226284D02*
X937798D01*
G01X936382Y225497D02*
G02X937688Y226284I1365J-788D01*
G01X934452Y224335D02*
G03X936382Y225497I-85J2325D01*
G01X934323Y224335D02*
X934452D01*
G01X933002Y223547D02*
G02X934323Y224335I1365J-787D01*
G01X931057Y222384D02*
G03X933002Y223547I-70J2325D01*
G01X930928Y222384D02*
X931057D01*
G01X929622Y221597D02*
G02X930928Y222384I1365J-788D01*
G01X927692Y220435D02*
G03X929622Y221597I-85J2325D01*
G01X927563Y220435D02*
X927692D01*
G01X926242Y219647D02*
G02X927563Y220435I1365J-787D01*
G01X924297Y218484D02*
G03X926242Y219647I-70J2325D01*
G01X922117Y218484D02*
X924297D01*
G01X952698Y240981D02*
X954647Y238360D01*
G01X952632Y241097D02*
X952698Y240981D01*
G01X951326Y241884D02*
G02X952632Y241097I-59J-1575D01*
G01X951208Y241884D02*
X951326D01*
G01X950397Y241624D02*
G02X951208Y241884I869J-1315D01*
G01X948226Y240685D02*
X950397Y241624D01*
G01X947828Y240685D02*
X948226D01*
G01X946522Y241472D02*
G03X947828Y240685I1365J788D01*
G01X944592Y242634D02*
G02X946522Y241472I-85J-2325D01*
G01X944463Y242634D02*
X944592D01*
G01X943417Y243071D02*
G03X944463Y242634I1090J1138D01*
G01X941876Y243835D02*
X943417Y243071D01*
G01X941083Y243835D02*
X941876D01*
G01X939762Y243047D02*
G02X941083Y243835I1365J-787D01*
G01X937817Y241884D02*
G03X939762Y243047I-70J2325D01*
G01X937688Y241884D02*
X937817D01*
G01X936382Y241097D02*
G02X937688Y241884I1365J-788D01*
G01X934452Y239935D02*
G03X936382Y241097I-85J2325D01*
G01X934323Y239935D02*
X934452D01*
G01X933002Y239147D02*
G02X934323Y239935I1365J-787D01*
G01X931057Y237984D02*
G03X933002Y239147I-70J2325D01*
G01X930928Y237984D02*
X931057D01*
G01X929622Y237197D02*
G02X930928Y237984I1365J-788D01*
G01X927692Y236035D02*
G03X929622Y237197I-85J2325D01*
G01X927563Y236035D02*
X927692D01*
G01X926242Y235247D02*
G02X927563Y236035I1365J-787D01*
G01X924297Y234084D02*
G03X926242Y235247I-70J2325D01*
G01X920342Y234084D02*
X924297D01*
G01X916229Y229971D02*
X920342Y234084D01*
G01X949318Y246831D02*
X951267Y244209D01*
G01X949252Y246947D02*
X949318Y246831D01*
G01X947931Y247735D02*
G02X949252Y246947I-44J-1575D01*
G01X947802Y247735D02*
X947931D01*
G01X945872Y248897D02*
G03X947802Y247735I2015J1163D01*
G01X944566Y249684D02*
G02X945872Y248897I-59J-1575D01*
G01X944448Y249684D02*
X944566D01*
G01X943567Y249374D02*
G02X944448Y249684I940J-1265D01*
G01X941776Y248485D02*
X943567Y249374D01*
G01X941057Y248485D02*
X941776D01*
G01X939112Y247322D02*
G02X941057Y248485I2015J-1162D01*
G01X937791Y246534D02*
G03X939112Y247322I-44J1575D01*
G01X937662Y246534D02*
X937791D01*
G01X935732Y245372D02*
G02X937662Y246534I2015J-1163D01*
G01X934426Y244585D02*
G03X935732Y245372I-59J1575D01*
G01X934297Y244585D02*
X934426D01*
G01X932352Y243422D02*
G02X934297Y244585I2015J-1162D01*
G01X931031Y242634D02*
G03X932352Y243422I-44J1575D01*
G01X930902Y242634D02*
X931031D01*
G01X928972Y241472D02*
G02X930902Y242634I2015J-1163D01*
G01X927666Y240685D02*
G03X928972Y241472I-59J1575D01*
G01X927537Y240685D02*
X927666D01*
G01X925592Y239522D02*
G02X927537Y240685I2015J-1162D01*
G01X922862Y239522D02*
G03X925592I1365J787D01*
G01X920917Y240685D02*
G02X922862Y239522I-70J-2325D01*
G01X920777Y240685D02*
X920917D01*
G01X918832Y239522D02*
G02X920777Y240685I2015J-1162D01*
G01X918494Y238936D02*
X918832Y239522D01*
G01X915647Y236089D02*
X918494Y238936D01*
G01X961280Y230717D02*
X961406Y230559D01*
G01X959407Y230935D02*
X961280Y230717D01*
G01X957956Y230935D02*
X959407D01*
G01X956011Y229772D02*
G02X957956Y230935I2015J-1162D01*
G01X954695Y228985D02*
G03X956011Y229772I-48J1574D01*
G01X954562Y228985D02*
X954695D01*
G01X952632Y227823D02*
G02X954562Y228985I2015J-1163D01*
G01X951311Y227035D02*
G03X952632Y227823I-44J1575D01*
G01X951216Y227035D02*
X951311D01*
G01X949252Y225872D02*
G02X951216Y227035I2015J-1163D01*
G01X947946Y225085D02*
G03X949252Y225872I-59J1575D01*
G01X947817Y225085D02*
X947946D01*
G01X945872Y223922D02*
G02X947817Y225085I2015J-1162D01*
G01X944551Y223134D02*
G03X945872Y223922I-44J1575D01*
G01X944422Y223134D02*
X944551D01*
G01X942492Y221972D02*
G02X944422Y223134I2015J-1163D01*
G01X941186Y221185D02*
G03X942492Y221972I-59J1575D01*
G01X941057Y221185D02*
X941186D01*
G01X939112Y220022D02*
G02X941057Y221185I2015J-1162D01*
G01X937791Y219234D02*
G03X939112Y220022I-44J1575D01*
G01X937662Y219234D02*
X937791D01*
G01X935732Y218072D02*
G02X937662Y219234I2015J-1163D01*
G01X952698Y260481D02*
X954647Y257860D01*
G01X952632Y260597D02*
X952698Y260481D01*
G01X951326Y261384D02*
G02X952632Y260597I-59J-1575D01*
G01X951208Y261384D02*
X951326D01*
G01X950451Y261158D02*
G02X951208Y261384I815J-1349D01*
G01X948286Y260185D02*
X950451Y261158D01*
G01X947828Y260185D02*
X948286D01*
G01X946362Y261362D02*
G03X947828Y260185I1525J398D01*
G01X946107Y262469D02*
X946362Y261362D01*
G01X946161Y263348D02*
X946107Y262469D01*
G01X946104Y264096D02*
X946161Y263348D01*
G01X945872Y264497D02*
X946104Y264096D01*
G01X944566Y265284D02*
G02X945872Y264497I-59J-1575D01*
G01X944437Y265284D02*
X944566D01*
G01X942492Y266447D02*
G03X944437Y265284I2015J1162D01*
G01X939762Y266447D02*
G02X942492I1365J-787D01*
G01X937817Y265284D02*
G03X939762Y266447I-70J2325D01*
G01X937688Y265284D02*
X937817D01*
G01X936382Y264497D02*
G02X937688Y265284I1365J-788D01*
G01X934452Y263335D02*
G03X936382Y264497I-85J2325D01*
G01X934323Y263335D02*
X934452D01*
G01X933002Y262547D02*
G02X934323Y263335I1365J-787D01*
G01X931057Y261384D02*
G03X933002Y262547I-70J2325D01*
G01X930928Y261384D02*
X931057D01*
G01X929622Y260597D02*
G02X930928Y261384I1365J-788D01*
G01X927692Y259435D02*
G03X929622Y260597I-85J2325D01*
G01X927563Y259435D02*
X927692D01*
G01X926242Y258647D02*
G02X927563Y259435I1365J-787D01*
G01X924297Y257484D02*
G03X926242Y258647I-70J2325D01*
G01X924157Y257484D02*
X924297D01*
G01X922212Y258647D02*
G03X924157Y257484I2015J1162D01*
G01X919482Y258647D02*
G02X922212I1365J-787D01*
G01X917537Y257484D02*
G03X919482Y258647I-70J2325D01*
G01X917397Y257484D02*
X917537D01*
G01X915452Y258647D02*
G03X917397Y257484I2015J1162D01*
G01X914131Y259435D02*
G02X915452Y258647I-44J-1575D01*
G01X911931Y259435D02*
X914131D01*
G01X911626Y259130D02*
X911931Y259435D01*
G01X950065Y266480D02*
X951267Y263709D01*
G01X947957Y267985D02*
G02X950065Y266480I-69J-2326D01*
G01X947828Y267985D02*
X947957D01*
G01X946522Y268772D02*
G03X947828Y267985I1365J788D01*
G01X944592Y269934D02*
G02X946522Y268772I-85J-2325D01*
G01X944463Y269934D02*
X944592D01*
G01X943142Y270722D02*
G03X944463Y269934I1365J787D01*
G01X941197Y271885D02*
G02X943142Y270722I-70J-2325D01*
G01X941057Y271885D02*
X941197D01*
G01X939112Y270722D02*
G02X941057Y271885I2015J-1162D01*
G01X937791Y269934D02*
G03X939112Y270722I-44J1575D01*
G01X937662Y269934D02*
X937791D01*
G01X935732Y268772D02*
G02X937662Y269934I2015J-1163D01*
G01X934426Y267985D02*
G03X935732Y268772I-59J1575D01*
G01X934297Y267985D02*
X934426D01*
G01X932352Y266822D02*
G02X934297Y267985I2015J-1162D01*
G01X931031Y266034D02*
G03X932352Y266822I-44J1575D01*
G01X930902Y266034D02*
X931031D01*
G01X928972Y264872D02*
G02X930902Y266034I2015J-1163D01*
G01X927666Y264085D02*
G03X928972Y264872I-59J1575D01*
G01X927537Y264085D02*
X927666D01*
G01X925592Y262922D02*
G02X927537Y264085I2015J-1162D01*
G01X922862Y262922D02*
G03X925592I1365J787D01*
G01X920917Y264085D02*
G02X922862Y262922I-70J-2325D01*
G01X920777Y264085D02*
X920917D01*
G01X918832Y262922D02*
G02X920777Y264085I2015J-1162D01*
G01X916102Y262922D02*
G03X918832I1365J787D01*
G01X914157Y264085D02*
G02X916102Y262922I-70J-2325D01*
G01X912951Y264085D02*
X914157D01*
G01X911976Y265060D02*
X912951Y264085D01*
G01X911976Y265467D02*
Y265060D01*
G01X910813Y266630D02*
X911976Y265467D01*
G01X962837Y233788D02*
X964786Y236409D01*
G01X962771Y233672D02*
X962837Y233788D01*
G01X961465Y232885D02*
G03X962771Y233672I-59J1575D01*
G01X961176Y232885D02*
X961465D01*
G01X960253Y233142D02*
X961176Y232885D01*
G01X959107Y233656D02*
X960253Y233142D01*
G01X956675Y233319D02*
G02X959107Y233656I1352J-810D01*
G01X956662Y233296D02*
X956675Y233319D01*
G01X954717Y232134D02*
G03X956662Y233296I-70J2326D01*
G01X954603Y232134D02*
X954717D01*
G01X953282Y231346D02*
G02X954603Y232134I1365J-787D01*
G01X951352Y230184D02*
G03X953282Y231346I-85J2325D01*
G01X951196Y230184D02*
X951352D01*
G01X949902Y229397D02*
G02X951196Y230184I1365J-787D01*
G01X947957Y228234D02*
G03X949902Y229397I-70J2325D01*
G01X947816Y228234D02*
X947957D01*
G01X946522Y227447D02*
G02X947816Y228234I1365J-787D01*
G01X944558Y226284D02*
G03X946522Y227447I-51J2326D01*
G01X944448Y226284D02*
X944558D01*
G01X943142Y225497D02*
G02X944448Y226284I1365J-788D01*
G01X941212Y224335D02*
G03X943142Y225497I-85J2325D01*
G01X941083Y224335D02*
X941212D01*
G01X939762Y223547D02*
G02X941083Y224335I1365J-787D01*
G01X937817Y222384D02*
G03X939762Y223547I-70J2325D01*
G01X937688Y222384D02*
X937817D01*
G01X936382Y221597D02*
G02X937688Y222384I1365J-788D01*
G01X934452Y220435D02*
G03X936382Y221597I-85J2325D01*
G01X934323Y220435D02*
X934452D01*
G01X933002Y219647D02*
G02X934323Y220435I1365J-787D01*
G01X931057Y218484D02*
G03X933002Y219647I-70J2325D01*
G01X930928Y218484D02*
X931057D01*
G01X958385Y234808D02*
X961406Y234460D01*
G01X958111Y234834D02*
G02X958385Y234808I-82J-2325D01*
G01X957928Y234834D02*
X958111D01*
G01X956011Y233673D02*
G02X957928Y234834I2015J-1164D01*
G01X955998Y233650D02*
X956011Y233673D01*
G01X954647Y232885D02*
G03X955998Y233650I0J1575D01*
G01X954596Y232885D02*
X954647D01*
G01X952632Y231722D02*
G02X954596Y232885I2015J-1163D01*
G01X951338Y230935D02*
G03X952632Y231722I-71J1574D01*
G01X951197Y230935D02*
X951338D01*
G01X949252Y229772D02*
G02X951197Y230935I2015J-1162D01*
G01X947958Y228985D02*
G03X949252Y229772I-71J1574D01*
G01X947802Y228985D02*
X947958D01*
G01X945872Y227823D02*
G02X947802Y228985I2015J-1163D01*
G01X944551Y227035D02*
G03X945872Y227823I-44J1575D01*
G01X944456Y227035D02*
X944551D01*
G01X942492Y225872D02*
G02X944456Y227035I2015J-1163D01*
G01X941186Y225085D02*
G03X942492Y225872I-59J1575D01*
G01X941057Y225085D02*
X941186D01*
G01X939112Y223922D02*
G02X941057Y225085I2015J-1162D01*
G01X937791Y223134D02*
G03X939112Y223922I-44J1575D01*
G01X937662Y223134D02*
X937791D01*
G01X935732Y221972D02*
G02X937662Y223134I2015J-1163D01*
G01X934426Y221185D02*
G03X935732Y221972I-59J1575D01*
G01X934297Y221185D02*
X934426D01*
G01X932352Y220022D02*
G02X934297Y221185I2015J-1162D01*
G01X931031Y219234D02*
G03X932352Y220022I-44J1575D01*
G01X930902Y219234D02*
X931031D01*
G01X928972Y218072D02*
G02X930902Y219234I2015J-1163D01*
G01X942558Y233788D02*
X944507Y236409D01*
G01X942492Y233672D02*
X942558Y233788D01*
G01X941186Y232885D02*
G03X942492Y233672I-59J1575D01*
G01X941076Y232885D02*
X941186D01*
G01X939112Y231722D02*
G02X941076Y232885I2015J-1163D01*
G01X937818Y230935D02*
G03X939112Y231722I-71J1574D01*
G01X937677Y230935D02*
X937818D01*
G01X935732Y229772D02*
G02X937677Y230935I2015J-1162D01*
G01X934438Y228985D02*
G03X935732Y229772I-71J1574D01*
G01X934282Y228985D02*
X934438D01*
G01X932352Y227823D02*
G02X934282Y228985I2015J-1163D01*
G01X931031Y227035D02*
G03X932352Y227823I-44J1575D01*
G01X930936Y227035D02*
X931031D01*
G01X928972Y225872D02*
G02X930936Y227035I2015J-1163D01*
G01X927666Y225085D02*
G03X928972Y225872I-59J1575D01*
G01X927537Y225085D02*
X927666D01*
G01X925592Y223922D02*
G02X927537Y225085I2015J-1162D01*
G01X924271Y223134D02*
G03X925592Y223922I-44J1575D01*
G01X921437Y223134D02*
X924271D01*
G01X951413Y262134D02*
X954647Y261760D01*
G01X951223Y262134D02*
X951413D01*
G01X949902Y262922D02*
G03X951223Y262134I1365J787D01*
G01X949748Y263189D02*
X949902Y262922D01*
G01X949544Y264073D02*
X949748Y263189D01*
G01X949460Y265567D02*
X949544Y264073D01*
G01X947931Y267235D02*
G02X949460Y265567I-44J-1575D01*
G01X947802Y267235D02*
X947931D01*
G01X945872Y268397D02*
G03X947802Y267235I2015J1163D01*
G01X944566Y269184D02*
G02X945872Y268397I-59J-1575D01*
G01X944437Y269184D02*
X944566D01*
G01X942492Y270347D02*
G03X944437Y269184I2015J1162D01*
G01X939762Y270347D02*
G02X942492I1365J-787D01*
G01X937817Y269184D02*
G03X939762Y270347I-70J2325D01*
G01X937688Y269184D02*
X937817D01*
G01X936382Y268397D02*
G02X937688Y269184I1365J-788D01*
G01X934452Y267235D02*
G03X936382Y268397I-85J2325D01*
G01X934323Y267235D02*
X934452D01*
G01X933002Y266447D02*
G02X934323Y267235I1365J-787D01*
G01X931057Y265284D02*
G03X933002Y266447I-70J2325D01*
G01X930928Y265284D02*
X931057D01*
G01X929622Y264497D02*
G02X930928Y265284I1365J-788D01*
G01X927692Y263335D02*
G03X929622Y264497I-85J2325D01*
G01X927563Y263335D02*
X927692D01*
G01X926242Y262547D02*
G02X927563Y263335I1365J-787D01*
G01X924297Y261384D02*
G03X926242Y262547I-70J2325D01*
G01X924157Y261384D02*
X924297D01*
G01X922212Y262547D02*
G03X924157Y261384I2015J1162D01*
G01X919482Y262547D02*
G02X922212I1365J-787D01*
G01X917537Y261384D02*
G03X919482Y262547I-70J2325D01*
G01X917397Y261384D02*
X917537D01*
G01X915452Y262547D02*
G03X917397Y261384I2015J1162D01*
G01X914131Y263335D02*
G02X915452Y262547I-44J-1575D01*
G01X911809Y263335D02*
X914131D01*
G01X911014Y264130D02*
X911809Y263335D01*
G01X909976Y264130D02*
X911014D01*
G01X948033Y251635D02*
X951267Y252009D01*
G01X947802Y251635D02*
X948033D01*
G01X945872Y252797D02*
G03X947802Y251635I2015J1163D01*
G01X944566Y253584D02*
G02X945872Y252797I-59J-1575D01*
G01X944437Y253584D02*
X944566D01*
G01X942492Y254747D02*
G03X944437Y253584I2015J1162D01*
G01X939762Y254747D02*
G02X942492I1365J-787D01*
G01X937817Y253584D02*
G03X939762Y254747I-70J2325D01*
G01X937688Y253584D02*
X937817D01*
G01X936382Y252797D02*
G02X937688Y253584I1365J-788D01*
G01X934452Y251635D02*
G03X936382Y252797I-85J2325D01*
G01X934323Y251635D02*
X934452D01*
G01X933002Y250847D02*
G02X934323Y251635I1365J-787D01*
G01X931057Y249684D02*
G03X933002Y250847I-70J2325D01*
G01X930928Y249684D02*
X931057D01*
G01X929622Y248897D02*
G02X930928Y249684I1365J-788D01*
G01X927692Y247735D02*
G03X929622Y248897I-85J2325D01*
G01X927563Y247735D02*
X927692D01*
G01X926242Y246947D02*
G02X927563Y247735I1365J-787D01*
G01X924297Y245784D02*
G03X926242Y246947I-70J2325D01*
G01X924157Y245784D02*
X924297D01*
G01X922212Y246947D02*
G03X924157Y245784I2015J1162D01*
G01X919482Y246947D02*
G02X922212I1365J-787D01*
G01X917537Y245784D02*
G03X919482Y246947I-70J2325D01*
G01X917397Y245784D02*
X917537D01*
G01X915452Y246947D02*
G03X917397Y245784I2015J1162D01*
G01X914131Y247735D02*
G02X915452Y246947I-44J-1575D01*
G01X944466Y252060D02*
X944507Y252009D01*
G01X941670Y252385D02*
X944466Y252060D01*
G01X941057Y252385D02*
X941670D01*
G01X939112Y251222D02*
G02X941057Y252385I2015J-1162D01*
G01X937791Y250434D02*
G03X939112Y251222I-44J1575D01*
G01X937662Y250434D02*
X937791D01*
G01X935732Y249272D02*
G02X937662Y250434I2015J-1163D01*
G01X934426Y248485D02*
G03X935732Y249272I-59J1575D01*
G01X934297Y248485D02*
X934426D01*
G01X932352Y247322D02*
G02X934297Y248485I2015J-1162D01*
G01X931031Y246534D02*
G03X932352Y247322I-44J1575D01*
G01X930902Y246534D02*
X931031D01*
G01X928972Y245372D02*
G02X930902Y246534I2015J-1163D01*
G01X927666Y244585D02*
G03X928972Y245372I-59J1575D01*
G01X927537Y244585D02*
X927666D01*
G01X925592Y243422D02*
G02X927537Y244585I2015J-1162D01*
G01X922862Y243422D02*
G03X925592I1365J787D01*
G01X920917Y244585D02*
G02X922862Y243422I-70J-2325D01*
G01X920777Y244585D02*
X920917D01*
G01X918832Y243422D02*
G02X920777Y244585I2015J-1162D01*
G01X917511Y242634D02*
G03X918832Y243422I-44J1575D01*
G01X916812Y242634D02*
X917511D01*
G01X915959Y243411D02*
G03X916812Y242634I1508J798D01*
G01X914585Y244585D02*
G02X915959Y243411I-798J-2325D01*
G01X912724Y244585D02*
X914585D01*
G01X912505Y244366D02*
X912724Y244585D01*
G01X912505Y244364D02*
Y244366D01*
G01X912506Y244364D02*
X912505D01*
G01X910774Y242632D02*
X912506Y244364D01*
G01X910411Y242632D02*
X910774D01*
G01X910408Y242635D02*
X910411Y242632D01*
G01X964928Y234084D02*
X968166Y234460D01*
G01X964727Y234084D02*
X964928D01*
G01X963232Y232248D02*
G02X964727Y234084I1554J261D01*
G01X962980Y230134D02*
X963232Y232248D01*
G01X962681Y229467D02*
X962980Y230134D01*
G01X962256Y229203D02*
X962681Y229467D01*
G01X961906Y228985D02*
X962256Y229203D01*
G01X960826Y228985D02*
X961906D01*
G01X959202Y229659D02*
X960826Y228985D01*
G01X958821Y229971D02*
G02X959202Y229659I-796J-1360D01*
G01X958097Y230184D02*
G02X958821Y229971I-70J-1574D01*
G01X958026Y230184D02*
X958097D01*
G01X956675Y229419D02*
G02X958026Y230184I1351J-810D01*
G01X956662Y229396D02*
X956675Y229419D01*
G01X954732Y228234D02*
G03X956662Y229396I-85J2325D01*
G01X954576Y228234D02*
X954732D01*
G01X953282Y227447D02*
G02X954576Y228234I1365J-787D01*
G01X951318Y226284D02*
G03X953282Y227447I-51J2326D01*
G01X951208Y226284D02*
X951318D01*
G01X949902Y225497D02*
G02X951208Y226284I1365J-788D01*
G01X947972Y224335D02*
G03X949902Y225497I-85J2325D01*
G01X947843Y224335D02*
X947972D01*
G01X946522Y223547D02*
G02X947843Y224335I1365J-787D01*
G01X944577Y222384D02*
G03X946522Y223547I-70J2325D01*
G01X944448Y222384D02*
X944577D01*
G01X943142Y221597D02*
G02X944448Y222384I1365J-788D01*
G01X941212Y220435D02*
G03X943142Y221597I-85J2325D01*
G01X941083Y220435D02*
X941212D01*
G01X939762Y219647D02*
G02X941083Y220435I1365J-787D01*
G01X937817Y218484D02*
G03X939762Y219647I-70J2325D01*
G01X937688Y218484D02*
X937817D01*
G01X962837Y222088D02*
X964786Y224709D01*
G01X962771Y221972D02*
X962837Y222088D01*
G01X961465Y221185D02*
G03X962771Y221972I-59J1575D01*
G01X961336Y221185D02*
X961465D01*
G01X959391Y220022D02*
G02X961336Y221185I2015J-1162D01*
G01X958070Y219234D02*
G03X959391Y220022I-44J1575D01*
G01X957928Y219234D02*
X958070D01*
G01X956011Y218073D02*
G02X957928Y219234I2015J-1164D01*
G01X955998Y218050D02*
X956011Y218073D01*
G01X942558Y229888D02*
X944507Y232509D01*
G01X942492Y229772D02*
X942558Y229888D01*
G01X941198Y228985D02*
G03X942492Y229772I-71J1574D01*
G01X941042Y228985D02*
X941198D01*
G01X939112Y227823D02*
G02X941042Y228985I2015J-1163D01*
G01X937791Y227035D02*
G03X939112Y227823I-44J1575D01*
G01X937696Y227035D02*
X937791D01*
G01X935732Y225872D02*
G02X937696Y227035I2015J-1163D01*
G01X934426Y225085D02*
G03X935732Y225872I-59J1575D01*
G01X934297Y225085D02*
X934426D01*
G01X932352Y223922D02*
G02X934297Y225085I2015J-1162D01*
G01X931031Y223134D02*
G03X932352Y223922I-44J1575D01*
G01X930902Y223134D02*
X931031D01*
G01X928972Y221972D02*
G02X930902Y223134I2015J-1163D01*
G01X927666Y221185D02*
G03X928972Y221972I-59J1575D01*
G01X927537Y221185D02*
X927666D01*
G01X925592Y220022D02*
G02X927537Y221185I2015J-1162D01*
G01X924271Y219234D02*
G03X925592Y220022I-44J1575D01*
G01X921809Y219234D02*
X924271D01*
G01X970247Y225611D02*
X971546Y228610D01*
G01X970181Y225497D02*
X970247Y225611D01*
G01X968251Y224335D02*
G03X970181Y225497I-85J2325D01*
G01X968122Y224335D02*
X968251D01*
G01X966801Y223547D02*
G02X968122Y224335I1365J-787D01*
G01X964856Y222384D02*
G03X966801Y223547I-70J2325D01*
G01X964727Y222384D02*
X964856D01*
G01X963421Y221597D02*
G02X964727Y222384I1365J-788D01*
G01X961491Y220435D02*
G03X963421Y221597I-85J2325D01*
G01X961362Y220435D02*
X961491D01*
G01X960041Y219647D02*
G02X961362Y220435I1365J-787D01*
G01X958096Y218484D02*
G03X960041Y219647I-70J2325D01*
G01X958026Y218484D02*
X958096D01*
G01X966587Y220568D02*
X968166Y222760D01*
G01X966151Y220022D02*
G02X966587Y220568I2015J-1162D01*
G01X964830Y219234D02*
G03X966151Y220022I-44J1575D01*
G01X964701Y219234D02*
X964830D01*
G01X962771Y218072D02*
G02X964701Y219234I2015J-1163D01*
G01X945872Y340922D02*
G02X946587Y341335I715J-412D01*
G01X944510Y340135D02*
G03X945872Y340922I0J1572D01*
G01X944504Y340135D02*
X944510D01*
G01X943566Y340446D02*
G03X944504Y340135I939J1261D01*
G01X941726Y341335D02*
X943566Y340446D01*
G01X922212Y340547D02*
G03X920891Y341335I-1365J-787D01*
G01X924157Y339384D02*
G02X922212Y340547I70J2325D01*
G01X924286Y339384D02*
X924157D01*
G01X925592Y338597D02*
G03X924286Y339384I-1365J-788D01*
G01X927522Y337435D02*
G02X925592Y338597I85J2325D01*
G01X927651Y337435D02*
X927522D01*
G01X928972Y336647D02*
G03X927651Y337435I-1365J-787D01*
G01X930917Y335484D02*
G02X928972Y336647I70J2325D01*
G01X931046Y335484D02*
X930917D01*
G01X932352Y334697D02*
G03X931046Y335484I-1365J-788D01*
G01X934282Y333535D02*
G02X932352Y334697I85J2325D01*
G01X934411Y333535D02*
X934282D01*
G01X935732Y332747D02*
G03X934411Y333535I-1365J-787D01*
G01X937677Y331584D02*
G02X935732Y332747I70J2325D01*
G01X937806Y331584D02*
X937677D01*
G01X939112Y330797D02*
G03X937806Y331584I-1365J-788D01*
G01X941042Y329635D02*
G02X939112Y330797I85J2325D01*
G01X941212Y329635D02*
X941042D01*
G01X943142Y330797D02*
G02X941212Y329635I-2015J1163D01*
G01X944448Y331584D02*
G03X943142Y330797I59J-1575D01*
G01X944577Y331584D02*
X944448D01*
G01X946522Y332747D02*
G02X944577Y331584I-2015J1162D01*
G01X947843Y333535D02*
G03X946522Y332747I44J-1575D01*
G01X947972Y333535D02*
X947843D01*
G01X949902Y334697D02*
G02X947972Y333535I-2015J1163D01*
G01X951208Y335484D02*
G03X949902Y334697I59J-1575D01*
G01X951337Y335484D02*
X951208D01*
G01X953282Y336647D02*
G02X951337Y335484I-2015J1162D01*
G01X953350Y336764D02*
X953282Y336647D01*
G01X954647Y339760D02*
X953350Y336764D01*
G01X911462Y339642D02*
X910609Y338789D01*
G01X911462Y340808D02*
Y339642D01*
G01X912739Y342085D02*
X911462Y340808D01*
G01X916102Y340922D02*
G03X914157Y342085I-2015J-1162D01*
G01X917423Y340134D02*
G02X916102Y340922I44J1575D01*
G01X917552Y340134D02*
X917423D01*
G01X919482Y338972D02*
G03X917552Y340134I-2015J-1163D01*
G01X920788Y338185D02*
G02X919482Y338972I59J1575D01*
G01X920917Y338185D02*
X920788D01*
G01X922862Y337022D02*
G03X920917Y338185I-2015J-1162D01*
G01X924183Y336234D02*
G02X922862Y337022I44J1575D01*
G01X924312Y336234D02*
X924183D01*
G01X926242Y335072D02*
G03X924312Y336234I-2015J-1163D01*
G01X927548Y334285D02*
G02X926242Y335072I59J1575D01*
G01X927677Y334285D02*
X927548D01*
G01X929622Y333122D02*
G03X927677Y334285I-2015J-1162D01*
G01X930943Y332334D02*
G02X929622Y333122I44J1575D01*
G01X931072Y332334D02*
X930943D01*
G01X933002Y331172D02*
G03X931072Y332334I-2015J-1163D01*
G01X934308Y330385D02*
G02X933002Y331172I59J1575D01*
G01X934437Y330385D02*
X934308D01*
G01X936382Y329222D02*
G03X934437Y330385I-2015J-1162D01*
G01X937676Y328435D02*
G02X936382Y329222I71J1574D01*
G01X937832Y328435D02*
X937676D01*
G01X939762Y327273D02*
G03X937832Y328435I-2015J-1163D01*
G01X942492Y327273D02*
G02X939762I-1365J787D01*
G01X944422Y328435D02*
G03X942492Y327273I85J-2325D01*
G01X944578Y328435D02*
X944422D01*
G01X945872Y329222D02*
G02X944578Y328435I-1365J787D01*
G01X947817Y330385D02*
G03X945872Y329222I70J-2325D01*
G01X947946Y330385D02*
X947817D01*
G01X949252Y331172D02*
G02X947946Y330385I-1365J788D01*
G01X949318Y331288D02*
X949252Y331172D01*
G01X951267Y333909D02*
X949318Y331288D01*
G01X922862Y340922D02*
G03X920917Y342085I-2015J-1162D01*
G01X924183Y340134D02*
G02X922862Y340922I44J1575D01*
G01X924312Y340134D02*
X924183D01*
G01X926242Y338972D02*
G03X924312Y340134I-2015J-1163D01*
G01X927548Y338185D02*
G02X926242Y338972I59J1575D01*
G01X927677Y338185D02*
X927548D01*
G01X929622Y337022D02*
G03X927677Y338185I-2015J-1162D01*
G01X930943Y336234D02*
G02X929622Y337022I44J1575D01*
G01X931072Y336234D02*
X930943D01*
G01X933002Y335072D02*
G03X931072Y336234I-2015J-1163D01*
G01X934308Y334285D02*
G02X933002Y335072I59J1575D01*
G01X934437Y334285D02*
X934308D01*
G01X936382Y333122D02*
G03X934437Y334285I-2015J-1162D01*
G01X937703Y332334D02*
G02X936382Y333122I44J1575D01*
G01X937832Y332334D02*
X937703D01*
G01X939762Y331172D02*
G03X937832Y332334I-2015J-1163D01*
G01X941068Y330385D02*
G02X939762Y331172I59J1575D01*
G01X941186Y330385D02*
X941068D01*
G01X942492Y331172D02*
G02X941186Y330385I-1365J788D01*
G01X944422Y332334D02*
G03X942492Y331172I85J-2325D01*
G01X944551Y332334D02*
X944422D01*
G01X945872Y333122D02*
G02X944551Y332334I-1365J787D01*
G01X945938Y333238D02*
X945872Y333122D01*
G01X947887Y335860D02*
X945938Y333238D01*
G01X912212Y339297D02*
X910954Y338039D01*
G01X912212Y340497D02*
Y339297D01*
G01X913050Y341335D02*
X912212Y340497D01*
G01X915452Y340547D02*
G03X914131Y341335I-1365J-787D01*
G01X917397Y339384D02*
G02X915452Y340547I70J2325D01*
G01X917526Y339384D02*
X917397D01*
G01X918832Y338597D02*
G03X917526Y339384I-1365J-788D01*
G01X920762Y337435D02*
G02X918832Y338597I85J2325D01*
G01X920891Y337435D02*
X920762D01*
G01X922212Y336647D02*
G03X920891Y337435I-1365J-787D01*
G01X924157Y335484D02*
G02X922212Y336647I70J2325D01*
G01X924286Y335484D02*
X924157D01*
G01X925592Y334697D02*
G03X924286Y335484I-1365J-788D01*
G01X927522Y333535D02*
G02X925592Y334697I85J2325D01*
G01X927651Y333535D02*
X927522D01*
G01X928972Y332747D02*
G03X927651Y333535I-1365J-787D01*
G01X930917Y331584D02*
G02X928972Y332747I70J2325D01*
G01X931046Y331584D02*
X930917D01*
G01X932352Y330797D02*
G03X931046Y331584I-1365J-788D01*
G01X934282Y329635D02*
G02X932352Y330797I85J2325D01*
G01X934411Y329635D02*
X934282D01*
G01X935732Y328847D02*
G03X934411Y329635I-1365J-787D01*
G01X937677Y327684D02*
G02X935732Y328847I70J2325D01*
G01X937818Y327684D02*
X937677D01*
G01X939112Y326897D02*
G03X937818Y327684I-1365J-787D01*
G01X941042Y325735D02*
G02X939112Y326897I85J2325D01*
G01X941212Y325735D02*
X941042D01*
G01X943142Y326897D02*
G02X941212Y325735I-2015J1163D01*
G01X944436Y327684D02*
G03X943142Y326897I71J-1574D01*
G01X944577Y327684D02*
X944436D01*
G01X946522Y328847D02*
G02X944577Y327684I-2015J1162D01*
G01X947843Y329635D02*
G03X946522Y328847I44J-1575D01*
G01X947972Y329635D02*
X947843D01*
G01X949902Y330797D02*
G02X947972Y329635I-2015J1163D01*
G01X951208Y331584D02*
G03X949902Y330797I59J-1575D01*
G01X951337Y331584D02*
X951208D01*
G01X953282Y332747D02*
G02X951337Y331584I-2015J1162D01*
G01X953350Y332864D02*
X953282Y332747D01*
G01X954647Y335860D02*
X953350Y332864D01*
G01X917979Y394888D02*
X910042D01*
G01X919173Y394106D02*
X917979Y394888D01*
G01X919410Y393692D02*
X919173Y394106D01*
G01X919507Y393530D02*
X919410Y393692D01*
G01X919482Y391247D02*
G03X919507Y393530I-2015J1164D01*
G01X919463Y391213D02*
X919482Y391247D01*
G01Y389672D02*
G02X919463Y391213I1365J787D01*
G01X919507Y387389D02*
G03X919482Y389672I-2040J1119D01*
G01Y387347D02*
X919507Y387389D01*
G01X919463Y387313D02*
X919482Y387347D01*
G01Y385772D02*
G02X919463Y387313I1365J787D01*
G01X919507Y383489D02*
G03X919482Y385772I-2040J1119D01*
G01X919155Y382879D02*
X919507Y383489D01*
G01X920190Y381085D02*
G02X919155Y382879I657J1575D01*
G01X920917Y381085D02*
X920190D01*
G01X922862Y379922D02*
G03X920917Y381085I-2015J-1162D01*
G01X924183Y379134D02*
G02X922862Y379922I44J1575D01*
G01X924312Y379134D02*
X924183D01*
G01X926242Y377972D02*
G03X924312Y379134I-2015J-1163D01*
G01X927548Y377185D02*
G02X926242Y377972I59J1575D01*
G01X927677Y377185D02*
X927548D01*
G01X929622Y376022D02*
G03X927677Y377185I-2015J-1162D01*
G01X930943Y375234D02*
G02X929622Y376022I44J1575D01*
G01X931072Y375234D02*
X930943D01*
G01X933002Y374072D02*
G03X931072Y375234I-2015J-1163D01*
G01X934308Y373285D02*
G02X933002Y374072I59J1575D01*
G01X934418Y373285D02*
X934308D01*
G01X936382Y372122D02*
G03X934418Y373285I-2015J-1163D01*
G01X937676Y371335D02*
G02X936382Y372122I71J1574D01*
G01X937817Y371335D02*
X937676D01*
G01X939762Y370172D02*
G03X937817Y371335I-2015J-1162D01*
G01X941056Y369385D02*
G02X939762Y370172I71J1574D01*
G01X941212Y369385D02*
X941056D01*
G01X943142Y368223D02*
G03X941212Y369385I-2015J-1163D01*
G01X944463Y367435D02*
G02X943142Y368223I44J1575D01*
G01X944644Y367435D02*
X944463D01*
G01X947887Y367060D02*
X944644Y367435D01*
G01X915304Y388251D02*
X914066Y389489D01*
G01X915304Y379851D02*
Y388251D01*
G01X916966Y378189D02*
X915304Y379851D01*
G01X920727Y378189D02*
X916966D01*
G01X922741Y376175D02*
X920727Y378189D01*
G01X922862Y376022D02*
G03X922741Y376175I-580J-335D01*
G01X924156Y375235D02*
G02X922862Y376022I71J1574D01*
G01X924297Y375235D02*
X924156D01*
G01X926242Y374072D02*
G03X924297Y375235I-2015J-1162D01*
G01X927548Y373285D02*
G02X926242Y374072I59J1575D01*
G01X927658Y373285D02*
X927548D01*
G01X929622Y372122D02*
G03X927658Y373285I-2015J-1163D01*
G01X930916Y371335D02*
G02X929622Y372122I71J1574D01*
G01X931057Y371335D02*
X930916D01*
G01X933002Y370172D02*
G03X931057Y371335I-2015J-1162D01*
G01X934296Y369385D02*
G02X933002Y370172I71J1574D01*
G01X934452Y369385D02*
X934296D01*
G01X936382Y368223D02*
G03X934452Y369385I-2015J-1163D01*
G01X937703Y367435D02*
G02X936382Y368223I44J1575D01*
G01X937798Y367435D02*
X937703D01*
G01X939762Y366272D02*
G03X937798Y367435I-2015J-1163D01*
G01X941068Y365485D02*
G02X939762Y366272I59J1575D01*
G01X941269Y365485D02*
X941068D01*
G01X944507Y365109D02*
X941269Y365485D01*
G01X922348Y400314D02*
Y403207D01*
G01X922862Y399422D02*
X922348Y400314D01*
G01X924183Y398634D02*
G02X922862Y399422I44J1575D01*
G01X924312Y398634D02*
X924183D01*
G01X926242Y395146D02*
G03X924312Y398634I-2015J1163D01*
G01X926242Y393572D02*
G02Y395146I1365J787D01*
G01X926267Y393530D02*
X926242Y393572D01*
G01Y391247D02*
G03X926267Y393530I-2015J1164D01*
G01X926242Y389673D02*
G02Y391247I1365J787D01*
G01Y387347D02*
G03Y389673I-2015J1163D01*
G01X927563Y384985D02*
G02X926242Y387347I44J1575D01*
G01X927677Y384985D02*
X927563D01*
G01X929622Y383822D02*
G03X927677Y384985I-2015J-1162D01*
G01X930943Y383034D02*
G02X929622Y383822I44J1575D01*
G01X931072Y383034D02*
X930943D01*
G01X933002Y381872D02*
G03X931072Y383034I-2015J-1163D01*
G01X934308Y381085D02*
G02X933002Y381872I59J1575D01*
G01X934437Y381085D02*
X934308D01*
G01X936382Y379922D02*
G03X934437Y381085I-2015J-1162D01*
G01X937703Y379134D02*
G02X936382Y379922I44J1575D01*
G01X937832Y379134D02*
X937703D01*
G01X939762Y377972D02*
G03X937832Y379134I-2015J-1163D01*
G01X941068Y377185D02*
G02X939762Y377972I59J1575D01*
G01X941197Y377185D02*
X941068D01*
G01X943142Y376022D02*
G03X941197Y377185I-2015J-1162D01*
G01X944463Y375234D02*
G02X943142Y376022I44J1575D01*
G01X944592Y375234D02*
X944463D01*
G01X946522Y374072D02*
G03X944592Y375234I-2015J-1163D01*
G01X947828Y373285D02*
G02X946522Y374072I59J1575D01*
G01X947938Y373285D02*
X947828D01*
G01X949902Y372122D02*
G03X947938Y373285I-2015J-1163D01*
G01X951196Y371335D02*
G02X949902Y372122I71J1574D01*
G01X951337Y371335D02*
X951196D01*
G01X953282Y370172D02*
G03X951337Y371335I-2015J-1162D01*
G01X954576Y369385D02*
G02X953282Y370172I71J1574D01*
G01X954732Y369385D02*
X954576D01*
G01X956662Y368223D02*
G03X954732Y369385I-2015J-1163D01*
G01X956675Y368200D02*
X956662Y368223D01*
G01X958026Y367435D02*
G02X956675Y368200I0J1575D01*
G01X959132Y367435D02*
X958026D01*
G01X959219Y367427D02*
X959132Y367435D01*
G01X961406Y367060D02*
X959219Y367427D01*
G01X939360Y399799D02*
Y405584D01*
G01X939112Y399422D02*
X939360Y399799D01*
G01X939087Y399380D02*
X939112Y399422D01*
G01Y397097D02*
G02X939087Y399380I2015J1164D01*
G01X939131Y395556D02*
G03X939112Y397097I-1384J754D01*
G01Y395522D02*
X939131Y395556D01*
G01X939087Y393239D02*
G02X939112Y395522I2040J1119D01*
G01Y393197D02*
X939087Y393239D01*
G01X939112Y391623D02*
G03Y393197I-1365J787D01*
G01X941042Y388135D02*
G02X939112Y391623I85J2325D01*
G01X941171Y388135D02*
X941042D01*
G01X942492Y387347D02*
G03X941171Y388135I-1365J-787D01*
G01X944437Y386184D02*
G02X942492Y387347I70J2325D01*
G01X944566Y386184D02*
X944437D01*
G01X945872Y385397D02*
G03X944566Y386184I-1365J-788D01*
G01X947802Y384235D02*
G02X945872Y385397I85J2325D01*
G01X947931Y384235D02*
X947802D01*
G01X949252Y383447D02*
G03X947931Y384235I-1365J-787D01*
G01X951197Y382284D02*
G02X949252Y383447I70J2325D01*
G01X951326Y382284D02*
X951197D01*
G01X952632Y381497D02*
G03X951326Y382284I-1365J-788D01*
G01X954562Y380335D02*
G02X952632Y381497I85J2325D01*
G01X954647Y380335D02*
X954562D01*
G01X955998Y379570D02*
G03X954647Y380335I-1351J-810D01*
G01X956011Y379547D02*
X955998Y379570D01*
G01X957956Y378384D02*
G02X956011Y379547I70J2325D01*
G01X958085Y378384D02*
X957956D01*
G01X959391Y377597D02*
G03X958085Y378384I-1365J-788D01*
G01X961321Y376435D02*
G02X959391Y377597I85J2325D01*
G01X961450Y376435D02*
X961321D01*
G01X962771Y374072D02*
G03X961450Y376435I-1365J788D01*
G01X962771Y373249D02*
G02Y374072I713J412D01*
G01X963421Y372122D02*
X962771Y373249D01*
G01X964715Y371335D02*
G02X963421Y372122I71J1574D01*
G01X964856Y371335D02*
X964715D01*
G01X966801Y370172D02*
G03X964856Y371335I-2015J-1162D01*
G01X968095Y369385D02*
G02X966801Y370172I71J1574D01*
G01X968310Y369385D02*
X968095D01*
G01X971546Y369010D02*
X968310Y369385D01*
G01X920047Y380335D02*
G02X918434Y383132I800J2325D01*
G01X920891Y380335D02*
X920047D01*
G01X922212Y379547D02*
G03X920891Y380335I-1365J-787D01*
G01X924157Y378384D02*
G02X922212Y379547I70J2325D01*
G01X924286Y378384D02*
X924157D01*
G01X925592Y377597D02*
G03X924286Y378384I-1365J-788D01*
G01X927522Y376435D02*
G02X925592Y377597I85J2325D01*
G01X927651Y376435D02*
X927522D01*
G01X928972Y375647D02*
G03X927651Y376435I-1365J-787D01*
G01X930917Y374484D02*
G02X928972Y375647I70J2325D01*
G01X931046Y374484D02*
X930917D01*
G01X932352Y373697D02*
G03X931046Y374484I-1365J-788D01*
G01X934316Y372534D02*
G02X932352Y373697I51J2326D01*
G01X934411Y372534D02*
X934316D01*
G01X935732Y371746D02*
G03X934411Y372534I-1365J-787D01*
G01X937662Y370584D02*
G02X935732Y371746I85J2325D01*
G01X937818Y370584D02*
X937662D01*
G01X939112Y369797D02*
G03X937818Y370584I-1365J-787D01*
G01X941057Y368634D02*
G02X939112Y369797I70J2325D01*
G01X941198Y368634D02*
X941057D01*
G01X942492Y367847D02*
G03X941198Y368634I-1365J-787D01*
G01X944456Y366684D02*
G02X942492Y367847I51J2326D01*
G01X944566Y366684D02*
X944456D01*
G01X945872Y365897D02*
G03X944566Y366684I-1365J-788D01*
G01X947802Y364735D02*
G02X945872Y365897I85J2325D01*
G01X948033Y364735D02*
X947802D01*
G01X951267Y365109D02*
X948033Y364735D01*
G01X918612Y393578D02*
X917755Y394140D01*
G01X918832Y393197D02*
X918612Y393578D01*
G01X918832Y391623D02*
G03Y393197I-1365J787D01*
G01Y389297D02*
G02Y391623I2015J1163D01*
G01X918851Y387756D02*
G03X918832Y389297I-1384J754D01*
G01Y387722D02*
X918851Y387756D01*
G01X918807Y387680D02*
X918832Y387722D01*
G01Y385397D02*
G02X918807Y387680I2015J1164D01*
G01X918851Y383856D02*
G03X918832Y385397I-1384J754D01*
G01X918434Y383132D02*
X918851Y383856D01*
G01X949968Y342610D02*
X951267Y345609D01*
G01X949902Y342497D02*
X949968Y342610D01*
G01X947972Y341335D02*
G03X949902Y342497I-85J2325D01*
G01X946587Y341335D02*
X947972D01*
G01X941042D02*
X941726D01*
G01X939112Y342497D02*
G03X941042Y341335I2015J1163D01*
G01X937806Y343284D02*
G02X939112Y342497I-59J-1575D01*
G01X937677Y343284D02*
X937806D01*
G01X935732Y344447D02*
G03X937677Y343284I2015J1162D01*
G01X934411Y345235D02*
G02X935732Y344447I-44J-1575D01*
G01X934282Y345235D02*
X934411D01*
G01X932352Y346397D02*
G03X934282Y345235I2015J1163D01*
G01X931046Y347184D02*
G02X932352Y346397I-59J-1575D01*
G01X930917Y347184D02*
X931046D01*
G01X928972Y348347D02*
G03X930917Y347184I2015J1162D01*
G01X927651Y349135D02*
G02X928972Y348347I-44J-1575D01*
G01X927522Y349135D02*
X927651D01*
G01X925592Y350297D02*
G03X927522Y349135I2015J1163D01*
G01X924286Y351084D02*
G02X925592Y350297I-59J-1575D01*
G01X924157Y351084D02*
X924286D01*
G01X922212Y352247D02*
G03X924157Y351084I2015J1162D01*
G01X920891Y353035D02*
G02X922212Y352247I-44J-1575D01*
G01X920762Y353035D02*
X920891D01*
G01X918832Y354197D02*
G03X920762Y353035I2015J1163D01*
G01X917526Y354984D02*
G02X918832Y354197I-59J-1575D01*
G01X916669Y354984D02*
X917526D01*
G01X912568Y356935D02*
X912274Y356641D01*
G01X913787Y356935D02*
X912568D01*
G01X915295Y356158D02*
G03X913787Y356935I-1508J-1075D01*
G01X916669Y354984D02*
G02X915295Y356158I798J2325D01*
G01X912300Y345235D02*
X910406Y343341D01*
G01X914131Y345235D02*
X912300D01*
G01X915452Y344447D02*
G03X914131Y345235I-1365J-787D01*
G01X917397Y343284D02*
G02X915452Y344447I70J2325D01*
G01X917526Y343284D02*
X917397D01*
G01X918832Y342497D02*
G03X917526Y343284I-1365J-788D01*
G01X920762Y341335D02*
G02X918832Y342497I85J2325D01*
G01X920891Y341335D02*
X920762D01*
G01X914556Y387941D02*
X913756Y388741D01*
G01X914556Y379541D02*
Y387941D01*
G01X916656Y377441D02*
X914556Y379541D01*
G01X920417Y377441D02*
X916656D01*
G01X922212Y375646D02*
X920417Y377441D01*
G01X924142Y374484D02*
G02X922212Y375646I85J2325D01*
G01X924298Y374484D02*
X924142D01*
G01X925592Y373697D02*
G03X924298Y374484I-1365J-787D01*
G01X927556Y372534D02*
G02X925592Y373697I51J2326D01*
G01X927651Y372534D02*
X927556D01*
G01X928972Y371746D02*
G03X927651Y372534I-1365J-787D01*
G01X930902Y370584D02*
G02X928972Y371746I85J2325D01*
G01X931058Y370584D02*
X930902D01*
G01X932352Y369797D02*
G03X931058Y370584I-1365J-787D01*
G01X934297Y368634D02*
G02X932352Y369797I70J2325D01*
G01X934438Y368634D02*
X934297D01*
G01X935732Y367847D02*
G03X934438Y368634I-1365J-787D01*
G01X937696Y366684D02*
G02X935732Y367847I51J2326D01*
G01X937806Y366684D02*
X937696D01*
G01X939112Y365897D02*
G03X937806Y366684I-1365J-788D01*
G01X941042Y364735D02*
G02X939112Y365897I85J2325D01*
G01X941171Y364735D02*
X941042D01*
G01X942492Y363947D02*
G03X941171Y364735I-1365J-787D01*
G01X942558Y363831D02*
X942492Y363947D01*
G01X944507Y361209D02*
X942558Y363831D01*
G01X912078Y359961D02*
X910356Y361683D01*
G01X915062Y359961D02*
X912078D01*
G01X916139Y358884D02*
X915062Y359961D01*
G01X917526Y358884D02*
X916139D01*
G01X918832Y358097D02*
G03X917526Y358884I-1365J-788D01*
G01X920671Y356940D02*
G02X918832Y358097I178J2323D01*
G01X921020Y356926D02*
G03X920671Y356940I-274J-2484D01*
G01X922212Y356147D02*
G03X921020Y356926I-1365J-787D01*
G01X924157Y354984D02*
G02X922212Y356147I70J2325D01*
G01X924286Y354984D02*
X924157D01*
G01X925592Y354197D02*
G03X924286Y354984I-1365J-788D01*
G01X927522Y353035D02*
G02X925592Y354197I85J2325D01*
G01X927651Y353035D02*
X927522D01*
G01X928972Y352247D02*
G03X927651Y353035I-1365J-787D01*
G01X930917Y351084D02*
G02X928972Y352247I70J2325D01*
G01X931046Y351084D02*
X930917D01*
G01X932352Y350297D02*
G03X931046Y351084I-1365J-788D01*
G01X934282Y349135D02*
G02X932352Y350297I85J2325D01*
G01X934411Y349135D02*
X934282D01*
G01X935732Y348347D02*
G03X934411Y349135I-1365J-787D01*
G01X937677Y347184D02*
G02X935732Y348347I70J2325D01*
G01X937806Y347184D02*
X937677D01*
G01X939112Y346397D02*
G03X937806Y347184I-1365J-788D01*
G01X941042Y345235D02*
G02X939112Y346397I85J2325D01*
G01X941171Y345235D02*
X941042D01*
G01X942492Y344447D02*
G03X941171Y345235I-1365J-787D01*
G01X944437Y343284D02*
G02X942492Y344447I70J2325D01*
G01X944577Y343284D02*
X944437D01*
G01X946522Y344447D02*
G02X944577Y343284I-2015J1162D01*
G01X946590Y344564D02*
X946522Y344447D01*
G01X947887Y347560D02*
X946590Y344564D01*
G01X918169Y363889D02*
X913766D01*
G01X921597Y360461D02*
X918169Y363889D01*
G01X922677Y360461D02*
X921597D01*
G01X923504Y359634D02*
X922677Y360461D01*
G01X924312Y359634D02*
X923504D01*
G01X926242Y358472D02*
G03X924312Y359634I-2015J-1163D01*
G01X927548Y357685D02*
G02X926242Y358472I59J1575D01*
G01X927677Y357685D02*
X927548D01*
G01X929622Y356522D02*
G03X927677Y357685I-2015J-1162D01*
G01X930943Y355734D02*
G02X929622Y356522I44J1575D01*
G01X931072Y355734D02*
X930943D01*
G01X933002Y354572D02*
G03X931072Y355734I-2015J-1163D01*
G01X934308Y353785D02*
G02X933002Y354572I59J1575D01*
G01X934437Y353785D02*
X934308D01*
G01X936382Y352622D02*
G03X934437Y353785I-2015J-1162D01*
G01X937703Y351834D02*
G02X936382Y352622I44J1575D01*
G01X937832Y351834D02*
X937703D01*
G01X939762Y350672D02*
G03X937832Y351834I-2015J-1163D01*
G01X941068Y349885D02*
G02X939762Y350672I59J1575D01*
G01X941197Y349885D02*
X941068D01*
G01X943142Y348722D02*
G03X941197Y349885I-2015J-1162D01*
G01X945872Y348722D02*
G02X943142I-1365J787D01*
G01X947817Y349885D02*
G03X945872Y348722I70J-2325D01*
G01X947946Y349885D02*
X947817D01*
G01X949252Y350672D02*
G02X947946Y349885I-1365J788D01*
G01X949318Y350788D02*
X949252Y350672D01*
G01X951267Y353409D02*
X949318Y350788D01*
G01X914157Y342085D02*
X912739D01*
G01X917856Y363141D02*
X913456D01*
G01X921286Y359711D02*
X917856Y363141D01*
G01X922364Y359711D02*
X921286D01*
G01X923191Y358884D02*
X922364Y359711D01*
G01X924286Y358884D02*
X923191D01*
G01X925592Y358097D02*
G03X924286Y358884I-1365J-788D01*
G01X927522Y356935D02*
G02X925592Y358097I85J2325D01*
G01X927651Y356935D02*
X927522D01*
G01X928972Y356147D02*
G03X927651Y356935I-1365J-787D01*
G01X930917Y354984D02*
G02X928972Y356147I70J2325D01*
G01X931046Y354984D02*
X930917D01*
G01X932352Y354197D02*
G03X931046Y354984I-1365J-788D01*
G01X934282Y353035D02*
G02X932352Y354197I85J2325D01*
G01X934411Y353035D02*
X934282D01*
G01X935732Y352247D02*
G03X934411Y353035I-1365J-787D01*
G01X937677Y351084D02*
G02X935732Y352247I70J2325D01*
G01X937806Y351084D02*
X937677D01*
G01X939112Y350297D02*
G03X937806Y351084I-1365J-788D01*
G01X941042Y349135D02*
G02X939112Y350297I85J2325D01*
G01X941171Y349135D02*
X941042D01*
G01X942492Y348347D02*
G03X941171Y349135I-1365J-787D01*
G01X944437Y347184D02*
G02X942492Y348347I70J2325D01*
G01X944577Y347184D02*
X944437D01*
G01X946522Y348347D02*
G02X944577Y347184I-2015J1162D01*
G01X947843Y349135D02*
G03X946522Y348347I44J-1575D01*
G01X947972Y349135D02*
X947843D01*
G01X949902Y350297D02*
G02X947972Y349135I-2015J1163D01*
G01X951208Y351084D02*
G03X949902Y350297I59J-1575D01*
G01X951337Y351084D02*
X951208D01*
G01X953282Y352247D02*
G02X951337Y351084I-2015J1162D01*
G01X953350Y352364D02*
X953282Y352247D01*
G01X954647Y355360D02*
X953350Y352364D01*
G01X911992Y345985D02*
X910096Y344089D01*
G01X914141Y345985D02*
X911992D01*
G01X916102Y344822D02*
G03X914141Y345985I-2015J-1162D01*
G01X917423Y344034D02*
G02X916102Y344822I44J1575D01*
G01X917552Y344034D02*
X917423D01*
G01X919482Y342872D02*
G03X917552Y344034I-2015J-1163D01*
G01X920788Y342085D02*
G02X919482Y342872I59J1575D01*
G01X920917Y342085D02*
X920788D01*
G01X912260Y357685D02*
X911964Y357389D01*
G01X913787Y357685D02*
X912260D01*
G01X916080Y356316D02*
G03X913787Y357685I-2293J-1236D01*
G01X916812Y355734D02*
G02X916080Y356316I655J1575D01*
G01X917552Y355734D02*
X916812D01*
G01X919482Y354572D02*
G03X917552Y355734I-2015J-1163D01*
G01X920788Y353785D02*
G02X919482Y354572I59J1575D01*
G01X920917Y353785D02*
X920788D01*
G01X922862Y352622D02*
G03X920917Y353785I-2015J-1162D01*
G01X924183Y351834D02*
G02X922862Y352622I44J1575D01*
G01X924312Y351834D02*
X924183D01*
G01X926242Y350672D02*
G03X924312Y351834I-2015J-1163D01*
G01X927548Y349885D02*
G02X926242Y350672I59J1575D01*
G01X927677Y349885D02*
X927548D01*
G01X929622Y348722D02*
G03X927677Y349885I-2015J-1162D01*
G01X930943Y347934D02*
G02X929622Y348722I44J1575D01*
G01X931072Y347934D02*
X930943D01*
G01X933002Y346772D02*
G03X931072Y347934I-2015J-1163D01*
G01X934308Y345985D02*
G02X933002Y346772I59J1575D01*
G01X934437Y345985D02*
X934308D01*
G01X936382Y344822D02*
G03X934437Y345985I-2015J-1162D01*
G01X937703Y344034D02*
G02X936382Y344822I44J1575D01*
G01X937832Y344034D02*
X937703D01*
G01X939762Y342872D02*
G03X937832Y344034I-2015J-1163D01*
G01X941068Y342085D02*
G02X939762Y342872I59J1575D01*
G01X941810Y342085D02*
X941068D01*
G01X942405Y342016D02*
X941810Y342085D01*
G01X944507Y341709D02*
X942405Y342016D01*
G01X940108Y399574D02*
Y405894D01*
G01X939766Y399054D02*
X940108Y399574D01*
G01X939743Y399013D02*
X939766Y399054D01*
G01X939762Y397472D02*
G02X939743Y399013I1365J787D01*
G01X939762Y395146D02*
G03Y397472I-2015J1163D01*
G01Y393572D02*
G02Y395146I1365J787D01*
G01X939787Y393530D02*
X939762Y393572D01*
G01Y391247D02*
G03X939787Y393530I-2015J1164D01*
G01X939743Y391213D02*
X939762Y391247D01*
G01X941068Y388885D02*
G02X939743Y391213I59J1575D01*
G01X941197Y388885D02*
X941068D01*
G01X943142Y387722D02*
G03X941197Y388885I-2015J-1162D01*
G01X944463Y386934D02*
G02X943142Y387722I44J1575D01*
G01X944592Y386934D02*
X944463D01*
G01X946522Y385772D02*
G03X944592Y386934I-2015J-1163D01*
G01X947828Y384985D02*
G02X946522Y385772I59J1575D01*
G01X947957Y384985D02*
X947828D01*
G01X949902Y383822D02*
G03X947957Y384985I-2015J-1162D01*
G01X951223Y383034D02*
G02X949902Y383822I44J1575D01*
G01X951352Y383034D02*
X951223D01*
G01X953282Y381872D02*
G03X951352Y383034I-2015J-1163D01*
G01X954588Y381085D02*
G02X953282Y381872I59J1575D01*
G01X954717Y381085D02*
X954588D01*
G01X956662Y379922D02*
G03X954717Y381085I-2015J-1162D01*
G01X956675Y379899D02*
X956662Y379922D01*
G01X958026Y379134D02*
G02X956675Y379899I0J1575D01*
G01X958111Y379134D02*
X958026D01*
G01X960041Y377972D02*
G03X958111Y379134I-2015J-1163D01*
G01X961347Y377185D02*
G02X960041Y377972I59J1575D01*
G01X961476Y377185D02*
X961347D01*
G01X963421Y376022D02*
G03X961476Y377185I-2015J-1162D01*
G01X963489Y375905D02*
X963421Y376022D01*
G01X964786Y372909D02*
X963489Y375905D01*
G01X947009Y399922D02*
Y407346D01*
G01X946503Y399013D02*
X947009Y399922D01*
G01X946522Y397472D02*
G02X946503Y399013I1365J787D01*
G01X946522Y395146D02*
G03Y397472I-2015J1163D01*
G01Y393572D02*
G02Y395146I1365J787D01*
G01X946547Y393530D02*
X946522Y393572D01*
G01Y391247D02*
G03X946547Y393530I-2015J1164D01*
G01X946503Y391213D02*
X946522Y391247D01*
G01X947828Y388885D02*
G02X946503Y391213I59J1575D01*
G01X947957Y388885D02*
X947828D01*
G01X949902Y387722D02*
G03X947957Y388885I-2015J-1162D01*
G01X951223Y386934D02*
G02X949902Y387722I44J1575D01*
G01X951352Y386934D02*
X951223D01*
G01X953282Y385772D02*
G03X951352Y386934I-2015J-1163D01*
G01X954588Y384985D02*
G02X953282Y385772I59J1575D01*
G01X954717Y384985D02*
X954588D01*
G01X956662Y383822D02*
G03X954717Y384985I-2015J-1162D01*
G01X956675Y383799D02*
X956662Y383822D01*
G01X958026Y383034D02*
G02X956675Y383799I0J1575D01*
G01X958111Y383034D02*
X958026D01*
G01X960041Y381872D02*
G03X958111Y383034I-2015J-1163D01*
G01X961347Y381085D02*
G02X960041Y381872I59J1575D01*
G01X961476Y381085D02*
X961347D01*
G01X963421Y379922D02*
G03X961476Y381085I-2015J-1162D01*
G01X964742Y379134D02*
G02X963421Y379922I44J1575D01*
G01X964871Y379134D02*
X964742D01*
G01X966801Y377972D02*
G03X964871Y379134I-2015J-1163D01*
G01X966867Y377859D02*
X966801Y377972D01*
G01X968166Y374860D02*
X966867Y377859D01*
G01X955604Y403003D02*
X956483Y403882D01*
G01X955604Y398351D02*
Y403003D01*
G01X957604Y396351D02*
X955604Y398351D01*
G01X957604Y393251D02*
Y396351D01*
G01X960529Y390326D02*
X957604Y393251D01*
G01X960529Y388220D02*
Y390326D01*
G01X960022Y387313D02*
X960529Y388220D01*
G01X961347Y384985D02*
G02X960022Y387313I59J1575D01*
G01X961476Y384985D02*
X961347D01*
G01X963421Y383822D02*
G03X961476Y384985I-2015J-1162D01*
G01X964742Y383034D02*
G02X963421Y383822I44J1575D01*
G01X964871Y383034D02*
X964742D01*
G01X966801Y381872D02*
G03X964871Y383034I-2015J-1163D01*
G01X968107Y381085D02*
G02X966801Y381872I59J1575D01*
G01X968236Y381085D02*
X968107D01*
G01X970181Y377597D02*
G03X968236Y381085I-2015J1163D01*
G01X971502Y375234D02*
G02X970181Y377597I44J1575D01*
G01X971631Y375234D02*
X971502D01*
G01X973561Y371746D02*
G03X971631Y375234I-2015J1163D01*
G01X919256Y366741D02*
X915256D01*
G01X922463Y363534D02*
X919256Y366741D01*
G01X924312Y363534D02*
X922463D01*
G01X926242Y362372D02*
G03X924312Y363534I-2015J-1163D01*
G01X927548Y361585D02*
G02X926242Y362372I59J1575D01*
G01X927677Y361585D02*
X927548D01*
G01X929622Y360422D02*
G03X927677Y361585I-2015J-1162D01*
G01X930943Y359634D02*
G02X929622Y360422I44J1575D01*
G01X931072Y359634D02*
X930943D01*
G01X933002Y358472D02*
G03X931072Y359634I-2015J-1163D01*
G01X934308Y357685D02*
G02X933002Y358472I59J1575D01*
G01X934437Y357685D02*
X934308D01*
G01X936382Y356522D02*
G03X934437Y357685I-2015J-1162D01*
G01X937703Y355734D02*
G02X936382Y356522I44J1575D01*
G01X937832Y355734D02*
X937703D01*
G01X939762Y354572D02*
G03X937832Y355734I-2015J-1163D01*
G01X941068Y353785D02*
G02X939762Y354572I59J1575D01*
G01X941197Y353785D02*
X941068D01*
G01X943142Y352622D02*
G03X941197Y353785I-2015J-1162D01*
G01X945872Y352622D02*
G02X943142I-1365J787D01*
G01X945938Y352738D02*
X945872Y352622D01*
G01X947887Y355360D02*
X945938Y352738D01*
G01X960804Y394851D02*
Y403447D01*
G01X963209Y392446D02*
X960804Y394851D01*
G01X963209Y388493D02*
Y392446D01*
G01X964729Y386934D02*
G02X963209Y388493I57J1576D01*
G01X964871Y386934D02*
X964729D01*
G01X966801Y385772D02*
G03X964871Y386934I-2015J-1163D01*
G01X968107Y384985D02*
G02X966801Y385772I59J1575D01*
G01X968236Y384985D02*
X968107D01*
G01X970181Y383822D02*
G03X968236Y384985I-2015J-1162D01*
G01X971546Y383034D02*
G02X970181Y383822I0J1576D01*
G01X971631Y383034D02*
X971546D01*
G01X973586Y379589D02*
G03X971631Y383034I-2040J1120D01*
G01X916377Y400093D02*
X915307D01*
G01X917793Y398677D02*
X916377Y400093D01*
G01X917800Y398666D02*
X917793Y398677D01*
G01X918832Y397097D02*
X917800Y398666D01*
G01X920796Y395934D02*
G02X918832Y397097I51J2326D01*
G01X920891Y395934D02*
X920796D01*
G01X922212Y393572D02*
G03X920891Y395934I-1365J787D01*
G01X922187Y393530D02*
X922212Y393572D01*
G01Y391247D02*
G02X922187Y393530I2015J1164D01*
G01X922212Y389673D02*
G03Y391247I-1365J787D01*
G01Y387347D02*
G02Y389673I2015J1163D01*
G01Y385773D02*
G03Y387347I-1365J787D01*
G01X924176Y382284D02*
G02X922212Y385773I51J2326D01*
G01X924286Y382284D02*
X924176D01*
G01X925592Y381497D02*
G03X924286Y382284I-1365J-788D01*
G01X927522Y380335D02*
G02X925592Y381497I85J2325D01*
G01X927651Y380335D02*
X927522D01*
G01X928972Y379547D02*
G03X927651Y380335I-1365J-787D01*
G01X930917Y378384D02*
G02X928972Y379547I70J2325D01*
G01X931046Y378384D02*
X930917D01*
G01X932352Y377597D02*
G03X931046Y378384I-1365J-788D01*
G01X934282Y376435D02*
G02X932352Y377597I85J2325D01*
G01X934411Y376435D02*
X934282D01*
G01X935732Y375647D02*
G03X934411Y376435I-1365J-787D01*
G01X937677Y374484D02*
G02X935732Y375647I70J2325D01*
G01X937806Y374484D02*
X937677D01*
G01X939112Y373697D02*
G03X937806Y374484I-1365J-788D01*
G01X941076Y372534D02*
G02X939112Y373697I51J2326D01*
G01X941171Y372534D02*
X941076D01*
G01X942492Y371746D02*
G03X941171Y372534I-1365J-787D01*
G01X944422Y370584D02*
G02X942492Y371746I85J2325D01*
G01X944578Y370584D02*
X944422D01*
G01X945872Y369797D02*
G03X944578Y370584I-1365J-787D01*
G01X947817Y368634D02*
G02X945872Y369797I70J2325D01*
G01X947958Y368634D02*
X947817D01*
G01X949252Y367847D02*
G03X947958Y368634I-1365J-787D01*
G01X951216Y366684D02*
G02X949252Y367847I51J2326D01*
G01X951326Y366684D02*
X951216D01*
G01X952632Y365897D02*
G03X951326Y366684I-1365J-788D01*
G01X954562Y364735D02*
G02X952632Y365897I85J2325D01*
G01X954647Y364735D02*
X954562D01*
G01X955998Y363970D02*
G03X954647Y364735I-1351J-810D01*
G01X956011Y363947D02*
X955998Y363970D01*
G01X957956Y362784D02*
G02X956011Y363947I70J2325D01*
G01X958085Y362784D02*
X957956D01*
G01X959391Y361997D02*
G03X958085Y362784I-1365J-788D01*
G01X960105Y361585D02*
G02X959391Y361997I0J825D01*
G01X961548Y361585D02*
X960105D01*
G01X964786Y361209D02*
X961548Y361585D01*
G01X961347Y365485D02*
G02X960559Y365720I63J1648D01*
G01X961476Y365485D02*
X961347D01*
G01X963421Y364322D02*
G03X961476Y365485I-2015J-1162D01*
G01X964742Y363534D02*
G02X963421Y364322I44J1575D01*
G01X964932Y363534D02*
X964742D01*
G01X968166Y363160D02*
X964932Y363534D01*
G01X921600Y402897D02*
X919900Y404597D01*
G01X921600Y400109D02*
Y402897D01*
G01X922212Y399047D02*
X921600Y400109D01*
G01X924157Y397884D02*
G02X922212Y399047I70J2325D01*
G01X924286Y397884D02*
X924157D01*
G01X925611Y395556D02*
G03X924286Y397884I-1384J753D01*
G01X925592Y395522D02*
X925611Y395556D01*
G01X925567Y393239D02*
G02X925592Y395522I2040J1119D01*
G01Y393197D02*
X925567Y393239D01*
G01X925592Y391623D02*
G03Y393197I-1365J787D01*
G01Y389297D02*
G02Y391623I2015J1163D01*
G01Y387723D02*
G03Y389297I-1365J787D01*
G01X927522Y384235D02*
G02X925592Y387723I85J2325D01*
G01X927651Y384235D02*
X927522D01*
G01X928972Y383447D02*
G03X927651Y384235I-1365J-787D01*
G01X930917Y382284D02*
G02X928972Y383447I70J2325D01*
G01X931046Y382284D02*
X930917D01*
G01X932352Y381497D02*
G03X931046Y382284I-1365J-788D01*
G01X934282Y380335D02*
G02X932352Y381497I85J2325D01*
G01X934411Y380335D02*
X934282D01*
G01X935732Y379547D02*
G03X934411Y380335I-1365J-787D01*
G01X937677Y378384D02*
G02X935732Y379547I70J2325D01*
G01X937806Y378384D02*
X937677D01*
G01X939112Y377597D02*
G03X937806Y378384I-1365J-788D01*
G01X941042Y376435D02*
G02X939112Y377597I85J2325D01*
G01X941171Y376435D02*
X941042D01*
G01X942492Y375647D02*
G03X941171Y376435I-1365J-787D01*
G01X944437Y374484D02*
G02X942492Y375647I70J2325D01*
G01X944566Y374484D02*
X944437D01*
G01X945872Y373697D02*
G03X944566Y374484I-1365J-788D01*
G01X947836Y372534D02*
G02X945872Y373697I51J2326D01*
G01X947931Y372534D02*
X947836D01*
G01X949252Y371746D02*
G03X947931Y372534I-1365J-787D01*
G01X951182Y370584D02*
G02X949252Y371746I85J2325D01*
G01X951338Y370584D02*
X951182D01*
G01X952632Y369797D02*
G03X951338Y370584I-1365J-787D01*
G01X954577Y368634D02*
G02X952632Y369797I70J2325D01*
G01X954695Y368634D02*
X954577D01*
G01X956011Y367847D02*
G03X954695Y368634I-1364J-787D01*
G01X956010Y367847D02*
X956011D01*
G01X956024Y367822D02*
X956010Y367847D01*
G01X958026Y366683D02*
G02X956024Y367822I-1J2328D01*
G01X958960Y366683D02*
X958026D01*
G01X960559Y365720D02*
X958960Y366683D01*
G01X917084Y400444D02*
Y401870D01*
G01X918376Y399152D02*
X917084Y400444D01*
G01X918696Y398666D02*
X918376Y399152D01*
G01X919457Y397508D02*
X918696Y398666D01*
G01X919482Y397472D02*
X919457Y397508D01*
G01X920788Y396685D02*
G02X919482Y397472I59J1575D01*
G01X920898Y396685D02*
X920788D01*
G01X922887Y393239D02*
G03X920898Y396685I-2040J1120D01*
G01X922862Y393197D02*
X922887Y393239D01*
G01X922862Y391623D02*
G02Y393197I1365J787D01*
G01Y389297D02*
G03Y391623I-2015J1163D01*
G01Y387723D02*
G02Y389297I1365J787D01*
G01Y385397D02*
G03Y387723I-2015J1163D01*
G01X924183Y383035D02*
G02X922862Y385397I44J1575D01*
G01X924278Y383035D02*
X924183D01*
G01X926242Y381872D02*
G03X924278Y383035I-2015J-1163D01*
G01X927548Y381085D02*
G02X926242Y381872I59J1575D01*
G01X927677Y381085D02*
X927548D01*
G01X929622Y379922D02*
G03X927677Y381085I-2015J-1162D01*
G01X930943Y379134D02*
G02X929622Y379922I44J1575D01*
G01X931072Y379134D02*
X930943D01*
G01X933002Y377972D02*
G03X931072Y379134I-2015J-1163D01*
G01X934308Y377185D02*
G02X933002Y377972I59J1575D01*
G01X934437Y377185D02*
X934308D01*
G01X936382Y376022D02*
G03X934437Y377185I-2015J-1162D01*
G01X937703Y375234D02*
G02X936382Y376022I44J1575D01*
G01X937832Y375234D02*
X937703D01*
G01X939762Y374072D02*
G03X937832Y375234I-2015J-1163D01*
G01X941068Y373285D02*
G02X939762Y374072I59J1575D01*
G01X941178Y373285D02*
X941068D01*
G01X943142Y372122D02*
G03X941178Y373285I-2015J-1163D01*
G01X944436Y371335D02*
G02X943142Y372122I71J1574D01*
G01X944577Y371335D02*
X944436D01*
G01X946522Y370172D02*
G03X944577Y371335I-2015J-1162D01*
G01X947816Y369385D02*
G02X946522Y370172I71J1574D01*
G01X947972Y369385D02*
X947816D01*
G01X949902Y368223D02*
G03X947972Y369385I-2015J-1163D01*
G01X951223Y367435D02*
G02X949902Y368223I44J1575D01*
G01X951318Y367435D02*
X951223D01*
G01X953282Y366272D02*
G03X951318Y367435I-2015J-1163D01*
G01X954588Y365485D02*
G02X953282Y366272I59J1575D01*
G01X954717Y365485D02*
X954588D01*
G01X956662Y364322D02*
G03X954717Y365485I-2015J-1162D01*
G01X956675Y364299D02*
X956662Y364322D01*
G01X958026Y363534D02*
G02X956675Y364299I0J1575D01*
G01X958172Y363534D02*
X958026D01*
G01X958200Y363531D02*
X958172Y363534D01*
G01X961406Y363160D02*
X958200Y363531D01*
G01X912388Y360709D02*
X910666Y362431D01*
G01X915372Y360709D02*
X912388D01*
G01X916447Y359634D02*
X915372Y360709D01*
G01X917552Y359634D02*
X916447D01*
G01X919482Y358472D02*
G03X917552Y359634I-2015J-1163D01*
G01X920627Y357699D02*
G02X919482Y358472I215J1554D01*
G01X921128Y357669D02*
G03X920627Y357699I-493J-4042D01*
G01X922862Y356522D02*
G03X921128Y357669I-2016J-1163D01*
G01X924183Y355734D02*
G02X922862Y356522I44J1575D01*
G01X924312Y355734D02*
X924183D01*
G01X926242Y354572D02*
G03X924312Y355734I-2015J-1163D01*
G01X927548Y353785D02*
G02X926242Y354572I59J1575D01*
G01X927677Y353785D02*
X927548D01*
G01X929622Y352622D02*
G03X927677Y353785I-2015J-1162D01*
G01X930943Y351834D02*
G02X929622Y352622I44J1575D01*
G01X931072Y351834D02*
X930943D01*
G01X933002Y350672D02*
G03X931072Y351834I-2015J-1163D01*
G01X934308Y349885D02*
G02X933002Y350672I59J1575D01*
G01X934437Y349885D02*
X934308D01*
G01X936382Y348722D02*
G03X934437Y349885I-2015J-1162D01*
G01X937703Y347934D02*
G02X936382Y348722I44J1575D01*
G01X937832Y347934D02*
X937703D01*
G01X939762Y346772D02*
G03X937832Y347934I-2015J-1163D01*
G01X941068Y345985D02*
G02X939762Y346772I59J1575D01*
G01X941269Y345985D02*
X941068D01*
G01X944507Y345609D02*
X941269Y345985D01*
G01X914131Y341335D02*
X913050D01*
G01X953350Y356264D02*
X954647Y359260D01*
G01X953282Y356147D02*
X953350Y356264D01*
G01X951337Y354984D02*
G03X953282Y356147I-70J2325D01*
G01X951208Y354984D02*
X951337D01*
G01X949902Y354197D02*
G02X951208Y354984I1365J-788D01*
G01X947972Y353035D02*
G03X949902Y354197I-85J2325D01*
G01X947843Y353035D02*
X947972D01*
G01X946522Y352247D02*
G02X947843Y353035I1365J-787D01*
G01X944577Y351084D02*
G03X946522Y352247I-70J2325D01*
G01X944437Y351084D02*
X944577D01*
G01X942492Y352247D02*
G03X944437Y351084I2015J1162D01*
G01X941171Y353035D02*
G02X942492Y352247I-44J-1575D01*
G01X941042Y353035D02*
X941171D01*
G01X939112Y354197D02*
G03X941042Y353035I2015J1163D01*
G01X937806Y354984D02*
G02X939112Y354197I-59J-1575D01*
G01X937677Y354984D02*
X937806D01*
G01X935732Y356147D02*
G03X937677Y354984I2015J1162D01*
G01X934411Y356935D02*
G02X935732Y356147I-44J-1575D01*
G01X934282Y356935D02*
X934411D01*
G01X932352Y358097D02*
G03X934282Y356935I2015J1163D01*
G01X931046Y358884D02*
G02X932352Y358097I-59J-1575D01*
G01X930917Y358884D02*
X931046D01*
G01X928972Y360047D02*
G03X930917Y358884I2015J1162D01*
G01X927651Y360835D02*
G02X928972Y360047I-44J-1575D01*
G01X927522Y360835D02*
X927651D01*
G01X925592Y361997D02*
G03X927522Y360835I2015J1163D01*
G01X924286Y362784D02*
G02X925592Y361997I-59J-1575D01*
G01X922152Y362784D02*
X924286D01*
G01X921933Y363003D02*
X922152Y362784D01*
G01X921933Y363005D02*
Y363003D01*
G01X921934Y363005D02*
X921933D01*
G01X918946Y365993D02*
X921934Y363005D01*
G01X914946Y365993D02*
X918946D01*
G01X954856Y403009D02*
X953983Y403882D01*
G01X954856Y398041D02*
Y403009D01*
G01X956856Y396041D02*
X954856Y398041D01*
G01X956856Y392941D02*
Y396041D01*
G01X959781Y390016D02*
X956856Y392941D01*
G01X959781Y388417D02*
Y390016D01*
G01X959366Y387680D02*
X959781Y388417D01*
G01X961321Y384235D02*
G02X959366Y387680I85J2325D01*
G01X961450Y384235D02*
X961321D01*
G01X962771Y383447D02*
G03X961450Y384235I-1365J-787D01*
G01X964716Y382284D02*
G02X962771Y383447I70J2325D01*
G01X964845Y382284D02*
X964716D01*
G01X966151Y381497D02*
G03X964845Y382284I-1365J-788D01*
G01X968081Y380335D02*
G02X966151Y381497I85J2325D01*
G01X968210Y380335D02*
X968081D01*
G01X969531Y377972D02*
G03X968210Y380335I-1365J788D01*
G01X971476Y374484D02*
G02X969531Y377972I70J2325D01*
G01X971605Y374484D02*
X971476D01*
G01X972930Y372156D02*
G03X971605Y374484I-1384J753D01*
G01X946261Y400118D02*
Y407036D01*
G01X945847Y399380D02*
X946261Y400118D01*
G01X945872Y397097D02*
G02X945847Y399380I2015J1164D01*
G01X945891Y395556D02*
G03X945872Y397097I-1384J754D01*
G01Y395522D02*
X945891Y395556D01*
G01X945847Y393239D02*
G02X945872Y395522I2040J1119D01*
G01Y393197D02*
X945847Y393239D01*
G01X945872Y391623D02*
G03Y393197I-1365J787D01*
G01X947802Y388135D02*
G02X945872Y391623I85J2325D01*
G01X947931Y388135D02*
X947802D01*
G01X949252Y387347D02*
G03X947931Y388135I-1365J-787D01*
G01X951197Y386184D02*
G02X949252Y387347I70J2325D01*
G01X951326Y386184D02*
X951197D01*
G01X952632Y385397D02*
G03X951326Y386184I-1365J-788D01*
G01X954562Y384235D02*
G02X952632Y385397I85J2325D01*
G01X954647Y384235D02*
X954562D01*
G01X955998Y383470D02*
G03X954647Y384235I-1351J-810D01*
G01X956011Y383447D02*
X955998Y383470D01*
G01X957956Y382284D02*
G02X956011Y383447I70J2325D01*
G01X958085Y382284D02*
X957956D01*
G01X959391Y381497D02*
G03X958085Y382284I-1365J-788D01*
G01X961321Y380335D02*
G02X959391Y381497I85J2325D01*
G01X961450Y380335D02*
X961321D01*
G01X962771Y379547D02*
G03X961450Y380335I-1365J-787D01*
G01X964716Y378384D02*
G02X962771Y379547I70J2325D01*
G01X964845Y378384D02*
X964716D01*
G01X966170Y376056D02*
G03X964845Y378384I-1384J753D01*
G01X966151Y376022D02*
X966170Y376056D01*
G01X966151Y375198D02*
G02Y376022I714J412D01*
G01X966801Y374072D02*
X966151Y375198D01*
G01X968107Y373285D02*
G02X966801Y374072I59J1575D01*
G01X968302Y373285D02*
X968107D01*
G01X971546Y372909D02*
X968302Y373285D01*
G01X960056Y394541D02*
Y403653D01*
G01X962459Y392138D02*
X960056Y394541D01*
G01X962459Y388489D02*
Y392138D01*
G01X964716Y386184D02*
G02X962459Y388489I70J2326D01*
G01X964845Y386184D02*
X964716D01*
G01X966151Y385397D02*
G03X964845Y386184I-1365J-788D01*
G01X968081Y384235D02*
G02X966151Y385397I85J2325D01*
G01X968210Y384235D02*
X968081D01*
G01X969531Y383447D02*
G03X968210Y384235I-1365J-787D01*
G01X971546Y382284D02*
G02X969531Y383447I0J2327D01*
G01X971605Y382284D02*
X971546D01*
G01X972930Y379956D02*
G03X971605Y382284I-1384J753D01*
G01X920480Y405075D02*
Y406365D01*
G01X922348Y403207D02*
X920480Y405075D01*
G01X934153Y410791D02*
X932706D01*
G01X939360Y405584D02*
X934153Y410791D01*
G01X934724Y411278D02*
Y412309D01*
G01X940108Y405894D02*
X934724Y411278D01*
G01X938279Y416076D02*
Y416664D01*
G01X947009Y407346D02*
X938279Y416076D01*
G01X960804Y403447D02*
X961783Y404426D01*
G01X919900Y404597D02*
X918712D01*
G01X938401Y414896D02*
X936511D01*
G01X946261Y407036D02*
X938401Y414896D01*
G01X960056Y403653D02*
X959283Y404426D01*
G01X1030926Y196764D02*
Y190630D01*
G01X1023872Y203818D02*
X1030926Y196764D01*
G01X1023872Y206969D02*
Y203818D01*
G01X1023610Y207948D02*
G02X1023872Y206969I-1698J-979D01*
G01X1023545Y208060D02*
X1023610Y207948D01*
G01X1022245Y211061D02*
X1023545Y208060D01*
G01X1022245Y211060D02*
Y211061D01*
G01X987081Y215747D02*
G03X987106Y218030I-2015J1164D01*
G01X986911Y215452D02*
X987081Y215747D01*
G01X983810Y212351D02*
X986911Y215452D01*
G01X983810Y206863D02*
Y212351D01*
G01X978981Y202034D02*
X983810Y206863D01*
G01X978981Y197747D02*
Y202034D01*
G01X979594Y197134D02*
X978981Y197747D01*
G01X979594Y196153D02*
Y197134D01*
G01X980326Y195421D02*
X979594Y196153D01*
G01X1030579Y206309D02*
X1034200Y202688D01*
G01X1030579Y209121D02*
Y206309D01*
G01X1027300Y212400D02*
X1030579Y209121D01*
G01X1027300Y238634D02*
Y212400D01*
G01X1015687Y200413D02*
Y198554D01*
G01X1013900Y202200D02*
X1015687Y200413D01*
G01X1013900Y203668D02*
Y202200D01*
G01X1014500Y204703D02*
X1013900Y203668D01*
G01X1014500Y213554D02*
Y204703D01*
G01X1014120Y214174D02*
X1014500Y213554D01*
G01X1014120Y215748D02*
G03Y214174I1365J-787D01*
G01Y218074D02*
G02Y215748I-2015J-1163D01*
G01X990596Y201300D02*
X991826Y205210D01*
G01X990596Y200519D02*
Y201300D01*
G01X1002600Y217100D02*
G03X1003279Y217985I-3014J3015D01*
G01X1001756Y216561D02*
G03X1002600Y217100I-800J2183D01*
G01X1001423Y216439D02*
X1001756Y216561D01*
G01X1000601Y214173D02*
G02X1001423Y216439I1364J787D01*
G01X1000636Y211907D02*
G03X1000601Y214173I-2050J1102D01*
G01Y211847D02*
X1000636Y211907D01*
G01X1000601Y210273D02*
G02Y211847I1364J787D01*
G01X1001400Y207289D02*
G03X1000601Y210273I-5970J0D01*
G01X1001400Y201376D02*
Y207289D01*
G01X1001796Y200980D02*
X1001400Y201376D01*
G01X1001796Y199802D02*
Y200980D01*
G01X993588Y207347D02*
X991826Y209109D01*
G01X993588Y201788D02*
Y207347D01*
G01X992596Y200796D02*
X993588Y201788D01*
G01X992596Y199608D02*
Y200796D01*
G01X1004046Y210010D02*
X1005345Y213009D01*
G01X1003980Y209897D02*
X1004046Y210010D01*
G01X1003700Y208863D02*
G02X1003980Y209897I2051J0D01*
G01X1003700Y203500D02*
Y208863D01*
G01X1005796Y201404D02*
X1003700Y203500D01*
G01X1005796Y200081D02*
Y201404D01*
G01X986406Y217739D02*
G02X986431Y220022I2040J1119D01*
G01Y217697D02*
X986406Y217739D01*
G01X986450Y217663D02*
X986431Y217697D01*
G01Y216122D02*
G03X986450Y217663I-1365J787D01*
G01X986311Y215914D02*
X986431Y216122D01*
G01X983060Y212663D02*
X986311Y215914D01*
G01X983060Y207175D02*
Y212663D01*
G01X978231Y202346D02*
X983060Y207175D01*
G01X978231Y197436D02*
Y202346D01*
G01X978846Y196821D02*
X978231Y197436D01*
G01X978846Y196301D02*
Y196821D01*
G01X977976Y195431D02*
X978846Y196301D01*
G01X1009426Y201581D02*
Y199064D01*
G01X1008676Y204830D02*
X1009426Y201581D01*
G01X1008676Y208128D02*
Y204830D01*
G01X1007360Y210272D02*
X1008676Y208128D01*
G01X1007341Y211813D02*
G03X1007360Y210272I1384J-754D01*
G01Y211847D02*
X1007341Y211813D01*
G01X1007385Y211889D02*
X1007360Y211847D01*
G01Y214172D02*
G02X1007385Y211889I-2015J-1164D01*
G01X1007149Y214979D02*
G03X1007360Y214172I1576J-19D01*
G01X1007149Y231830D02*
Y214979D01*
G01X1017726Y200073D02*
Y198724D01*
G01X1017100Y200699D02*
X1017726Y200073D01*
G01X1017100Y211100D02*
Y200699D01*
G01X1016538Y211662D02*
X1017100Y211100D01*
G01X1016538Y213000D02*
Y211662D01*
G01X1016850Y214174D02*
G03X1016538Y213000I2015J-1164D01*
G01X1016850Y215748D02*
G02Y214174I-1365J-787D01*
G01Y218074D02*
G03Y215748I2015J-1163D01*
G01X1003796Y201286D02*
Y200166D01*
G01X1002700Y202382D02*
X1003796Y201286D01*
G01X1002700Y208100D02*
Y202382D01*
G01X1003239Y210114D02*
G03X1002700Y208100I3494J-2014D01*
G01X1003330Y210272D02*
X1003239Y210114D01*
G01X1003349Y211813D02*
G02X1003330Y210272I-1384J-754D01*
G01Y211847D02*
X1003349Y211813D01*
G01X1003305Y211889D02*
X1003330Y211847D01*
G01Y214172D02*
G03X1003305Y211889I2015J-1164D01*
G01X1003700Y214542D02*
X1003330Y214172D01*
G01X1003700Y216653D02*
Y214542D01*
G01X1003980Y217698D02*
G03X1003700Y216653I1811J-1045D01*
G01X1003980Y220024D02*
G02Y217698I-2015J-1163D01*
G01X1029824Y217113D02*
X1029005Y218860D01*
G01X1032237Y214700D02*
X1029824Y217113D01*
G01X1033000Y214700D02*
X1032237D01*
G01X1034100Y213600D02*
X1033000Y214700D01*
G01X994596Y200397D02*
Y199498D01*
G01X996826Y202627D02*
X994596Y200397D01*
G01X996826Y205539D02*
Y202627D01*
G01X995206Y207159D02*
X996826Y205539D01*
G01X998586Y202196D02*
Y205210D01*
G01X996596Y200206D02*
X998586Y202196D01*
G01X996596Y199062D02*
Y200206D01*
G01X1023926Y212482D02*
Y238698D01*
G01X1025408Y211000D02*
X1023926Y212482D01*
G01X1025960Y211000D02*
X1025408D01*
G01X1027300Y209660D02*
X1025960Y211000D01*
G01X1027300Y206099D02*
Y209660D01*
G01X1027500Y205899D02*
X1027300Y206099D01*
G01X1027900Y205500D02*
X1027500Y205899D01*
G01X1030574Y202825D02*
X1027900Y205500D01*
G01X1030574Y200090D02*
Y202825D01*
G01X1034126Y196538D02*
X1030574Y200090D01*
G01X1000014Y216235D02*
X1001965Y218860D01*
G01X999915Y216062D02*
X1000014Y216235D01*
G01X999950Y213796D02*
G02X999915Y216062I2015J1164D01*
G01X999950Y212222D02*
G03Y213796I-1364J787D01*
G01X999915Y212162D02*
X999950Y212222D01*
G01Y209896D02*
G02X999915Y212162I2015J1164D01*
G01X1000200Y208964D02*
G03X999950Y209896I-1864J0D01*
G01X1000200Y200500D02*
Y208964D01*
G01X999796Y200096D02*
X1000200Y200500D01*
G01X999796Y199305D02*
Y200096D01*
G01X1019610Y211291D02*
X1018865Y213009D01*
G01X1019610Y202197D02*
Y211291D01*
G01X1022104Y199704D02*
X1019610Y202197D01*
G01X1023726Y198081D02*
X1022104Y199704D01*
G01X1023726Y197381D02*
Y198081D01*
G01X1020625Y213280D02*
X1018865Y216909D01*
G01X1020625Y203081D02*
Y213280D01*
G01X1025726Y197980D02*
X1020625Y203081D01*
G01X1025726Y196930D02*
Y197980D01*
G01X1036191Y216909D02*
X1032385D01*
G01X1011426Y200033D02*
Y198627D01*
G01X1010435Y204830D02*
X1011426Y200033D01*
G01X1010435Y234480D02*
Y204830D01*
G01X1013476Y200824D02*
Y198651D01*
G01X1013100Y201200D02*
X1013476Y200824D01*
G01X1013100Y203785D02*
Y201200D01*
G01X1013681Y204788D02*
X1013100Y203785D01*
G01X1013681Y212995D02*
Y204788D01*
G01X1013470Y213798D02*
G02X1013681Y212995I-1365J-788D01*
G01X1013470Y216124D02*
G03Y213798I2015J-1163D01*
G01Y217698D02*
G02Y216124I-1365J-787D01*
G01Y220024D02*
G03Y217698I2015J-1163D01*
G01X990461Y217697D02*
G03X990486Y219980I-2015J1164D01*
G01X990442Y216156D02*
G02X990461Y217697I1384J754D01*
G01Y216122D02*
X990442Y216156D01*
G01X990486Y216080D02*
X990461Y216122D01*
G01X988531Y212635D02*
G03X990486Y216080I-85J2325D01*
G01X987787Y212635D02*
X988531D01*
G01X986836Y211684D02*
X987787Y212635D01*
G01X986836Y204241D02*
Y211684D01*
G01X982296Y199701D02*
X986836Y204241D01*
G01X982296Y198461D02*
Y199701D01*
G01X984406Y196351D02*
X982296Y198461D01*
G01X984406Y195511D02*
Y196351D01*
G01X985326Y194591D02*
X984406Y195511D01*
G01X1019726Y199974D02*
Y198554D01*
G01X1018000Y201700D02*
X1019726Y199974D01*
G01X1018000Y211501D02*
Y201700D01*
G01X1017290Y212211D02*
X1018000Y211501D01*
G01X1017290Y212974D02*
Y212211D01*
G01X1017500Y213798D02*
G03X1017290Y212974I1365J-787D01*
G01X1017500Y216124D02*
G02Y213798I-2015J-1163D01*
G01Y217698D02*
G03Y216124I1365J-787D01*
G01Y220024D02*
G02Y217698I-2015J-1163D01*
G01X974224Y216128D02*
X976711Y218615D01*
G01X974224Y213171D02*
Y216128D01*
G01X973066Y212013D02*
X974224Y213171D01*
G01X973066Y210393D02*
Y212013D01*
G01X973474Y216439D02*
X975961Y218926D01*
G01X973474Y213483D02*
Y216439D01*
G01X972316Y212325D02*
X973474Y213483D01*
G01X972316Y210701D02*
Y212325D01*
G01X1028926Y192034D02*
Y191223D01*
G01X1029526Y192634D02*
X1028926Y192034D01*
G01X1029526Y196157D02*
Y192634D01*
G01X1024042Y201642D02*
X1029526Y196157D01*
G01X1022245Y203438D02*
X1024042Y201642D01*
G01X1022245Y207159D02*
Y203438D01*
G01X989786Y215789D02*
G02X989811Y218072I2040J1119D01*
G01Y215747D02*
X989786Y215789D01*
G01X989830Y215713D02*
X989811Y215747D01*
G01X988505Y213385D02*
G03X989830Y215713I-59J1575D01*
G01X987465Y213385D02*
X988505D01*
G01X986086Y212006D02*
X987465Y213385D01*
G01X986086Y204551D02*
Y212006D01*
G01X981546Y200011D02*
X986086Y204551D01*
G01X981546Y198151D02*
Y200011D01*
G01X983656Y196041D02*
X981546Y198151D01*
G01X983656Y195421D02*
Y196041D01*
G01X982826Y194591D02*
X983656Y195421D01*
G01X986431Y260597D02*
X985066Y263709D01*
G01X986618Y259540D02*
G03X986431Y260597I-1552J270D01*
G01X987081Y257073D02*
G02X986618Y259540I3278J1892D01*
G01X987081Y254747D02*
G03Y257073I-2015J1163D01*
G01Y253173D02*
G02Y254747I1365J787D01*
G01Y250847D02*
G03Y253173I-2015J1163D01*
G01Y249272D02*
G02Y250847I1364J787D01*
G01X987106Y246989D02*
G03X987081Y249272I-2040J1119D01*
G01Y246947D02*
X987106Y246989D01*
G01X987062Y246913D02*
X987081Y246947D01*
G01Y245372D02*
G02X987062Y246913I1365J787D01*
G01X987106Y243089D02*
G03X987081Y245372I-2040J1119D01*
G01Y243047D02*
X987106Y243089D01*
G01X987062Y243013D02*
X987081Y243047D01*
G01Y241472D02*
G02X987062Y243013I1365J787D01*
G01X987106Y239189D02*
G03X987081Y241472I-2040J1119D01*
G01Y239147D02*
X987106Y239189D01*
G01X987062Y239113D02*
X987081Y239147D01*
G01Y237572D02*
G02X987062Y239113I1365J787D01*
G01X987106Y235289D02*
G03X987081Y237572I-2040J1119D01*
G01Y235247D02*
X987106Y235289D01*
G01X987062Y235213D02*
X987081Y235247D01*
G01Y233672D02*
G02X987062Y235213I1365J787D01*
G01X987081Y231346D02*
G03Y233672I-2015J1163D01*
G01Y229772D02*
G02Y231346I1365J787D01*
G01X987106Y229730D02*
X987081Y229772D01*
G01Y227447D02*
G03X987106Y229730I-2015J1164D01*
G01X987062Y227413D02*
X987081Y227447D01*
G01Y225872D02*
G02X987062Y227413I1365J787D01*
G01X987106Y223589D02*
G03X987081Y225872I-2040J1119D01*
G01Y223547D02*
X987106Y223589D01*
G01X987062Y223513D02*
X987081Y223547D01*
G01Y221972D02*
G02X987062Y223513I1365J787D01*
G01X987106Y219689D02*
G03X987081Y221972I-2040J1119D01*
G01Y219647D02*
X987106Y219689D01*
G01X987062Y218106D02*
G02X987081Y219647I1384J754D01*
G01Y218072D02*
X987062Y218106D01*
G01X987106Y218030D02*
X987081Y218072D01*
G01X1025625Y240309D02*
X1027300Y238634D01*
G01X1014120Y219648D02*
G03Y218074I1365J-787D01*
G01Y221974D02*
G02Y219648I-2015J-1163D01*
G01Y223548D02*
G03Y221974I1365J-787D01*
G01Y225874D02*
G02Y223548I-2015J-1163D01*
G01Y227448D02*
G03Y225874I1365J-787D01*
G01Y229774D02*
G02Y227448I-2015J-1163D01*
G01Y231348D02*
G03Y229774I1365J-787D01*
G01Y233674D02*
G02Y231348I-2015J-1163D01*
G01Y235248D02*
G03Y233674I1365J-787D01*
G01Y237574D02*
G02Y235248I-2015J-1163D01*
G01X1013910Y238405D02*
G03X1014120Y237574I1575J-44D01*
G01X1013910Y241135D02*
Y238405D01*
G01X1012411Y242634D02*
X1013910Y241135D01*
G01X1012061Y242634D02*
X1012411D01*
G01X1010529Y244200D02*
G03X1012061Y242634I1576J9D01*
G01X1010529Y246671D02*
Y244200D01*
G01X1009400Y247800D02*
X1010529Y246671D01*
G01X1007600Y247800D02*
X1009400D01*
G01X1005960Y246160D02*
X1007600Y247800D01*
G01X1001965Y246160D02*
X1005960D01*
G01X1000732Y221397D02*
X998586Y224709D01*
G01X1002537Y220329D02*
X1000732Y221397D01*
G01X1003330Y218074D02*
G03X1002537Y220329I-1365J787D01*
G01X1003279Y217985D02*
X1003330Y218074D01*
G01X976223Y258764D02*
X974926Y261760D01*
G01X976310Y258613D02*
X976223Y258764D01*
G01X976291Y257072D02*
G03X976310Y258613I-1365J787D01*
G01X976034Y256626D02*
X976291Y257072D01*
G01X974360Y255431D02*
X976034Y256626D01*
G01X973561Y253172D02*
G02X974360Y255431I1365J788D01*
G01X973586Y250889D02*
G03X973561Y253172I-2040J1119D01*
G01Y250847D02*
X973586Y250889D01*
G01X973542Y250813D02*
X973561Y250847D01*
G01Y249272D02*
G02X973542Y250813I1365J787D01*
G01X973586Y246989D02*
G03X973561Y249272I-2040J1119D01*
G01Y246947D02*
X973586Y246989D01*
G01X973542Y246913D02*
X973561Y246947D01*
G01Y245372D02*
G02X973542Y246913I1365J787D01*
G01X973586Y243089D02*
G03X973561Y245372I-2040J1119D01*
G01Y243047D02*
X973586Y243089D01*
G01X973542Y243013D02*
X973561Y243047D01*
G01Y241472D02*
G02X973542Y243013I1365J787D01*
G01X973586Y239189D02*
G03X973561Y241472I-2040J1119D01*
G01Y239147D02*
X973586Y239189D01*
G01X973542Y239113D02*
X973561Y239147D01*
G01Y237572D02*
G02X973542Y239113I1365J787D01*
G01X973586Y235289D02*
G03X973561Y237572I-2040J1119D01*
G01Y235247D02*
X973586Y235289D01*
G01X973542Y235213D02*
X973561Y235247D01*
G01Y233672D02*
G02X973542Y235213I1365J787D01*
G01X973561Y231346D02*
G03Y233672I-2015J1163D01*
G01Y229772D02*
G02Y231346I1365J787D01*
G01X973586Y229730D02*
X973561Y229772D01*
G01Y227447D02*
G03X973586Y229730I-2015J1164D01*
G01X973542Y227413D02*
X973561Y227447D01*
G01Y225872D02*
G02X973542Y227413I1365J787D01*
G01X973586Y223589D02*
G03X973561Y225872I-2040J1119D01*
G01Y223547D02*
X973586Y223589D01*
G01X973542Y223513D02*
X973561Y223547D01*
G01Y221972D02*
G02X973542Y223513I1365J787D01*
G01X973561Y219646D02*
G03Y221972I-2015J1163D01*
G01X973147Y218929D02*
X973561Y219646D01*
G01X986300Y253061D02*
X985066Y255909D01*
G01X986431Y252797D02*
G02X986300Y253061I2014J1164D01*
G01X986431Y251223D02*
G03Y252797I-1365J787D01*
G01Y248897D02*
G02Y251223I2017J1163D01*
G01X986450Y247356D02*
G03X986431Y248897I-1384J754D01*
G01Y247322D02*
X986450Y247356D01*
G01X986406Y247280D02*
X986431Y247322D01*
G01Y244997D02*
G02X986406Y247280I2015J1164D01*
G01X986450Y243456D02*
G03X986431Y244997I-1384J754D01*
G01Y243422D02*
X986450Y243456D01*
G01X986406Y243380D02*
X986431Y243422D01*
G01Y241097D02*
G02X986406Y243380I2015J1164D01*
G01X986450Y239556D02*
G03X986431Y241097I-1384J754D01*
G01Y239522D02*
X986450Y239556D01*
G01X986406Y239480D02*
X986431Y239522D01*
G01Y237197D02*
G02X986406Y239480I2015J1164D01*
G01X986450Y235656D02*
G03X986431Y237197I-1384J754D01*
G01Y235622D02*
X986450Y235656D01*
G01X986406Y235580D02*
X986431Y235622D01*
G01Y233297D02*
G02X986406Y235580I2015J1164D01*
G01X986450Y231756D02*
G03X986431Y233297I-1384J754D01*
G01Y231722D02*
X986450Y231756D01*
G01X986406Y229439D02*
G02X986431Y231722I2040J1119D01*
G01Y229397D02*
X986406Y229439D01*
G01X986431Y227823D02*
G03Y229397I-1365J787D01*
G01Y225497D02*
G02Y227823I2015J1163D01*
G01X986450Y223956D02*
G03X986431Y225497I-1384J754D01*
G01Y223922D02*
X986450Y223956D01*
G01X986406Y223880D02*
X986431Y223922D01*
G01Y221597D02*
G02X986406Y223880I2015J1164D01*
G01X986450Y220056D02*
G03X986431Y221597I-1384J754D01*
G01Y220022D02*
X986450Y220056D01*
G01X1006891Y233215D02*
X1007149Y231830D01*
G01X1006017Y234089D02*
X1006891Y233215D01*
G01X1005541Y234393D02*
X1006017Y234089D01*
G01X997794Y238947D02*
X1005541Y234393D01*
G01X997221Y239522D02*
G03X997794Y238947I1365J787D01*
G01X997155Y239638D02*
X997221Y239522D01*
G01X995206Y242260D02*
X997155Y239638D01*
G01X1016850Y219648D02*
G02Y218074I-1365J-787D01*
G01Y221974D02*
G03Y219648I2015J-1163D01*
G01Y223548D02*
G02Y221974I-1365J-787D01*
G01Y225874D02*
G03Y223548I2015J-1163D01*
G01Y227448D02*
G02Y225874I-1365J-787D01*
G01Y229774D02*
G03Y227448I2015J-1163D01*
G01Y231348D02*
G02Y229774I-1365J-787D01*
G01Y233674D02*
G03Y231348I2015J-1163D01*
G01Y235248D02*
G02Y233674I-1365J-787D01*
G01Y237574D02*
G03Y235248I2015J-1163D01*
G01Y239148D02*
G02Y237574I-1365J-787D01*
G01X1016785Y239260D02*
X1016850Y239148D01*
G01X1015485Y242260D02*
X1016785Y239260D01*
G01X1003915Y220137D02*
X1003980Y220024D01*
G01X1001965Y222760D02*
X1003915Y220137D01*
G01X1023926Y238698D02*
X1022245Y242260D01*
G01X1010045Y235485D02*
X1010435Y234480D01*
G01X1008946Y236419D02*
X1010045Y235485D01*
G01X1008145Y236851D02*
X1008946Y236419D01*
G01X997788Y242850D02*
X1008145Y236851D01*
G01X997221Y243422D02*
G03X997788Y242850I1365J786D01*
G01X997155Y243538D02*
X997221Y243422D01*
G01X995206Y246160D02*
X997155Y243538D01*
G01X1013470Y221598D02*
G02Y220024I-1365J-787D01*
G01Y223924D02*
G03Y221598I2015J-1163D01*
G01Y225498D02*
G02Y223924I-1365J-787D01*
G01Y227824D02*
G03Y225498I2015J-1163D01*
G01Y229398D02*
G02Y227824I-1365J-787D01*
G01Y231724D02*
G03Y229398I2015J-1163D01*
G01Y233298D02*
G02Y231724I-1365J-787D01*
G01Y235624D02*
G03Y233298I2015J-1163D01*
G01X1012149Y237986D02*
G02X1013470Y235624I-44J-1575D01*
G01X1012147Y237984D02*
X1012149Y237986D01*
G01X1012035Y237984D02*
X1012147D01*
G01X1010090Y241472D02*
G03X1012035Y237984I2015J-1163D01*
G01X1010109Y243013D02*
G02X1010090Y241472I-1384J-754D01*
G01X1010022Y243164D02*
X1010109Y243013D01*
G01X1008725Y246160D02*
X1010022Y243164D01*
G01X990395Y259138D02*
X988446Y261760D01*
G01X990461Y259022D02*
X990395Y259138D01*
G01X990486Y258980D02*
X990461Y259022D01*
G01Y256697D02*
G03X990486Y258980I-2015J1164D01*
G01X990442Y255156D02*
G02X990461Y256697I1384J754D01*
G01Y255122D02*
X990442Y255156D01*
G01X990486Y255080D02*
X990461Y255122D01*
G01Y252797D02*
G03X990486Y255080I-2015J1164D01*
G01X990442Y251256D02*
G02X990461Y252797I1384J754D01*
G01Y251222D02*
X990442Y251256D01*
G01X990486Y251180D02*
X990461Y251222D01*
G01Y248897D02*
G03X990486Y251180I-2015J1164D01*
G01X990442Y247356D02*
G02X990461Y248897I1384J754D01*
G01Y247322D02*
X990442Y247356D01*
G01X990486Y247280D02*
X990461Y247322D01*
G01Y244997D02*
G03X990486Y247280I-2015J1164D01*
G01X990442Y243456D02*
G02X990461Y244997I1384J754D01*
G01Y243422D02*
X990442Y243456D01*
G01X990486Y243380D02*
X990461Y243422D01*
G01Y241097D02*
G03X990486Y243380I-2015J1164D01*
G01X990442Y239556D02*
G02X990461Y241097I1384J754D01*
G01Y239522D02*
X990442Y239556D01*
G01X990486Y239480D02*
X990461Y239522D01*
G01Y237197D02*
G03X990486Y239480I-2015J1164D01*
G01X990442Y235656D02*
G02X990461Y237197I1384J754D01*
G01Y235622D02*
X990442Y235656D01*
G01X990486Y235580D02*
X990461Y235622D01*
G01Y233297D02*
G03X990486Y235580I-2015J1164D01*
G01X990442Y231756D02*
G02X990461Y233297I1384J754D01*
G01Y231722D02*
X990442Y231756D01*
G01X990486Y229439D02*
G03X990461Y231722I-2040J1119D01*
G01Y229397D02*
X990486Y229439D01*
G01X990461Y227823D02*
G02Y229397I1365J787D01*
G01Y225497D02*
G03Y227823I-2015J1163D01*
G01X990442Y223956D02*
G02X990461Y225497I1384J754D01*
G01Y223922D02*
X990442Y223956D01*
G01X990486Y223880D02*
X990461Y223922D01*
G01Y221597D02*
G03X990486Y223880I-2015J1164D01*
G01X990442Y220056D02*
G02X990461Y221597I1384J754D01*
G01Y220022D02*
X990442Y220056D01*
G01X990486Y219980D02*
X990461Y220022D01*
G01X972977Y255238D02*
X974926Y257860D01*
G01X972911Y255122D02*
X972977Y255238D01*
G01X972886Y255080D02*
X972911Y255122D01*
G01Y252797D02*
G02X972886Y255080I2015J1164D01*
G01X972930Y251256D02*
G03X972911Y252797I-1384J754D01*
G01Y251222D02*
X972930Y251256D01*
G01X972886Y251180D02*
X972911Y251222D01*
G01Y248897D02*
G02X972886Y251180I2015J1164D01*
G01X972930Y247356D02*
G03X972911Y248897I-1384J754D01*
G01Y247322D02*
X972930Y247356D01*
G01X972886Y247280D02*
X972911Y247322D01*
G01Y244997D02*
G02X972886Y247280I2015J1164D01*
G01X972930Y243456D02*
G03X972911Y244997I-1384J754D01*
G01Y243422D02*
X972930Y243456D01*
G01X972886Y243380D02*
X972911Y243422D01*
G01Y241097D02*
G02X972886Y243380I2015J1164D01*
G01X972930Y239556D02*
G03X972911Y241097I-1384J754D01*
G01Y239522D02*
X972930Y239556D01*
G01X972886Y239480D02*
X972911Y239522D01*
G01Y237197D02*
G02X972886Y239480I2015J1164D01*
G01X972930Y235656D02*
G03X972911Y237197I-1384J754D01*
G01Y235622D02*
X972930Y235656D01*
G01X972886Y235580D02*
X972911Y235622D01*
G01Y233297D02*
G02X972886Y235580I2015J1164D01*
G01X972930Y231756D02*
G03X972911Y233297I-1384J754D01*
G01Y231722D02*
X972930Y231756D01*
G01X972886Y229439D02*
G02X972911Y231722I2040J1119D01*
G01Y229397D02*
X972886Y229439D01*
G01X972911Y227823D02*
G03Y229397I-1365J787D01*
G01Y225497D02*
G02Y227823I2015J1163D01*
G01X972930Y223956D02*
G03X972911Y225497I-1384J754D01*
G01Y223922D02*
X972930Y223956D01*
G01X972886Y223880D02*
X972911Y223922D01*
G01Y221597D02*
G02X972886Y223880I2015J1164D01*
G01X972911Y220021D02*
G03Y221597I-1365J788D01*
G01X972550Y219396D02*
X972911Y220021D01*
G01X1017500Y221598D02*
G03Y220024I1365J-787D01*
G01Y223924D02*
G02Y221598I-2015J-1163D01*
G01Y225498D02*
G03Y223924I1365J-787D01*
G01Y227824D02*
G02Y225498I-2015J-1163D01*
G01Y229398D02*
G03Y227824I1365J-787D01*
G01Y231724D02*
G02Y229398I-2015J-1163D01*
G01Y233298D02*
G03Y231724I1365J-787D01*
G01Y235624D02*
G02Y233298I-2015J-1163D01*
G01Y237198D02*
G03Y235624I1365J-787D01*
G01X1017565Y237310D02*
X1017500Y237198D01*
G01X1018865Y240309D02*
X1017565Y237310D01*
G01X978293Y263704D02*
X978306Y263709D01*
G01X976964Y260643D02*
X978293Y263704D01*
G01X976941Y260597D02*
G03X976964Y260643I-395J226D01*
G01X977702Y258355D02*
G02X976941Y260597I604J1455D01*
G01X979556Y256869D02*
G03X977702Y258355I-3490J-2454D01*
G01X978880Y254443D02*
G03X979556Y256869I-574J1467D01*
G01X976941Y252797D02*
G02X978880Y254443I3267J-1884D01*
G01X976941Y251223D02*
G02Y252797I1365J787D01*
G01Y248897D02*
G03Y251223I-2017J1163D01*
G01X976922Y247356D02*
G02X976941Y248897I1384J754D01*
G01Y247322D02*
X976922Y247356D01*
G01X976966Y247280D02*
X976941Y247322D01*
G01Y244997D02*
G03X976966Y247280I-2015J1164D01*
G01X976922Y243456D02*
G02X976941Y244997I1384J754D01*
G01Y243422D02*
X976922Y243456D01*
G01X976966Y243380D02*
X976941Y243422D01*
G01Y241097D02*
G03X976966Y243380I-2015J1164D01*
G01X976922Y239556D02*
G02X976941Y241097I1384J754D01*
G01Y239522D02*
X976922Y239556D01*
G01X976966Y239480D02*
X976941Y239522D01*
G01Y237197D02*
G03X976966Y239480I-2015J1164D01*
G01X976922Y235656D02*
G02X976941Y237197I1384J754D01*
G01Y235622D02*
X976922Y235656D01*
G01X976966Y235580D02*
X976941Y235622D01*
G01Y233297D02*
G03X976966Y235580I-2015J1164D01*
G01X976922Y231756D02*
G02X976941Y233297I1384J754D01*
G01Y231722D02*
X976922Y231756D01*
G01X976966Y229439D02*
G03X976941Y231722I-2040J1119D01*
G01Y229397D02*
X976966Y229439D01*
G01X976941Y227823D02*
G02Y229397I1365J787D01*
G01Y225497D02*
G03Y227823I-2015J1163D01*
G01X976922Y223956D02*
G02X976941Y225497I1384J754D01*
G01Y223922D02*
X976922Y223956D01*
G01X976966Y223880D02*
X976941Y223922D01*
G01Y221597D02*
G03X976966Y223880I-2015J1164D01*
G01X976711Y221199D02*
X976941Y221597D01*
G01X976711Y218615D02*
Y221199D01*
G01X978140Y255733D02*
X978306Y255909D01*
G01X976307Y253201D02*
G02X978140Y255733I13166J-7602D01*
G01X976291Y253173D02*
X976307Y253201D01*
G01X976291Y250847D02*
G02Y253173I2015J1163D01*
G01Y249272D02*
G03Y250847I-1364J787D01*
G01X976266Y246989D02*
G02X976291Y249272I2040J1119D01*
G01Y246947D02*
X976266Y246989D01*
G01X976310Y246913D02*
X976291Y246947D01*
G01Y245372D02*
G03X976310Y246913I-1365J787D01*
G01X976266Y243089D02*
G02X976291Y245372I2040J1119D01*
G01Y243047D02*
X976266Y243089D01*
G01X976310Y243013D02*
X976291Y243047D01*
G01Y241472D02*
G03X976310Y243013I-1365J787D01*
G01X976266Y239189D02*
G02X976291Y241472I2040J1119D01*
G01Y239147D02*
X976266Y239189D01*
G01X976310Y239113D02*
X976291Y239147D01*
G01Y237572D02*
G03X976310Y239113I-1365J787D01*
G01X976266Y235289D02*
G02X976291Y237572I2040J1119D01*
G01Y235247D02*
X976266Y235289D01*
G01X976310Y235213D02*
X976291Y235247D01*
G01Y233672D02*
G03X976310Y235213I-1365J787D01*
G01X976291Y231346D02*
G02Y233672I2015J1163D01*
G01Y229772D02*
G03Y231346I-1365J787D01*
G01X976266Y229730D02*
X976291Y229772D01*
G01Y227447D02*
G02X976266Y229730I2015J1164D01*
G01X976310Y227413D02*
X976291Y227447D01*
G01Y225872D02*
G03X976310Y227413I-1365J787D01*
G01X976266Y223589D02*
G02X976291Y225872I2040J1119D01*
G01Y223547D02*
X976266Y223589D01*
G01X976310Y223513D02*
X976291Y223547D01*
G01Y221972D02*
G03X976310Y223513I-1365J787D01*
G01X975961Y221399D02*
X976291Y221972D01*
G01X975961Y218926D02*
Y221399D01*
G01X989743Y254864D02*
X988446Y257860D01*
G01X989830Y254713D02*
X989743Y254864D01*
G01X989811Y253172D02*
G03X989830Y254713I-1365J787D01*
G01X989786Y250889D02*
G02X989811Y253172I2040J1119D01*
G01Y250847D02*
X989786Y250889D01*
G01X989830Y250813D02*
X989811Y250847D01*
G01Y249272D02*
G03X989830Y250813I-1365J787D01*
G01X989786Y246989D02*
G02X989811Y249272I2040J1119D01*
G01Y246947D02*
X989786Y246989D01*
G01X989830Y246913D02*
X989811Y246947D01*
G01Y245372D02*
G03X989830Y246913I-1365J787D01*
G01X989786Y243089D02*
G02X989811Y245372I2040J1119D01*
G01Y243047D02*
X989786Y243089D01*
G01X989830Y243013D02*
X989811Y243047D01*
G01Y241472D02*
G03X989830Y243013I-1365J787D01*
G01X989786Y239189D02*
G02X989811Y241472I2040J1119D01*
G01Y239147D02*
X989786Y239189D01*
G01X989830Y239113D02*
X989811Y239147D01*
G01Y237572D02*
G03X989830Y239113I-1365J787D01*
G01X989786Y235289D02*
G02X989811Y237572I2040J1119D01*
G01Y235247D02*
X989786Y235289D01*
G01X989830Y235213D02*
X989811Y235247D01*
G01Y233672D02*
G03X989830Y235213I-1365J787D01*
G01X989811Y231346D02*
G02Y233672I2015J1163D01*
G01Y229772D02*
G03Y231346I-1365J787D01*
G01X989786Y229730D02*
X989811Y229772D01*
G01Y227447D02*
G02X989786Y229730I2015J1164D01*
G01X989830Y227413D02*
X989811Y227447D01*
G01Y225872D02*
G03X989830Y227413I-1365J787D01*
G01X989786Y223589D02*
G02X989811Y225872I2040J1119D01*
G01Y223547D02*
X989786Y223589D01*
G01X989830Y223513D02*
X989811Y223547D01*
G01Y221972D02*
G03X989830Y223513I-1365J787D01*
G01X989786Y219689D02*
G02X989811Y221972I2040J1119D01*
G01Y219647D02*
X989786Y219689D01*
G01X989830Y219613D02*
X989811Y219647D01*
G01Y218072D02*
G03X989830Y219613I-1365J787D01*
G01X976266Y340589D02*
G02X976291Y342872I2040J1119D01*
G01Y340547D02*
X976266Y340589D01*
G01X976357Y340431D02*
X976291Y340547D01*
G01X978306Y337809D02*
X976357Y340431D01*
G01X990442Y340956D02*
G02X990461Y342497I1384J754D01*
G01X990529Y340805D02*
X990442Y340956D01*
G01X991826Y337809D02*
X990529Y340805D01*
G01X987106Y340589D02*
G03X987081Y342872I-2040J1119D01*
G01Y340547D02*
X987106Y340589D01*
G01X987062Y340513D02*
X987081Y340547D01*
G01Y338972D02*
G02X987062Y340513I1365J787D01*
G01X987147Y338859D02*
X987081Y338972D01*
G01X988446Y335860D02*
X987147Y338859D01*
G01X980249Y340407D02*
G03X980188Y341602I-1197J538D01*
G01X980321Y338974D02*
G02X980249Y340407I1365J787D01*
G01X981686Y335860D02*
X980321Y338974D01*
G01X1014926Y395976D02*
X1015275Y396325D01*
G01X1014926Y384853D02*
Y395976D01*
G01X1014101Y383413D02*
X1014926Y384853D01*
G01X1014120Y381872D02*
G02X1014101Y383413I1365J787D01*
G01X1014145Y379589D02*
G03X1014120Y381872I-2040J1119D01*
G01Y379547D02*
X1014145Y379589D01*
G01X1014101Y379513D02*
X1014120Y379547D01*
G01Y377972D02*
G02X1014101Y379513I1365J787D01*
G01X1014145Y375689D02*
G03X1014120Y377972I-2040J1119D01*
G01Y375647D02*
X1014145Y375689D01*
G01X1014101Y375613D02*
X1014120Y375647D01*
G01Y374072D02*
G02X1014101Y375613I1365J787D01*
G01X1014120Y371746D02*
G03Y374072I-2015J1163D01*
G01Y370172D02*
G02Y371746I1365J787D01*
G01X1014145Y370130D02*
X1014120Y370172D01*
G01Y367847D02*
G03X1014145Y370130I-2015J1164D01*
G01X1014101Y367813D02*
X1014120Y367847D01*
G01X1013909Y367050D02*
G02X1014101Y367813I1576J9D01*
G01X1013909Y360340D02*
Y367050D01*
G01X1012105Y357309D02*
X1013909Y360340D01*
G01X979904Y396227D02*
Y404899D01*
G01X987939Y388192D02*
X979904Y396227D01*
G01X990486Y383780D02*
X987939Y388192D01*
G01X990461Y381497D02*
G03X990486Y383780I-2015J1164D01*
G01X990442Y379956D02*
G02X990461Y381497I1384J754D01*
G01Y379922D02*
X990442Y379956D01*
G01X990486Y379880D02*
X990461Y379922D01*
G01Y377597D02*
G03X990486Y379880I-2015J1164D01*
G01X990442Y376056D02*
G02X990461Y377597I1384J754D01*
G01Y376022D02*
X990442Y376056D01*
G01X990486Y375980D02*
X990461Y376022D01*
G01Y373697D02*
G03X990486Y375980I-2015J1164D01*
G01X991755Y371335D02*
G02X990461Y373697I71J1574D01*
G01X991896Y371335D02*
X991755D01*
G01X993841Y367847D02*
G03X991896Y371335I-2015J1163D01*
G01X993822Y367813D02*
X993841Y367847D01*
G01Y366272D02*
G02X993822Y367813I1365J787D01*
G01X993866Y363989D02*
G03X993841Y366272I-2040J1119D01*
G01Y363947D02*
X993866Y363989D01*
G01X993822Y363913D02*
X993841Y363947D01*
G01Y362372D02*
G02X993822Y363913I1365J787D01*
G01X993866Y360089D02*
G03X993841Y362372I-2040J1119D01*
G01Y360047D02*
X993866Y360089D01*
G01X993822Y360013D02*
X993841Y360047D01*
G01Y358472D02*
G02X993822Y360013I1365J787D01*
G01X993866Y356189D02*
G03X993841Y358472I-2040J1119D01*
G01Y356147D02*
X993866Y356189D01*
G01X993822Y356113D02*
X993841Y356147D01*
G01Y354572D02*
G02X993822Y356113I1365J787D01*
G01X993866Y352289D02*
G03X993841Y354572I-2040J1119D01*
G01Y352247D02*
X993866Y352289D01*
G01X993822Y352213D02*
X993841Y352247D01*
G01Y350672D02*
G02X993822Y352213I1365J787D01*
G01X993866Y348389D02*
G03X993841Y350672I-2040J1119D01*
G01Y348347D02*
X993866Y348389D01*
G01X993822Y348313D02*
X993841Y348347D01*
G01Y346772D02*
G02X993822Y348313I1365J787D01*
G01X993866Y344489D02*
G03X993841Y346772I-2040J1119D01*
G01Y344447D02*
X993866Y344489D01*
G01X993775Y344331D02*
X993841Y344447D01*
G01X991826Y341709D02*
X993775Y344331D01*
G01X1005976Y395330D02*
Y403476D01*
G01X1003726Y393080D02*
X1005976Y395330D01*
G01X1003726Y388162D02*
Y393080D01*
G01X1004048Y387605D02*
X1003726Y388162D01*
G01X1004053Y387594D02*
X1004048Y387605D01*
G01X1005345Y384609D02*
X1004053Y387594D01*
G01X1010353Y397153D02*
X1011900Y398700D01*
G01X1010353Y389900D02*
Y397153D01*
G01X1010346Y389893D02*
X1010353Y389900D01*
G01X1010346Y388426D02*
Y389893D01*
G01X1010766Y387676D02*
X1010346Y388426D01*
G01X1010740Y385397D02*
G03X1010766Y387676I-2015J1163D01*
G01X1010721Y383856D02*
G02X1010740Y385397I1384J754D01*
G01Y383822D02*
X1010721Y383856D01*
G01X1010765Y383780D02*
X1010740Y383822D01*
G01Y381497D02*
G03X1010765Y383780I-2015J1164D01*
G01X1010721Y379956D02*
G02X1010740Y381497I1384J754D01*
G01Y379922D02*
X1010721Y379956D01*
G01X1010765Y379880D02*
X1010740Y379922D01*
G01Y377597D02*
G03X1010765Y379880I-2015J1164D01*
G01X1010721Y376056D02*
G02X1010740Y377597I1384J754D01*
G01Y376022D02*
X1010721Y376056D01*
G01X1010765Y375980D02*
X1010740Y376022D01*
G01Y373697D02*
G03X1010765Y375980I-2015J1164D01*
G01X1010721Y372156D02*
G02X1010740Y373697I1384J754D01*
G01Y372122D02*
X1010721Y372156D01*
G01X1008795Y368634D02*
G03X1010740Y372122I-70J2325D01*
G01X1008654Y368634D02*
X1008795D01*
G01X1007360Y367847D02*
G02X1008654Y368634I1365J-787D01*
G01X1007341Y367813D02*
X1007360Y367847D01*
G01X1007151Y367067D02*
G02X1007341Y367813I1561J0D01*
G01X1007151Y353025D02*
Y367067D01*
G01X1008716Y351460D02*
X1007151Y353025D01*
G01X1008725Y351460D02*
X1008716D01*
G01X1011968Y367435D02*
X1008725Y367060D01*
G01X1012149Y367435D02*
X1011968D01*
G01X1013470Y369797D02*
G02X1012149Y367435I-1365J-787D01*
G01X1013445Y369839D02*
X1013470Y369797D01*
G01Y372122D02*
G03X1013445Y369839I2015J-1164D01*
G01X1013489Y372156D02*
X1013470Y372122D01*
G01Y373697D02*
G02X1013489Y372156I-1365J-787D01*
G01X1013445Y375980D02*
G03X1013470Y373697I2040J-1119D01*
G01Y376022D02*
X1013445Y375980D01*
G01X1013489Y376056D02*
X1013470Y376022D01*
G01Y377597D02*
G02X1013489Y376056I-1365J-787D01*
G01X1013445Y379880D02*
G03X1013470Y377597I2040J-1119D01*
G01Y379922D02*
X1013445Y379880D01*
G01X1013489Y379956D02*
X1013470Y379922D01*
G01Y381497D02*
G02X1013489Y379956I-1365J-787D01*
G01X1013445Y383780D02*
G03X1013470Y381497I2040J-1119D01*
G01Y383822D02*
X1013445Y383780D01*
G01X1013704Y384239D02*
X1013470Y383822D01*
G01X1013704Y393696D02*
Y384239D01*
G01X1013200Y394200D02*
X1013704Y393696D01*
G01X1013200Y397100D02*
Y394200D01*
G01X1013754Y397654D02*
X1013200Y397100D01*
G01X991961Y399461D02*
Y401161D01*
G01X989900Y397400D02*
X991961Y399461D01*
G01X989900Y395400D02*
Y397400D01*
G01X990800Y394500D02*
X989900Y395400D01*
G01X992000Y394500D02*
X990800D01*
G01X993669Y392831D02*
X992000Y394500D01*
G01X993669Y390807D02*
Y392831D01*
G01X993841Y389672D02*
G02X993669Y390807I1365J787D01*
G01X993907Y389559D02*
X993841Y389672D01*
G01X995206Y386560D02*
X993907Y389559D01*
G01X1008218Y349816D02*
X1007274D01*
G01X1008655Y349885D02*
G03X1008218Y349816I51J-1740D01*
G01X1008795Y349885D02*
X1008655D01*
G01X1010740Y348722D02*
G03X1008795Y349885I-2015J-1162D01*
G01X1013470Y348722D02*
G02X1010740I-1365J787D01*
G01X1015415Y349885D02*
G03X1013470Y348722I70J-2325D01*
G01X1015555Y349885D02*
X1015415D01*
G01X1017500Y348722D02*
G03X1015555Y349885I-2015J-1162D01*
G01X1020230Y348722D02*
G02X1017500I-1365J787D01*
G01X1022175Y349885D02*
G03X1020230Y348722I70J-2325D01*
G01X1022935Y349885D02*
X1022175D01*
G01X1024230Y351180D02*
X1022935Y349885D01*
G01X1026620Y351180D02*
X1024230D01*
G01X1027914Y349886D02*
X1026620Y351180D01*
G01X1030286Y349886D02*
X1027914D01*
G01X1031800Y351400D02*
X1030286Y349886D01*
G01X1016100Y394300D02*
X1016650Y394850D01*
G01X1016100Y386248D02*
Y394300D01*
G01X1016850Y383446D02*
G02X1016100Y386248I4861J2802D01*
G01X1016850Y381872D02*
G03Y383446I-1365J787D01*
G01Y379546D02*
G02Y381872I2015J1163D01*
G01Y377972D02*
G03Y379546I-1365J787D01*
G01Y375646D02*
G02Y377972I2015J1163D01*
G01Y374072D02*
G03Y375646I-1365J787D01*
G01Y371746D02*
G02Y374072I2015J1163D01*
G01Y370172D02*
G03Y371746I-1365J787D01*
G01Y367846D02*
G02Y370172I2015J1163D01*
G01Y366272D02*
G03Y367846I-1365J787D01*
G01Y363946D02*
G02Y366272I2015J1163D01*
G01Y362372D02*
G03Y363946I-1365J787D01*
G01Y360046D02*
G02Y362372I2015J1163D01*
G01Y358472D02*
G03Y360046I-1365J787D01*
G01X1016713Y358194D02*
G02X1016850Y358472I2151J-887D01*
G01X1015485Y355360D02*
X1016713Y358194D01*
G01X1028349Y393972D02*
X1029138Y394761D01*
G01X1026990Y391622D02*
X1028349Y393972D01*
G01X1026990Y389296D02*
G02Y391622I2015J1163D01*
G01Y387722D02*
G03Y389296I-1365J787D01*
G01Y385396D02*
G02Y387722I2015J1163D01*
G01Y383822D02*
G03Y385396I-1365J787D01*
G01Y381496D02*
G02Y383822I2015J1163D01*
G01X1025669Y379134D02*
G03X1026990Y381496I-44J1575D01*
G01X1025540Y379134D02*
X1025669D01*
G01X1023610Y375646D02*
G02X1025540Y379134I2015J1163D01*
G01X1023610Y374072D02*
G03Y375646I-1365J787D01*
G01Y371746D02*
G02Y374072I2015J1163D01*
G01Y370172D02*
G03Y371746I-1365J787D01*
G01Y367846D02*
G02Y370172I2015J1163D01*
G01Y366272D02*
G03Y367846I-1365J787D01*
G01Y363946D02*
G02Y366272I2015J1163D01*
G01Y362372D02*
G03Y363946I-1365J787D01*
G01X1023585Y360089D02*
G02X1023610Y362372I2040J1119D01*
G01Y360047D02*
X1023585Y360089D01*
G01X1023629Y360013D02*
X1023610Y360047D01*
G01Y358472D02*
G03X1023629Y360013I-1365J787D01*
G01X1023455Y358149D02*
G02X1023610Y358472I2169J-842D01*
G01X1022245Y355360D02*
X1023455Y358149D01*
G01X997962Y394604D02*
Y396007D01*
G01X997012Y393654D02*
X997962Y394604D01*
G01X997012Y392403D02*
Y393654D01*
G01X997221Y391623D02*
G02X997012Y392403I1352J780D01*
G01X997528Y390317D02*
G03X997221Y391623I-2322J143D01*
G01X998586Y389259D02*
X997528Y390317D01*
G01X998586Y388509D02*
Y389259D01*
G01X983492Y388305D02*
X976456Y395341D01*
G01X983492Y383956D02*
Y388305D01*
G01X984413Y383035D02*
X983492Y383956D01*
G01X984800Y383035D02*
X984413D01*
G01X984801Y383034D02*
X984800Y383035D01*
G01X985151Y383034D02*
X984801D01*
G01X987106Y379589D02*
G03X985151Y383034I-2040J1120D01*
G01X987081Y379547D02*
X987106Y379589D01*
G01X987062Y379513D02*
X987081Y379547D01*
G01Y377972D02*
G02X987062Y379513I1365J787D01*
G01X987106Y375689D02*
G03X987081Y377972I-2040J1119D01*
G01Y375647D02*
X987106Y375689D01*
G01X987062Y375613D02*
X987081Y375647D01*
G01Y374072D02*
G02X987062Y375613I1365J787D01*
G01X987081Y371746D02*
G03Y374072I-2015J1163D01*
G01X988375Y369385D02*
G02X987081Y371746I71J1574D01*
G01X988531Y369385D02*
X988375D01*
G01X990461Y365897D02*
G03X988531Y369385I-2015J1163D01*
G01X990442Y364356D02*
G02X990461Y365897I1384J754D01*
G01Y364322D02*
X990442Y364356D01*
G01X990486Y364280D02*
X990461Y364322D01*
G01Y361997D02*
G03X990486Y364280I-2015J1164D01*
G01X990442Y360456D02*
G02X990461Y361997I1384J754D01*
G01Y360422D02*
X990442Y360456D01*
G01X990486Y360380D02*
X990461Y360422D01*
G01Y358097D02*
G03X990486Y360380I-2015J1164D01*
G01X990442Y356556D02*
G02X990461Y358097I1384J754D01*
G01Y356522D02*
X990442Y356556D01*
G01X990486Y356480D02*
X990461Y356522D01*
G01Y354197D02*
G03X990486Y356480I-2015J1164D01*
G01X990442Y352656D02*
G02X990461Y354197I1384J754D01*
G01Y352622D02*
X990442Y352656D01*
G01X990486Y352580D02*
X990461Y352622D01*
G01Y350297D02*
G03X990486Y352580I-2015J1164D01*
G01X990442Y348756D02*
G02X990461Y350297I1384J754D01*
G01Y348722D02*
X990442Y348756D01*
G01X990486Y348680D02*
X990461Y348722D01*
G01Y346397D02*
G03X990486Y348680I-2015J1164D01*
G01X990395Y346281D02*
X990461Y346397D01*
G01X988446Y343660D02*
X990395Y346281D01*
G01X976456Y401641D02*
X974656Y403441D01*
G01X976456Y395341D02*
Y401641D01*
G01X1030300Y401600D02*
Y406200D01*
G01X1021500Y392800D02*
X1030300Y401600D01*
G01X1021500Y392000D02*
Y392800D01*
G01X1020861Y391213D02*
G02X1021500Y392000I2444J-1332D01*
G01X1020880Y389672D02*
G02X1020861Y391213I1365J787D01*
G01X1020905Y387389D02*
G03X1020880Y389672I-2040J1119D01*
G01Y387347D02*
X1020905Y387389D01*
G01X1020861Y387313D02*
X1020880Y387347D01*
G01Y385772D02*
G02X1020861Y387313I1365J787D01*
G01X1020927Y385597D02*
G03X1020880Y385772I-351J0D01*
G01X1020927Y383927D02*
Y385597D01*
G01X1020300Y383300D02*
X1020927Y383927D01*
G01X1020300Y382144D02*
Y383300D01*
G01X1018865Y380709D02*
X1020300Y382144D01*
G01X1031200Y401400D02*
Y408614D01*
G01X1023026Y393226D02*
X1031200Y401400D01*
G01X1023026Y391241D02*
Y393226D01*
G01X1022245Y390460D02*
X1023026Y391241D01*
G01X1018800Y394099D02*
X1019301Y394600D01*
G01X1018300Y394099D02*
X1018800D01*
G01X1017222Y393021D02*
X1018300Y394099D01*
G01X1017222Y386322D02*
Y393021D01*
G01X1017200Y386300D02*
X1017222Y386322D01*
G01X1017200Y384942D02*
Y386300D01*
G01X1017500Y383822D02*
G02X1017200Y384942I1940J1120D01*
G01X1017500Y381496D02*
G03Y383822I-2015J1163D01*
G01Y379922D02*
G02Y381496I1365J787D01*
G01Y377596D02*
G03Y379922I-2015J1163D01*
G01Y376022D02*
G02Y377596I1365J787D01*
G01Y373696D02*
G03Y376022I-2015J1163D01*
G01Y372122D02*
G02Y373696I1365J787D01*
G01Y369796D02*
G03Y372122I-2015J1163D01*
G01Y368222D02*
G02Y369796I1365J787D01*
G01Y365896D02*
G03Y368222I-2015J1163D01*
G01Y364322D02*
G02Y365896I1365J787D01*
G01Y361996D02*
G03Y364322I-2015J1163D01*
G01Y360422D02*
G02Y361996I1365J787D01*
G01X1017725Y359888D02*
G03X1017500Y360422I-2240J-629D01*
G01X1018500Y358135D02*
X1017725Y359888D01*
G01X1018865Y357309D02*
X1018500Y358135D01*
G01X995962Y393037D02*
Y395968D01*
G01X996097Y392251D02*
X995962Y393037D01*
G01X996571Y391247D02*
G02X996097Y392251I7091J3962D01*
G01X996590Y391213D02*
X996571Y391247D01*
G01Y389672D02*
G03X996590Y391213I-1365J787D01*
G01X996546Y387389D02*
G02X996571Y389672I2040J1119D01*
G01Y387347D02*
X996546Y387389D01*
G01X996590Y387313D02*
X996571Y387347D01*
G01X995265Y384985D02*
G03X996590Y387313I-59J1575D01*
G01X995136Y384985D02*
X995265D01*
G01X993191Y383822D02*
G02X995136Y384985I2015J-1162D01*
G01X993123Y383705D02*
X993191Y383822D01*
G01X991826Y380709D02*
X993123Y383705D01*
G01X991461Y390085D02*
X988817Y392729D01*
G01X991845Y390085D02*
X991461D01*
G01X993210Y387756D02*
G03X991845Y390085I-1384J753D01*
G01X993123Y387605D02*
X993210Y387756D01*
G01X991826Y384609D02*
X993123Y387605D01*
G01X1007826Y400326D02*
X1009000Y401500D01*
G01X1007826Y389330D02*
Y400326D01*
G01X1007026Y388530D02*
X1007826Y389330D01*
G01X1007026Y381121D02*
Y388530D01*
G01X1006729Y379956D02*
G03X1007026Y381121I-2138J1165D01*
G01X1006710Y379922D02*
X1006729Y379956D01*
G01X1006685Y379880D02*
X1006710Y379922D01*
G01Y377597D02*
G02X1006685Y379880I2015J1164D01*
G01X1006729Y376056D02*
G03X1006710Y377597I-1384J754D01*
G01Y376022D02*
X1006729Y376056D01*
G01X1006685Y375980D02*
X1006710Y376022D01*
G01Y373697D02*
G02X1006685Y375980I2015J1164D01*
G01X1005416Y371335D02*
G03X1006710Y373697I-71J1574D01*
G01X1005275Y371335D02*
X1005416D01*
G01X1003330Y370172D02*
G02X1005275Y371335I2015J-1162D01*
G01X1002036Y369385D02*
G03X1003330Y370172I-71J1574D01*
G01X1001880Y369385D02*
X1002036D01*
G01X999950Y365896D02*
G02X1001880Y369385I2015J1164D01*
G01X999950Y364322D02*
G03Y365896I-1364J787D01*
G01X999915Y364262D02*
X999950Y364322D01*
G01Y361996D02*
G02X999915Y364262I2015J1164D01*
G01X999950Y360422D02*
G03Y361996I-1364J787D01*
G01X999884Y360308D02*
X999950Y360422D01*
G01X998586Y357309D02*
X999884Y360308D01*
G01X1008579Y345235D02*
X1005345Y345609D01*
G01X1008810Y345235D02*
X1008579D01*
G01X1010740Y346397D02*
G02X1008810Y345235I-2015J1163D01*
G01X1012046Y347184D02*
G03X1010740Y346397I59J-1575D01*
G01X1012164Y347184D02*
X1012046D01*
G01X1013470Y346397D02*
G03X1012164Y347184I-1365J-788D01*
G01X1015400Y345235D02*
G02X1013470Y346397I85J2325D01*
G01X1015570Y345235D02*
X1015400D01*
G01X1017500Y346397D02*
G02X1015570Y345235I-2015J1163D01*
G01X1018806Y347184D02*
G03X1017500Y346397I59J-1575D01*
G01X1018935Y347184D02*
X1018806D01*
G01X1020880Y348347D02*
G02X1018935Y347184I-2015J1162D01*
G01X1022201Y349135D02*
G03X1020880Y348347I44J-1575D01*
G01X1023085Y349135D02*
X1022201D01*
G01X1024360Y347860D02*
X1023085Y349135D01*
G01X1026070Y347860D02*
X1024360D01*
G01X1027980Y345950D02*
X1026070Y347860D01*
G01X973561Y370172D02*
G02Y371746I1365J787D01*
G01X973586Y370130D02*
X973561Y370172D01*
G01Y367847D02*
G03X973586Y370130I-2015J1164D01*
G01X973542Y367813D02*
X973561Y367847D01*
G01Y366272D02*
G02X973542Y367813I1365J787D01*
G01X973586Y363989D02*
G03X973561Y366272I-2040J1119D01*
G01Y363947D02*
X973586Y363989D01*
G01X973542Y363913D02*
X973561Y363947D01*
G01X974867Y361585D02*
G02X973542Y363913I59J1575D01*
G01X974996Y361585D02*
X974867D01*
G01X976941Y358097D02*
G03X974996Y361585I-2015J1163D01*
G01X976922Y356556D02*
G02X976941Y358097I1384J754D01*
G01Y356522D02*
X976922Y356556D01*
G01X976966Y356480D02*
X976941Y356522D01*
G01Y354197D02*
G03X976966Y356480I-2015J1164D01*
G01X976922Y352656D02*
G02X976941Y354197I1384J754D01*
G01Y352622D02*
X976922Y352656D01*
G01X976966Y352580D02*
X976941Y352622D01*
G01Y350297D02*
G03X976966Y352580I-2015J1164D01*
G01X976922Y348756D02*
G02X976941Y350297I1384J754D01*
G01Y348722D02*
X976922Y348756D01*
G01X976966Y348680D02*
X976941Y348722D01*
G01Y346397D02*
G03X976966Y348680I-2015J1164D01*
G01X976922Y344856D02*
G02X976941Y346397I1384J754D01*
G01X977009Y344705D02*
X976922Y344856D01*
G01X978306Y341709D02*
X977009Y344705D01*
G01X1003776Y396579D02*
Y404276D01*
G01X1001376Y394179D02*
X1003776Y396579D01*
G01X1001376Y388694D02*
Y394179D01*
G01X1000601Y387347D02*
G03X1001376Y388694I-551038J317938D01*
G01X1000601Y385773D02*
G02Y387347I1364J787D01*
G01X1000636Y383507D02*
G03X1000601Y385773I-2050J1102D01*
G01Y383447D02*
X1000636Y383507D01*
G01X1000601Y381873D02*
G02Y383447I1364J787D01*
G01X1000636Y379607D02*
G03X1000601Y381873I-2050J1102D01*
G01Y379547D02*
X1000636Y379607D01*
G01X1000601Y377973D02*
G02Y379547I1364J787D01*
G01X1000664Y377866D02*
X1000601Y377973D01*
G01X1001965Y374860D02*
X1000664Y377866D01*
G01X1003264Y366159D02*
X1001965Y363160D01*
G01X1003330Y366272D02*
X1003264Y366159D01*
G01X1005294Y367435D02*
G03X1003330Y366272I51J-2326D01*
G01X1005389Y367435D02*
X1005294D01*
G01X1006710Y368223D02*
G02X1005389Y367435I-1365J787D01*
G01X1008640Y369385D02*
G03X1006710Y368223I85J-2325D01*
G01X1008796Y369385D02*
X1008640D01*
G01X1010090Y371746D02*
G02X1008796Y369385I-1365J-787D01*
G01X1010090Y374072D02*
G03Y371746I2015J-1163D01*
G01X1010109Y375613D02*
G02X1010090Y374072I-1384J-754D01*
G01Y375647D02*
X1010109Y375613D01*
G01X1010065Y375689D02*
X1010090Y375647D01*
G01Y377972D02*
G03X1010065Y375689I2015J-1164D01*
G01X1010109Y379513D02*
G02X1010090Y377972I-1384J-754D01*
G01Y379547D02*
X1010109Y379513D01*
G01X1010065Y379589D02*
X1010090Y379547D01*
G01Y381872D02*
G03X1010065Y379589I2015J-1164D01*
G01X1010109Y383413D02*
G02X1010090Y381872I-1384J-754D01*
G01Y383447D02*
X1010109Y383413D01*
G01X1010065Y383489D02*
X1010090Y383447D01*
G01Y385772D02*
G03X1010065Y383489I2015J-1164D01*
G01X1010109Y387313D02*
G02X1010090Y385772I-1384J-754D01*
G01X1009610Y388205D02*
X1010109Y387313D01*
G01X1009326Y389005D02*
G03X1009610Y388205I2486J432D01*
G01X1009336Y389015D02*
X1009326Y389005D01*
G01X1009336Y398986D02*
Y389015D01*
G01X1010575Y400225D02*
X1009336Y398986D01*
G01X1002526Y397081D02*
Y405606D01*
G01X1000226Y394781D02*
X1002526Y397081D01*
G01X1000226Y389580D02*
Y394781D01*
G01X999950Y387722D02*
G03X1000226Y389580I-2184J1274D01*
G01X999915Y387662D02*
X999950Y387722D01*
G01Y385396D02*
G02X999915Y387662I2015J1164D01*
G01X999950Y383822D02*
G03Y385396I-1364J787D01*
G01X999915Y383762D02*
X999950Y383822D01*
G01Y381496D02*
G02X999915Y383762I2015J1164D01*
G01X999950Y379922D02*
G03Y381496I-1364J787D01*
G01X999915Y379862D02*
X999950Y379922D01*
G01Y377596D02*
G02X999915Y379862I2015J1164D01*
G01X999950Y376022D02*
G03Y377596I-1364J787D01*
G01X999915Y375962D02*
X999950Y376022D01*
G01X999763Y375613D02*
G02X999915Y375962I2202J-752D01*
G01X998683Y373006D02*
G03X999763Y375613I-2607J2607D01*
G01X998586Y372909D02*
X998683Y373006D01*
G01X973561Y379547D02*
X973586Y379589D01*
G01X973542Y379513D02*
X973561Y379547D01*
G01X974867Y377185D02*
G02X973542Y379513I59J1575D01*
G01X974996Y377185D02*
X974867D01*
G01X976941Y373697D02*
G03X974996Y377185I-2015J1163D01*
G01X976922Y372156D02*
G02X976941Y373697I1384J754D01*
G01Y372122D02*
X976922Y372156D01*
G01X976966Y369839D02*
G03X976941Y372122I-2040J1119D01*
G01Y369797D02*
X976966Y369839D01*
G01X976941Y368223D02*
G02Y369797I1365J787D01*
G01Y365898D02*
G03Y368223I-2016J1162D01*
G01X978307Y363534D02*
G02X976941Y365898I0J1577D01*
G01X978308Y363534D02*
X978307D01*
G01X980321Y360048D02*
G03X978308Y363534I-2013J1162D01*
G01X980321Y358474D02*
G02Y360048I1365J787D01*
G01Y356148D02*
G03Y358474I-2015J1163D01*
G01Y354574D02*
G02Y356148I1365J787D01*
G01Y352248D02*
G03Y354574I-2015J1163D01*
G01Y350674D02*
G02Y352248I1365J787D01*
G01Y348348D02*
G03Y350674I-2015J1163D01*
G01Y346774D02*
G02Y348348I1365J787D01*
G01X980479Y346443D02*
G03X980321Y346774I-2172J-834D01*
G01X981686Y343660D02*
X980479Y346443D01*
G01X1030800Y393000D02*
X1032084Y394284D01*
G01X1029200Y393000D02*
X1030800D01*
G01X1028686Y392486D02*
X1029200Y393000D01*
G01X1028163Y392123D02*
X1028686Y392486D01*
G01X1027640Y391247D02*
X1028163Y392123D01*
G01X1027621Y391213D02*
X1027640Y391247D01*
G01Y389672D02*
G02X1027621Y391213I1365J787D01*
G01X1027665Y387389D02*
G03X1027640Y389672I-2040J1119D01*
G01Y387347D02*
X1027665Y387389D01*
G01X1027621Y387313D02*
X1027640Y387347D01*
G01Y385772D02*
G02X1027621Y387313I1365J787D01*
G01X1027665Y383489D02*
G03X1027640Y385772I-2040J1119D01*
G01Y383447D02*
X1027665Y383489D01*
G01X1027621Y383413D02*
X1027640Y383447D01*
G01Y381872D02*
G02X1027621Y383413I1365J787D01*
G01X1027665Y379589D02*
G03X1027640Y381872I-2040J1119D01*
G01Y379547D02*
X1027665Y379589D01*
G01X1027621Y379513D02*
X1027640Y379547D01*
G01X1027431Y378766D02*
G02X1027621Y379513I1562J0D01*
G01X1027431Y362507D02*
Y378766D01*
G01X1027435Y362503D02*
X1027431Y362507D01*
G01X1027435Y360389D02*
Y362503D01*
G01X1025625Y357309D02*
X1027435Y360389D01*
G01X1003330Y381872D02*
G03X1001965Y378760I13451J-7755D01*
G01X1003349Y383413D02*
G02X1003330Y381872I-1384J-754D01*
G01Y383447D02*
X1003349Y383413D01*
G01X1003305Y383489D02*
X1003330Y383447D01*
G01Y385772D02*
G03X1003305Y383489I2015J-1164D01*
G01X1003349Y387313D02*
G02X1003330Y385772I-1384J-754D01*
G01X1002561Y388683D02*
X1003349Y387313D01*
G01X1002561Y393715D02*
Y388683D01*
G01X1004926Y396080D02*
X1002561Y393715D01*
G01X1004926Y404126D02*
Y396080D01*
G01X972911Y372122D02*
X972930Y372156D01*
G01X972886Y369839D02*
G02X972911Y372122I2040J1119D01*
G01Y369797D02*
X972886Y369839D01*
G01X972911Y368223D02*
G03Y369797I-1365J787D01*
G01Y365897D02*
G02Y368223I2015J1163D01*
G01X972930Y364356D02*
G03X972911Y365897I-1384J754D01*
G01Y364322D02*
X972930Y364356D01*
G01X972886Y364280D02*
X972911Y364322D01*
G01X974841Y360835D02*
G02X972886Y364280I85J2325D01*
G01X974970Y360835D02*
X974841D01*
G01X976291Y358472D02*
G03X974970Y360835I-1365J788D01*
G01X976266Y356189D02*
G02X976291Y358472I2040J1119D01*
G01Y356147D02*
X976266Y356189D01*
G01X976310Y356113D02*
X976291Y356147D01*
G01Y354572D02*
G03X976310Y356113I-1365J787D01*
G01X976266Y352289D02*
G02X976291Y354572I2040J1119D01*
G01Y352247D02*
X976266Y352289D01*
G01X976310Y352213D02*
X976291Y352247D01*
G01Y350672D02*
G03X976310Y352213I-1365J787D01*
G01X976266Y348389D02*
G02X976291Y350672I2040J1119D01*
G01Y348347D02*
X976266Y348389D01*
G01X976310Y348313D02*
X976291Y348347D01*
G01Y346772D02*
G03X976310Y348313I-1365J787D01*
G01X976266Y344489D02*
G02X976291Y346772I2040J1119D01*
G01Y344447D02*
X976266Y344489D01*
G01X976310Y344413D02*
X976291Y344447D01*
G01Y342872D02*
G03X976310Y344413I-1365J787D01*
G01X979156Y395917D02*
Y404899D01*
G01X987340Y387733D02*
X979156Y395917D01*
G01X989830Y383413D02*
X987340Y387733D01*
G01X989811Y381872D02*
G03X989830Y383413I-1365J787D01*
G01X989786Y379589D02*
G02X989811Y381872I2040J1119D01*
G01Y379547D02*
X989786Y379589D01*
G01X989830Y379513D02*
X989811Y379547D01*
G01Y377972D02*
G03X989830Y379513I-1365J787D01*
G01X989786Y375689D02*
G02X989811Y377972I2040J1119D01*
G01Y375647D02*
X989786Y375689D01*
G01X989830Y375613D02*
X989811Y375647D01*
G01Y374072D02*
G03X989830Y375613I-1365J787D01*
G01X991741Y370584D02*
G02X989811Y374072I85J2325D01*
G01X991897Y370584D02*
X991741D01*
G01X993191Y368223D02*
G03X991897Y370584I-1365J787D01*
G01X993191Y365897D02*
G02Y368223I2015J1163D01*
G01X993210Y364356D02*
G03X993191Y365897I-1384J754D01*
G01Y364322D02*
X993210Y364356D01*
G01X993166Y364280D02*
X993191Y364322D01*
G01Y361997D02*
G02X993166Y364280I2015J1164D01*
G01X993210Y360456D02*
G03X993191Y361997I-1384J754D01*
G01Y360422D02*
X993210Y360456D01*
G01X993166Y360380D02*
X993191Y360422D01*
G01Y358097D02*
G02X993166Y360380I2015J1164D01*
G01X993210Y356556D02*
G03X993191Y358097I-1384J754D01*
G01Y356522D02*
X993210Y356556D01*
G01X993166Y356480D02*
X993191Y356522D01*
G01Y354197D02*
G02X993166Y356480I2015J1164D01*
G01X993210Y352656D02*
G03X993191Y354197I-1384J754D01*
G01Y352622D02*
X993210Y352656D01*
G01X993166Y352580D02*
X993191Y352622D01*
G01Y350297D02*
G02X993166Y352580I2015J1164D01*
G01X993210Y348756D02*
G03X993191Y350297I-1384J754D01*
G01Y348722D02*
X993210Y348756D01*
G01X993166Y348680D02*
X993191Y348722D01*
G01Y346397D02*
G02X993166Y348680I2015J1164D01*
G01X991870Y344034D02*
G03X993191Y346397I-44J1575D01*
G01X991826Y344034D02*
X991870D01*
G01X991109Y343620D02*
G02X991826Y344034I717J-414D01*
G01X990461Y342497D02*
X991109Y343620D01*
G01X975708Y401289D02*
X973856Y403141D01*
G01X975708Y395031D02*
Y401289D01*
G01X982744Y387995D02*
X975708Y395031D01*
G01X982744Y383646D02*
Y387995D01*
G01X984103Y382287D02*
X982744Y383646D01*
G01X984490Y382287D02*
X984103D01*
G01X984491Y382286D02*
X984490Y382287D01*
G01X984773Y382286D02*
X984491D01*
G01X984775Y382284D02*
X984773Y382286D01*
G01X985125Y382284D02*
X984775D01*
G01X986450Y379956D02*
G03X985125Y382284I-1384J753D01*
G01X986431Y379922D02*
X986450Y379956D01*
G01X986406Y379880D02*
X986431Y379922D01*
G01Y377597D02*
G02X986406Y379880I2015J1164D01*
G01X986450Y376056D02*
G03X986431Y377597I-1384J754D01*
G01Y376022D02*
X986450Y376056D01*
G01X986406Y375980D02*
X986431Y376022D01*
G01Y373697D02*
G02X986406Y375980I2015J1164D01*
G01X986450Y372156D02*
G03X986431Y373697I-1384J754D01*
G01Y372122D02*
X986450Y372156D01*
G01X988376Y368634D02*
G02X986431Y372122I70J2325D01*
G01X988517Y368634D02*
X988376D01*
G01X989811Y366272D02*
G03X988517Y368634I-1365J788D01*
G01X989786Y363989D02*
G02X989811Y366272I2040J1119D01*
G01Y363947D02*
X989786Y363989D01*
G01X989830Y363913D02*
X989811Y363947D01*
G01Y362372D02*
G03X989830Y363913I-1365J787D01*
G01X989786Y360089D02*
G02X989811Y362372I2040J1119D01*
G01Y360047D02*
X989786Y360089D01*
G01X989830Y360013D02*
X989811Y360047D01*
G01Y358472D02*
G03X989830Y360013I-1365J787D01*
G01X989786Y356189D02*
G02X989811Y358472I2040J1119D01*
G01Y356147D02*
X989786Y356189D01*
G01X989830Y356113D02*
X989811Y356147D01*
G01Y354572D02*
G03X989830Y356113I-1365J787D01*
G01X989786Y352289D02*
G02X989811Y354572I2040J1119D01*
G01Y352247D02*
X989786Y352289D01*
G01X989830Y352213D02*
X989811Y352247D01*
G01Y350672D02*
G03X989830Y352213I-1365J787D01*
G01X989786Y348389D02*
G02X989811Y350672I2040J1119D01*
G01Y348347D02*
X989786Y348389D01*
G01X989830Y348313D02*
X989811Y348347D01*
G01X988505Y345985D02*
G03X989830Y348313I-59J1575D01*
G01X988446Y345985D02*
X988505D01*
G01X987729Y345571D02*
G02X988446Y345985I717J-414D01*
G01X987062Y344413D02*
X987729Y345571D01*
G01X987081Y342872D02*
G02X987062Y344413I1365J787D01*
G01X1032000Y401100D02*
Y407240D01*
G01X1024026Y393126D02*
X1032000Y401100D01*
G01X1024026Y388341D02*
Y393126D01*
G01X1022245Y386560D02*
X1024026Y388341D01*
G01X1029500Y402000D02*
Y404662D01*
G01X1020500Y393000D02*
X1029500Y402000D01*
G01X1020500Y392700D02*
Y393000D01*
G01X1020230Y391623D02*
G03X1020500Y392700I-1753J1012D01*
G01X1020230Y389297D02*
G02Y391623I2015J1163D01*
G01X1020249Y387756D02*
G03X1020230Y389297I-1384J754D01*
G01X1020162Y387605D02*
X1020249Y387756D01*
G01X1018865Y384609D02*
X1020162Y387605D01*
G01X972911Y379922D02*
X972930Y379956D01*
G01X972886Y379880D02*
X972911Y379922D01*
G01X974841Y376435D02*
G02X972886Y379880I85J2325D01*
G01X974970Y376435D02*
X974841D01*
G01X976291Y374072D02*
G03X974970Y376435I-1365J788D01*
G01X976291Y371746D02*
G02Y374072I2015J1163D01*
G01Y370172D02*
G03Y371746I-1365J787D01*
G01X976266Y370130D02*
X976291Y370172D01*
G01Y367847D02*
G02X976266Y370130I2015J1164D01*
G01X976291Y366274D02*
G03Y367847I-1363J787D01*
G01X978306Y362784D02*
G02X976291Y366274I0J2327D01*
G01X978308Y362784D02*
X978306D01*
G01X979671Y360424D02*
G03X978308Y362784I-1363J786D01*
G01X979671Y358098D02*
G02Y360424I2015J1163D01*
G01Y356524D02*
G03Y358098I-1365J787D01*
G01Y354198D02*
G02Y356524I2015J1163D01*
G01Y352624D02*
G03Y354198I-1365J787D01*
G01Y350298D02*
G02Y352624I2015J1163D01*
G01Y348724D02*
G03Y350298I-1365J787D01*
G01Y346398D02*
G02Y348724I2015J1163D01*
G01Y344824D02*
G03Y346398I-1365J787D01*
G01Y342498D02*
G02Y344824I2015J1163D01*
G01X980188Y341602D02*
X979671Y342498D01*
G01X979904Y404899D02*
X980856Y405851D01*
G01X1009162Y406662D02*
Y407781D01*
G01X1005976Y403476D02*
X1009162Y406662D01*
G01X974656Y405345D02*
X975483Y406172D01*
G01X974656Y403441D02*
Y405345D01*
G01X1029562Y406938D02*
Y410706D01*
G01X1030300Y406200D02*
X1029562Y406938D01*
G01X1032762Y410176D02*
Y411204D01*
G01X1031200Y408614D02*
X1032762Y410176D01*
G01X1005162Y405662D02*
Y407821D01*
G01X1003776Y404276D02*
X1005162Y405662D01*
G01X1003162Y406242D02*
Y407821D01*
G01X1002526Y405606D02*
X1003162Y406242D01*
G01X1007162Y406362D02*
X1004926Y404126D01*
G01X1007162Y407727D02*
Y406362D01*
G01X979156Y404899D02*
X978356Y405699D01*
G01X973856Y405299D02*
X972983Y406172D01*
G01X973856Y403141D02*
Y405299D01*
G01X1032000Y407240D02*
X1034762Y410002D01*
G01X1027562Y406600D02*
Y410841D01*
G01X1029500Y404662D02*
X1027562Y406600D01*
G01X1083706Y217359D02*
G03X1083725Y218900I-1365J787D01*
G01X1083681Y215076D02*
G02X1083706Y217359I2040J1119D01*
G01Y215034D02*
X1083681Y215076D01*
G01X1083725Y215000D02*
X1083706Y215034D01*
G01Y213459D02*
G03X1083725Y215000I-1365J787D01*
G01X1083396Y212303D02*
G02X1083706Y213459I2312J0D01*
G01X1083396Y207646D02*
Y212303D01*
G01X1086166Y204876D02*
X1083396Y207646D01*
G01X1086166Y191577D02*
Y204876D01*
G01X1088186Y189557D02*
X1086166Y191577D01*
G01X1088186Y186686D02*
Y189557D01*
G01X1087379Y185879D02*
X1088186Y186686D01*
G01X1047256Y191865D02*
Y190969D01*
G01X1043437Y198479D02*
X1047256Y191865D01*
G01X1040950Y200966D02*
X1043437Y198479D01*
G01X1040950Y207450D02*
Y200966D01*
G01X1041700Y208200D02*
X1040950Y207450D01*
G01X1041700Y210236D02*
Y208200D01*
G01X1042524Y211060D02*
X1041700Y210236D01*
G01X1036126Y196794D02*
Y195037D01*
G01X1034200Y198720D02*
X1036126Y196794D01*
G01X1034200Y202688D02*
Y198720D01*
G01X1071356Y190286D02*
X1072065Y189577D01*
G01X1071356Y191530D02*
Y190286D01*
G01X1073608Y193782D02*
X1071356Y191530D01*
G01X1073608Y201419D02*
Y193782D01*
G01X1070915Y204112D02*
X1073608Y201419D01*
G01X1070915Y210762D02*
Y204112D01*
G01X1071147Y210994D02*
X1070915Y210762D01*
G01X1071147Y214870D02*
Y210994D01*
G01X1070818Y215443D02*
X1071147Y214870D01*
G01X1070837Y216984D02*
G03X1070818Y215443I1365J-787D01*
G01X1070862Y219267D02*
G02X1070837Y216984I-2040J-1119D01*
G01X1057806Y192394D02*
Y191151D01*
G01X1051800Y198400D02*
X1057806Y192394D01*
G01X1051800Y204643D02*
Y198400D01*
G01X1049284Y207159D02*
X1051800Y204643D01*
G01X1084356Y216984D02*
G03X1084381Y219267I-2015J1164D01*
G01X1084337Y215443D02*
G02X1084356Y216984I1384J754D01*
G01Y215409D02*
X1084337Y215443D01*
G01X1084381Y215367D02*
X1084356Y215409D01*
G01Y213084D02*
G03X1084381Y215367I-2015J1164D01*
G01X1084146Y212300D02*
G02X1084356Y213084I1569J0D01*
G01X1084146Y207954D02*
Y212300D01*
G01X1086914Y205186D02*
X1084146Y207954D01*
G01X1086914Y191890D02*
Y205186D01*
G01X1088936Y189868D02*
X1086914Y191890D01*
G01X1088936Y187064D02*
Y189868D01*
G01X1089879Y186121D02*
X1088936Y187064D01*
G01X1034100Y206598D02*
Y213600D01*
G01X1036200Y204498D02*
X1034100Y206598D01*
G01X1036200Y200300D02*
Y204498D01*
G01X1040056Y196444D02*
X1036200Y200300D01*
G01X1040056Y191575D02*
Y196444D01*
G01X1043824Y215860D02*
X1042524Y218860D01*
G01X1043889Y215748D02*
X1043824Y215860D01*
G01X1043889Y214174D02*
G03Y215748I-1365J787D01*
G01Y211848D02*
G02Y214174I2015J1163D01*
G01Y210274D02*
G03Y211848I-1365J787D01*
G01X1043578Y209180D02*
G02X1043889Y210274I2326J-70D01*
G01X1043578Y207780D02*
Y209180D01*
G01X1046800Y202457D02*
X1043578Y207780D01*
G01X1048806Y194629D02*
X1046800Y202457D01*
G01X1050506Y192929D02*
X1048806Y194629D01*
G01X1050506Y191694D02*
Y192929D01*
G01X1034126Y194697D02*
Y196538D01*
G01X1055806Y192494D02*
Y190981D01*
G01X1051000Y197300D02*
X1055806Y192494D01*
G01X1051000Y203685D02*
Y197300D01*
G01X1050271Y204692D02*
X1051000Y203685D01*
G01X1048142Y205789D02*
X1050271Y204692D01*
G01X1047576Y207031D02*
X1048142Y205789D01*
G01X1047576Y209280D02*
Y207031D01*
G01X1045904Y213009D02*
X1047576Y209280D01*
G01X1070606Y190618D02*
X1069565Y189577D01*
G01X1070606Y191841D02*
Y190618D01*
G01X1072858Y194093D02*
X1070606Y191841D01*
G01X1072858Y201109D02*
Y194093D01*
G01X1070166Y203801D02*
X1072858Y201109D01*
G01X1070166Y211071D02*
Y203801D01*
G01X1070397Y211302D02*
X1070166Y211071D01*
G01X1070397Y214649D02*
Y211302D01*
G01X1070187Y215034D02*
X1070397Y214649D01*
G01X1070162Y215076D02*
X1070187Y215034D01*
G01Y217359D02*
G03X1070162Y215076I2015J-1164D01*
G01X1070206Y218900D02*
G02X1070187Y217359I-1384J-754D01*
G01X1037400Y215700D02*
X1036191Y216909D01*
G01X1037400Y200500D02*
Y215700D01*
G01X1040900Y197000D02*
X1037400Y200500D01*
G01X1040900Y194092D02*
Y197000D01*
G01X1042056Y192936D02*
X1040900Y194092D01*
G01X1042056Y191624D02*
Y192936D01*
G01X1040726Y209630D02*
X1039145Y213009D01*
G01X1040726Y208326D02*
Y209630D01*
G01X1040100Y207700D02*
X1040726Y208326D01*
G01X1040100Y200600D02*
Y207700D01*
G01X1042568Y198132D02*
X1040100Y200600D01*
G01X1045256Y193480D02*
X1042568Y198132D01*
G01X1045256Y191381D02*
Y193480D01*
G01X1087736Y217359D02*
G02X1087717Y218900I1365J787D01*
G01X1087761Y215076D02*
G03X1087736Y217359I-2040J1119D01*
G01Y215034D02*
X1087761Y215076D01*
G01X1087717Y215000D02*
X1087736Y215034D01*
G01Y213459D02*
G02X1087717Y215000I1365J787D01*
G01X1087736Y211133D02*
G03Y213459I-2015J1163D01*
G01X1087717Y211099D02*
X1087736Y211133D01*
G01X1087525Y210346D02*
G02X1087717Y211099I1576J-1D01*
G01X1087525Y208849D02*
Y210346D01*
G01X1089766Y206608D02*
X1087525Y208849D01*
G01X1089766Y194810D02*
Y206608D01*
G01X1093886Y190690D02*
X1089766Y194810D01*
G01X1093886Y189570D02*
Y190690D01*
G01X1094879Y188577D02*
X1093886Y189570D01*
G01X1087086Y211509D02*
G03X1086774Y210346I2015J-1164D01*
G01X1087105Y211543D02*
X1087086Y211509D01*
G01Y213084D02*
G02X1087105Y211543I-1365J-787D01*
G01X1087061Y215367D02*
G03X1087086Y213084I2040J-1119D01*
G01Y215409D02*
X1087061Y215367D01*
G01X1087105Y215443D02*
X1087086Y215409D01*
G01Y216984D02*
G02X1087105Y215443I-1365J-787D01*
G01X1087061Y219267D02*
G03X1087086Y216984I2040J-1119D01*
G01X1086774Y208537D02*
Y210346D01*
G01X1089016Y206295D02*
X1086774Y208537D01*
G01X1089016Y194498D02*
Y206295D01*
G01X1093136Y190378D02*
X1089016Y194498D01*
G01X1093136Y189334D02*
Y190378D01*
G01X1092379Y188577D02*
X1093136Y189334D01*
G01X1073567Y216984D02*
G02X1073542Y219267I2015J1164D01*
G01X1073778Y216196D02*
G03X1073567Y216984I-1575J1D01*
G01X1073778Y215533D02*
Y216196D01*
G01X1073417Y215172D02*
X1073778Y215533D01*
G01X1073417Y208253D02*
Y215172D01*
G01X1073185Y208021D02*
X1073417Y208253D01*
G01X1073185Y205044D02*
Y208021D01*
G01X1075878Y202351D02*
X1073185Y205044D01*
G01X1075878Y192841D02*
Y202351D01*
G01X1075266Y192229D02*
X1075878Y192841D01*
G01X1075266Y189278D02*
Y192229D01*
G01X1074565Y188577D02*
X1075266Y189278D01*
G01X1044604Y213910D02*
X1045904Y216909D01*
G01X1044539Y213798D02*
X1044604Y213910D01*
G01X1044539Y212224D02*
G02Y213798I1365J787D01*
G01Y209898D02*
G03Y212224I-2015J1163D01*
G01Y208324D02*
G02Y209898I1365J787D01*
G01X1047669Y202973D02*
X1044539Y208324D01*
G01X1049536Y196012D02*
X1047669Y202973D01*
G01X1052506Y193042D02*
X1049536Y196012D01*
G01X1052506Y191500D02*
Y193042D01*
G01X1074217Y217359D02*
G02X1074198Y218900I1365J787D01*
G01X1074528Y216198D02*
G03X1074217Y217359I-2323J0D01*
G01X1074528Y215222D02*
Y216198D01*
G01X1074167Y214861D02*
X1074528Y215222D01*
G01X1074167Y207945D02*
Y214861D01*
G01X1073934Y207712D02*
X1074167Y207945D01*
G01X1073934Y205361D02*
Y207712D01*
G01X1073936Y205359D02*
X1073934Y205361D01*
G01X1073936Y205357D02*
Y205359D01*
G01X1076629Y202664D02*
X1073936Y205357D01*
G01X1076628Y202663D02*
X1076629Y202664D01*
G01X1076628Y192530D02*
Y202663D01*
G01X1076016Y191918D02*
X1076628Y192530D01*
G01X1076016Y189626D02*
Y191918D01*
G01X1077065Y188577D02*
X1076016Y189626D01*
G01X1083495Y233081D02*
X1082341Y233746D01*
G01X1083589Y232730D02*
X1083495Y233081D01*
G01X1083706Y230634D02*
G02X1083589Y232730I2015J1164D01*
G01X1083706Y230633D02*
Y230634D01*
G01Y229059D02*
G03Y230633I-1365J787D01*
G01X1083681Y226776D02*
G02X1083706Y229059I2043J1119D01*
G01Y226734D02*
X1083681Y226776D01*
G01X1083725Y226700D02*
X1083706Y226734D01*
G01Y225159D02*
G03X1083725Y226700I-1365J787D01*
G01X1083681Y222876D02*
G02X1083706Y225159I2040J1119D01*
G01Y222834D02*
X1083681Y222876D01*
G01X1083725Y222800D02*
X1083706Y222834D01*
G01Y221259D02*
G03X1083725Y222800I-1365J787D01*
G01X1083681Y218976D02*
G02X1083706Y221259I2040J1119D01*
G01Y218934D02*
X1083681Y218976D01*
G01X1083725Y218900D02*
X1083706Y218934D01*
G01X1070837Y219309D02*
X1070862Y219267D01*
G01X1070818Y219343D02*
X1070837Y219309D01*
G01Y220884D02*
G03X1070818Y219343I1365J-787D01*
G01X1070862Y223167D02*
G02X1070837Y220884I-2040J-1119D01*
G01Y223209D02*
X1070862Y223167D01*
G01X1070818Y223243D02*
X1070837Y223209D01*
G01Y224784D02*
G03X1070818Y223243I1365J-787D01*
G01X1070862Y227067D02*
G02X1070837Y224784I-2040J-1119D01*
G01Y227109D02*
X1070862Y227067D01*
G01X1070818Y227143D02*
X1070837Y227109D01*
G01Y228683D02*
G03X1070818Y227143I1363J-787D01*
G01X1070837Y231009D02*
G02Y228683I-2015J-1163D01*
G01Y232583D02*
G03Y231009I1364J-787D01*
G01X1071000Y232866D02*
X1070837Y232583D01*
G01X1072649Y234185D02*
X1071000Y232866D01*
G01X1073567Y236484D02*
G02X1072649Y234185I-1365J-788D01*
G01X1073501Y236597D02*
X1073567Y236484D01*
G01X1072202Y239596D02*
X1073501Y236597D01*
G01X1083706Y238433D02*
X1082341Y241547D01*
G01X1083893Y237376D02*
G03X1083706Y238433I-1552J270D01*
G01X1084356Y234909D02*
G02X1083893Y237376I3278J1892D01*
G01X1084356Y232583D02*
G03Y234909I-2015J1163D01*
G01Y231009D02*
G02Y232583I1365J787D01*
G01Y228683D02*
G03Y231009I-2015J1163D01*
G01X1084337Y227143D02*
G02X1084356Y228683I1382J753D01*
G01Y227109D02*
X1084337Y227143D01*
G01X1084381Y227067D02*
X1084356Y227109D01*
G01Y224784D02*
G03X1084381Y227067I-2015J1164D01*
G01X1084337Y223243D02*
G02X1084356Y224784I1384J754D01*
G01Y223209D02*
X1084337Y223243D01*
G01X1084381Y223167D02*
X1084356Y223209D01*
G01Y220884D02*
G03X1084381Y223167I-2015J1164D01*
G01X1084337Y219343D02*
G02X1084356Y220884I1384J754D01*
G01X1084339Y219339D02*
X1084337Y219343D01*
G01X1084356Y219309D02*
X1084339Y219339D01*
G01X1084381Y219267D02*
X1084356Y219309D01*
G01X1070187Y218934D02*
X1070206Y218900D01*
G01X1070162Y218976D02*
X1070187Y218934D01*
G01Y221259D02*
G03X1070162Y218976I2015J-1164D01*
G01X1070206Y222800D02*
G02X1070187Y221259I-1384J-754D01*
G01Y222834D02*
X1070206Y222800D01*
G01X1070162Y222876D02*
X1070187Y222834D01*
G01Y225159D02*
G03X1070162Y222876I2015J-1164D01*
G01X1070206Y226700D02*
G02X1070187Y225159I-1384J-754D01*
G01Y226734D02*
X1070206Y226700D01*
G01X1070162Y226776D02*
X1070187Y226734D01*
G01X1070186Y229059D02*
G03X1070162Y226776I2015J-1163D01*
G01X1070186Y230633D02*
G02Y229059I-1364J-787D01*
G01Y232959D02*
G03Y230633I2015J-1163D01*
G01X1071013Y234406D02*
X1070186Y232959D01*
G01X1071061Y234471D02*
G03X1071013Y234406I256J-239D01*
G01X1072202Y235696D02*
X1071061Y234471D01*
G01X1087670Y236975D02*
X1085721Y239596D01*
G01X1087736Y236859D02*
X1087670Y236975D01*
G01X1087736Y234533D02*
G03Y236859I-2015J1163D01*
G01Y232959D02*
G02Y234533I1365J787D01*
G01X1087761Y232917D02*
X1087736Y232959D01*
G01Y230634D02*
G03X1087761Y232917I-2015J1164D01*
G01X1087717Y230600D02*
X1087736Y230634D01*
G01Y229059D02*
G02X1087717Y230600I1365J787D01*
G01X1087761Y226776D02*
G03X1087736Y229059I-2040J1119D01*
G01Y226734D02*
X1087761Y226776D01*
G01X1087717Y226700D02*
X1087736Y226734D01*
G01Y225159D02*
G02X1087717Y226700I1365J787D01*
G01X1087761Y222876D02*
G03X1087736Y225159I-2040J1119D01*
G01Y222834D02*
X1087761Y222876D01*
G01X1087717Y222800D02*
X1087736Y222834D01*
G01Y221259D02*
G02X1087717Y222800I1365J787D01*
G01X1087761Y218976D02*
G03X1087736Y221259I-2040J1119D01*
G01Y218934D02*
X1087761Y218976D01*
G01X1087717Y218900D02*
X1087736Y218934D01*
G01X1087086Y219309D02*
X1087061Y219267D01*
G01X1087105Y219343D02*
X1087086Y219309D01*
G01Y220884D02*
G02X1087105Y219343I-1365J-787D01*
G01X1087061Y223167D02*
G03X1087086Y220884I2040J-1119D01*
G01Y223209D02*
X1087061Y223167D01*
G01X1087105Y223243D02*
X1087086Y223209D01*
G01Y224784D02*
G02X1087105Y223243I-1365J-787D01*
G01X1087061Y227067D02*
G03X1087086Y224784I2040J-1119D01*
G01Y227109D02*
X1087061Y227067D01*
G01X1087105Y227143D02*
X1087086Y227109D01*
G01Y228684D02*
G02X1087105Y227143I-1365J-787D01*
G01X1087086Y231010D02*
G03Y228684I2015J-1163D01*
G01Y232584D02*
G02Y231010I-1365J-787D01*
G01X1087019Y232699D02*
X1087086Y232584D01*
G01X1085721Y235696D02*
X1087019Y232699D01*
G01X1075415Y233569D02*
X1075582Y233746D01*
G01X1073582Y231037D02*
G02X1075415Y233569I13166J-7602D01*
G01X1073566Y231009D02*
X1073582Y231037D01*
G01X1073566Y228683D02*
G02Y231009I2015J1163D01*
G01X1073586Y227143D02*
G03X1073566Y228683I-1385J752D01*
G01X1073567Y227109D02*
X1073586Y227143D01*
G01X1073542Y227067D02*
X1073567Y227109D01*
G01Y224784D02*
G02X1073542Y227067I2015J1164D01*
G01X1073586Y223243D02*
G03X1073567Y224784I-1384J754D01*
G01Y223209D02*
X1073586Y223243D01*
G01X1073542Y223167D02*
X1073567Y223209D01*
G01Y220884D02*
G02X1073542Y223167I2015J1164D01*
G01X1073586Y219343D02*
G03X1073567Y220884I-1384J754D01*
G01Y219309D02*
X1073586Y219343D01*
G01X1073542Y219267D02*
X1073567Y219309D01*
G01X1074216Y238433D02*
X1075582Y241547D01*
G01X1074977Y236191D02*
G02X1074216Y238433I604J1455D01*
G01X1076831Y234705D02*
G03X1074977Y236191I-3490J-2454D01*
G01X1076155Y232279D02*
G03X1076831Y234705I-574J1467D01*
G01X1074216Y230633D02*
G02X1076155Y232279I3267J-1884D01*
G01X1074216Y229059D02*
G02Y230633I1365J787D01*
G01X1074242Y226776D02*
G03X1074216Y229059I-2046J1118D01*
G01X1074217Y226734D02*
X1074242Y226776D01*
G01X1074198Y226700D02*
X1074217Y226734D01*
G01Y225159D02*
G02X1074198Y226700I1365J787D01*
G01X1074242Y222876D02*
G03X1074217Y225159I-2040J1119D01*
G01Y222834D02*
X1074242Y222876D01*
G01X1074198Y222800D02*
X1074217Y222834D01*
G01Y221259D02*
G02X1074198Y222800I1365J787D01*
G01X1074242Y218976D02*
G03X1074217Y221259I-2040J1119D01*
G01Y218934D02*
X1074242Y218976D01*
G01X1074198Y218900D02*
X1074217Y218934D01*
G01X1066201Y399501D02*
Y401566D01*
G01X1063250Y396550D02*
X1066201Y399501D01*
G01X1060650Y396550D02*
X1063250D01*
G01X1057700Y393600D02*
X1060650Y396550D01*
G01X1057700Y363709D02*
Y393600D01*
G01X1055200Y361209D02*
X1057700Y363709D01*
G01X1052664Y361209D02*
X1055200D01*
G01X1091605Y402642D02*
G03X1091586Y404108I-1314J716D01*
G01Y402608D02*
X1091605Y402642D01*
G01X1091586Y400282D02*
G02Y402608I2015J1163D01*
G01X1091605Y400248D02*
X1091586Y400282D01*
G01Y398707D02*
G03X1091605Y400248I-1365J787D01*
G01X1091561Y396424D02*
G02X1091586Y398707I2040J1119D01*
G01Y396382D02*
X1091561Y396424D01*
G01X1090292Y394021D02*
G03X1091586Y396382I-71J1574D01*
G01X1090136Y394021D02*
X1090292D01*
G01X1088206Y392859D02*
G02X1090136Y394021I2015J-1163D01*
G01X1086900Y392072D02*
G03X1088206Y392859I-59J1575D01*
G01X1086771Y392072D02*
X1086900D01*
G01X1084826Y390909D02*
G02X1086771Y392072I2015J-1162D01*
G01X1084813Y390886D02*
X1084826Y390909D01*
G01X1083462Y390121D02*
G03X1084813Y390886I0J1575D01*
G01X1083377Y390121D02*
X1083462D01*
G01X1081422Y386676D02*
G02X1083377Y390121I2040J1120D01*
G01X1081447Y386634D02*
X1081422Y386676D01*
G01X1081466Y386600D02*
X1081447Y386634D01*
G01Y385059D02*
G03X1081466Y386600I-1365J787D01*
G01X1081422Y382776D02*
G02X1081447Y385059I2040J1119D01*
G01Y382734D02*
X1081422Y382776D01*
G01X1081466Y382700D02*
X1081447Y382734D01*
G01Y381159D02*
G03X1081466Y382700I-1365J787D01*
G01X1081422Y378876D02*
G02X1081447Y381159I2040J1119D01*
G01Y378834D02*
X1081422Y378876D01*
G01X1081466Y378800D02*
X1081447Y378834D01*
G01Y377259D02*
G03X1081466Y378800I-1365J787D01*
G01X1081447Y374933D02*
G02Y377259I2015J1163D01*
G01Y373359D02*
G03Y374933I-1365J787D01*
G01X1081422Y373317D02*
X1081447Y373359D01*
G01Y371034D02*
G02X1081422Y373317I2015J1164D01*
G01X1081466Y371000D02*
X1081447Y371034D01*
G01Y369459D02*
G03X1081466Y371000I-1365J787D01*
G01X1081422Y367176D02*
G02X1081447Y369459I2040J1119D01*
G01Y367134D02*
X1081422Y367176D01*
G01X1081513Y367018D02*
X1081447Y367134D01*
G01X1083462Y364396D02*
X1081513Y367018D01*
G01X1045700Y390896D02*
Y392507D01*
G01X1044099Y389295D02*
X1045700Y390896D01*
G01X1044099Y386595D02*
Y389295D01*
G01X1043889Y385771D02*
G03X1044099Y386595I-1365J787D01*
G01X1043889Y383445D02*
G02Y385771I2015J1163D01*
G01Y381871D02*
G03Y383445I-1365J787D01*
G01X1043824Y381759D02*
X1043889Y381871D01*
G01X1042524Y378760D02*
X1043824Y381759D01*
G01X1059000Y400000D02*
Y401553D01*
G01X1053300Y394300D02*
X1059000Y400000D01*
G01X1051400Y394300D02*
X1053300D01*
G01X1051000Y393900D02*
X1051400Y394300D01*
G01X1051000Y392176D02*
Y393900D01*
G01X1049284Y390460D02*
X1051000Y392176D01*
G01X1093686Y383522D02*
G03X1095616Y384684I-85J2325D01*
G01X1093557Y383522D02*
X1093686D01*
G01X1092236Y381159D02*
G02X1093557Y383522I1365J788D01*
G01X1092261Y378876D02*
G03X1092236Y381159I-2040J1119D01*
G01Y378834D02*
X1092261Y378876D01*
G01X1092217Y378800D02*
X1092236Y378834D01*
G01Y377259D02*
G02X1092217Y378800I1365J787D01*
G01X1092236Y374933D02*
G03Y377259I-2015J1163D01*
G01Y373359D02*
G02Y374933I1365J787D01*
G01X1092261Y373317D02*
X1092236Y373359D01*
G01Y371034D02*
G03X1092261Y373317I-2015J1164D01*
G01X1092217Y371000D02*
X1092236Y371034D01*
G01Y369459D02*
G02X1092217Y371000I1365J787D01*
G01X1092261Y367176D02*
G03X1092236Y369459I-2040J1119D01*
G01Y367134D02*
X1092261Y367176D01*
G01X1092217Y367100D02*
X1092236Y367134D01*
G01Y365559D02*
G02X1092217Y367100I1365J787D01*
G01X1092302Y365446D02*
X1092236Y365559D01*
G01X1093601Y362447D02*
X1092302Y365446D01*
G01X1061000Y400301D02*
Y401633D01*
G01X1054600Y393901D02*
X1061000Y400301D01*
G01X1054600Y387300D02*
Y393901D01*
G01X1051909Y384609D02*
X1054600Y387300D01*
G01X1045904Y384609D02*
X1051909D01*
G01X1094966Y385059D02*
G02X1096896Y386221I2015J-1163D01*
G01X1093660Y384272D02*
G03X1094966Y385059I-59J1575D01*
G01X1093531Y384272D02*
X1093660D01*
G01X1091586Y380784D02*
G02X1093531Y384272I2015J1163D01*
G01X1091605Y379243D02*
G03X1091586Y380784I-1384J754D01*
G01Y379209D02*
X1091605Y379243D01*
G01X1091561Y379167D02*
X1091586Y379209D01*
G01Y376884D02*
G02X1091561Y379167I2015J1164D01*
G01X1091605Y375343D02*
G03X1091586Y376884I-1384J754D01*
G01Y375309D02*
X1091605Y375343D01*
G01X1091561Y373026D02*
G02X1091586Y375309I2040J1119D01*
G01Y372984D02*
X1091561Y373026D01*
G01X1091586Y371410D02*
G03Y372984I-1365J787D01*
G01Y369084D02*
G02Y371410I2015J1163D01*
G01X1091605Y367543D02*
G03X1091586Y369084I-1384J754D01*
G01Y367509D02*
X1091605Y367543D01*
G01X1091561Y367467D02*
X1091586Y367509D01*
G01Y365184D02*
G02X1091561Y367467I2015J1164D01*
G01X1091605Y363643D02*
G03X1091586Y365184I-1384J754D01*
G01Y363609D02*
X1091605Y363643D01*
G01X1091561Y363567D02*
X1091586Y363609D01*
G01Y361284D02*
G02X1091561Y363567I2015J1164D01*
G01X1091605Y359743D02*
G03X1091586Y361284I-1384J754D01*
G01Y359709D02*
X1091605Y359743D01*
G01X1091561Y359667D02*
X1091586Y359709D01*
G01Y357384D02*
G02X1091561Y359667I2015J1164D01*
G01X1091652Y357268D02*
X1091586Y357384D01*
G01X1093601Y354647D02*
X1091652Y357268D01*
G01X1064201Y401501D02*
Y402640D01*
G01X1056100Y393400D02*
X1064201Y401501D01*
G01X1056100Y365368D02*
Y393400D01*
G01X1053900Y363168D02*
X1056100Y365368D01*
G01X1051968Y363168D02*
X1053900D01*
G01X1050100Y361300D02*
X1051968Y363168D01*
G01X1050100Y360076D02*
Y361300D01*
G01X1049284Y359260D02*
X1050100Y360076D01*
G01X1047700Y387900D02*
Y391600D01*
G01X1046700Y386900D02*
G03X1047700Y387900I0J1000D01*
G01X1044761Y385780D02*
G02X1046700Y386900I1939J-1118D01*
G01X1044539Y385395D02*
X1044761Y385780D01*
G01X1044539Y383821D02*
G02Y385395I1365J787D01*
G01X1044604Y383709D02*
X1044539Y383821D01*
G01X1045904Y380709D02*
X1044604Y383709D01*
G01X1075651Y397548D02*
Y408572D01*
G01X1073392Y395221D02*
G03X1075651Y397548I-69J2327D01*
G01X1073322Y395222D02*
X1073392Y395221D01*
G01X1073278Y395222D02*
X1073322D01*
G01X1071957Y392859D02*
G02X1073278Y395222I1365J788D01*
G01X1071982Y390576D02*
G03X1071957Y392859I-2040J1119D01*
G01Y390534D02*
X1071982Y390576D01*
G01X1071938Y390500D02*
X1071957Y390534D01*
G01Y388959D02*
G02X1071938Y390500I1365J787D01*
G01X1071982Y386676D02*
G03X1071957Y388959I-2040J1119D01*
G01Y386634D02*
X1071982Y386676D01*
G01X1071938Y386600D02*
X1071957Y386634D01*
G01Y385059D02*
G02X1071938Y386600I1365J787D01*
G01X1071982Y382776D02*
G03X1071957Y385059I-2040J1119D01*
G01Y382734D02*
X1071982Y382776D01*
G01X1071938Y382700D02*
X1071957Y382734D01*
G01Y381159D02*
G02X1071938Y382700I1365J787D01*
G01X1071982Y378876D02*
G03X1071957Y381159I-2040J1119D01*
G01Y378834D02*
X1071982Y378876D01*
G01X1071938Y378800D02*
X1071957Y378834D01*
G01Y377259D02*
G02X1071938Y378800I1365J787D01*
G01X1071957Y374933D02*
G03Y377259I-2015J1163D01*
G01Y373359D02*
G02Y374933I1365J787D01*
G01X1071982Y373317D02*
X1071957Y373359D01*
G01Y371034D02*
G03X1071982Y373317I-2015J1164D01*
G01X1071858Y369666D02*
G02X1071957Y371034I1464J582D01*
G01X1072168Y369582D02*
X1071858Y369666D01*
G01X1073322Y370247D02*
X1072168Y369582D01*
G01X1040900Y391200D02*
X1043200Y393500D01*
G01X1040900Y388184D02*
Y391200D01*
G01X1042524Y386560D02*
X1040900Y388184D01*
G01X1094924Y402304D02*
G02X1094966Y404558I2057J1089D01*
G01X1094993Y402183D02*
X1094924Y402304D01*
G01X1094966Y400657D02*
G03X1094993Y402183I-1365J787D01*
G01X1094966Y398331D02*
G02Y400657I2015J1163D01*
G01Y396757D02*
G03Y398331I-1365J787D01*
G01X1094941Y396715D02*
X1094966Y396757D01*
G01Y394432D02*
G02X1094941Y396715I2015J1164D01*
G01X1093672Y392071D02*
G03X1094966Y394432I-71J1574D01*
G01X1093503Y392071D02*
X1093672D01*
G01X1091586Y390909D02*
G02X1093503Y392071I2015J-1162D01*
G01X1090265Y390121D02*
G03X1091586Y390909I-44J1575D01*
G01X1090136Y390121D02*
X1090265D01*
G01X1088206Y388959D02*
G02X1090136Y390121I2015J-1163D01*
G01X1086900Y388172D02*
G03X1088206Y388959I-59J1575D01*
G01X1086771Y388172D02*
X1086900D01*
G01X1084826Y384683D02*
G02X1086771Y388172I2015J1163D01*
G01X1084826Y383109D02*
G03Y384683I-1364J787D01*
G01X1084791Y383049D02*
X1084826Y383109D01*
G01Y380783D02*
G02X1084791Y383049I2015J1164D01*
G01X1084826Y379209D02*
G03Y380783I-1364J787D01*
G01X1084791Y379149D02*
X1084826Y379209D01*
G01Y376883D02*
G02X1084791Y379149I2015J1164D01*
G01X1084826Y375309D02*
G03Y376883I-1364J787D01*
G01X1084801Y373026D02*
G02X1084826Y375309I2040J1119D01*
G01Y372984D02*
X1084801Y373026D01*
G01X1084826Y371410D02*
G03Y372984I-1364J787D01*
G01X1084801Y371368D02*
X1084826Y371410D01*
G01X1086585Y367934D02*
G02X1084801Y371368I256J2313D01*
G01X1086841Y367678D02*
X1086585Y367934D01*
G01X1086841Y366347D02*
Y367678D01*
G01X1070980Y398499D02*
Y411038D01*
G01X1068138Y395657D02*
X1070980Y398499D01*
G01X1068138Y393647D02*
Y395657D01*
G01X1067927Y392859D02*
G03X1068138Y393647I-1363J787D01*
G01X1067902Y390576D02*
G02X1067927Y392859I2040J1119D01*
G01Y390534D02*
X1067902Y390576D01*
G01X1067946Y390500D02*
X1067927Y390534D01*
G01Y388959D02*
G03X1067946Y390500I-1365J787D01*
G01X1067902Y386676D02*
G02X1067927Y388959I2040J1119D01*
G01Y386634D02*
X1067902Y386676D01*
G01X1067946Y386600D02*
X1067927Y386634D01*
G01Y385059D02*
G03X1067946Y386600I-1365J787D01*
G01X1067902Y382776D02*
G02X1067927Y385059I2040J1119D01*
G01Y382734D02*
X1067902Y382776D01*
G01X1067946Y382700D02*
X1067927Y382734D01*
G01Y381159D02*
G03X1067946Y382700I-1365J787D01*
G01X1067902Y378876D02*
G02X1067927Y381159I2040J1119D01*
G01Y378834D02*
X1067902Y378876D01*
G01X1067946Y378800D02*
X1067927Y378834D01*
G01Y377259D02*
G03X1067946Y378800I-1365J787D01*
G01X1067927Y374933D02*
G02Y377259I2015J1163D01*
G01Y373359D02*
G03Y374933I-1365J787D01*
G01X1067902Y373317D02*
X1067927Y373359D01*
G01Y371034D02*
G02X1067902Y373317I2015J1164D01*
G01X1067927Y369460D02*
G03Y371034I-1365J787D01*
G01X1069857Y365972D02*
G02X1067927Y369460I85J2325D01*
G01X1069986Y365972D02*
X1069857D01*
G01X1071307Y363610D02*
G03X1069986Y365972I-1365J787D01*
G01X1073066Y360134D02*
G02X1071307Y363610I256J2313D01*
G01X1073322Y359878D02*
X1073066Y360134D01*
G01X1073322Y358547D02*
Y359878D01*
G01X1094966Y388959D02*
G02X1096896Y390121I2015J-1163D01*
G01X1093660Y388172D02*
G03X1094966Y388959I-59J1575D01*
G01X1093531Y388172D02*
X1093660D01*
G01X1091586Y387009D02*
G02X1093531Y388172I2015J-1162D01*
G01X1090265Y386221D02*
G03X1091586Y387009I-44J1575D01*
G01X1090136Y386221D02*
X1090265D01*
G01X1088181Y382776D02*
G02X1090136Y386221I2040J1120D01*
G01X1088206Y382734D02*
X1088181Y382776D01*
G01X1088225Y382700D02*
X1088206Y382734D01*
G01Y381159D02*
G03X1088225Y382700I-1365J787D01*
G01X1088181Y378876D02*
G02X1088206Y381159I2040J1119D01*
G01Y378834D02*
X1088181Y378876D01*
G01X1088225Y378800D02*
X1088206Y378834D01*
G01Y377259D02*
G03X1088225Y378800I-1365J787D01*
G01X1088206Y374933D02*
G02Y377259I2015J1163D01*
G01Y373359D02*
G03Y374933I-1365J787D01*
G01X1088181Y373317D02*
X1088206Y373359D01*
G01Y371034D02*
G02X1088181Y373317I2015J1164D01*
G01X1088225Y371000D02*
X1088206Y371034D01*
G01Y369459D02*
G03X1088225Y371000I-1365J787D01*
G01X1088181Y367176D02*
G02X1088206Y369459I2040J1119D01*
G01Y367134D02*
X1088181Y367176D01*
G01X1088225Y367100D02*
X1088206Y367134D01*
G01Y365559D02*
G03X1088225Y367100I-1365J787D01*
G01X1088181Y363276D02*
G02X1088206Y365559I2040J1119D01*
G01Y363234D02*
X1088181Y363276D01*
G01X1088225Y363200D02*
X1088206Y363234D01*
G01Y361659D02*
G03X1088225Y363200I-1365J787D01*
G01X1088181Y359376D02*
G02X1088206Y361659I2040J1119D01*
G01Y359334D02*
X1088181Y359376D01*
G01X1088272Y359218D02*
X1088206Y359334D01*
G01X1090221Y356596D02*
X1088272Y359218D01*
G01X1092261Y402274D02*
G03X1092236Y404559I-2040J1120D01*
G01Y402232D02*
X1092261Y402274D01*
G01X1092236Y400658D02*
G02Y402232I1365J787D01*
G01Y398332D02*
G03Y400658I-2015J1163D01*
G01X1092217Y396791D02*
G02X1092236Y398332I1384J754D01*
G01Y396757D02*
X1092217Y396791D01*
G01X1092261Y396715D02*
X1092236Y396757D01*
G01X1090306Y393270D02*
G03X1092261Y396715I-85J2325D01*
G01X1090140Y393270D02*
X1090306D01*
G01X1088856Y392484D02*
G02X1090140Y393270I1365J-788D01*
G01X1086926Y391322D02*
G03X1088856Y392484I-85J2325D01*
G01X1086841Y391322D02*
X1086926D01*
G01X1085490Y390557D02*
G02X1086841Y391322I1351J-810D01*
G01X1085477Y390534D02*
X1085490Y390557D01*
G01X1083532Y389371D02*
G03X1085477Y390534I-70J2325D01*
G01X1083403Y389371D02*
X1083532D01*
G01X1082078Y387043D02*
G02X1083403Y389371I1384J753D01*
G01X1082097Y387009D02*
X1082078Y387043D01*
G01X1082122Y386967D02*
X1082097Y387009D01*
G01Y384684D02*
G03X1082122Y386967I-2015J1164D01*
G01X1082078Y383143D02*
G02X1082097Y384684I1384J754D01*
G01Y383109D02*
X1082078Y383143D01*
G01X1082122Y383067D02*
X1082097Y383109D01*
G01Y380784D02*
G03X1082122Y383067I-2015J1164D01*
G01X1082078Y379243D02*
G02X1082097Y380784I1384J754D01*
G01Y379209D02*
X1082078Y379243D01*
G01X1082122Y379167D02*
X1082097Y379209D01*
G01Y376884D02*
G03X1082122Y379167I-2015J1164D01*
G01X1082078Y375343D02*
G02X1082097Y376884I1384J754D01*
G01Y375309D02*
G02X1082078Y375343I1184J684D01*
G01X1082122Y373026D02*
G03X1082097Y375309I-2040J1119D01*
G01Y372984D02*
X1082122Y373026D01*
G01X1082009Y372802D02*
G02X1082097Y372984I1093J-416D01*
G01X1081904Y372424D02*
G02X1082009Y372802I1558J-229D01*
G01X1082131Y372197D02*
X1081904Y372424D01*
G01X1083462Y372197D02*
X1082131D01*
G01X1037500Y389100D02*
X1042200Y393800D01*
G01X1037500Y387900D02*
Y389100D01*
G01X1039145Y386255D02*
X1037500Y387900D01*
G01X1039145Y384609D02*
Y386255D01*
G01X1074898Y397548D02*
Y408883D01*
G01X1073351Y395973D02*
G03X1074898Y397548I-28J1575D01*
G01X1073323Y395973D02*
X1073351D01*
G01X1073309Y395974D02*
X1073323Y395973D01*
G01X1071307Y392484D02*
G02X1073309Y395974I2015J1163D01*
G01X1071326Y390943D02*
G03X1071307Y392484I-1384J754D01*
G01Y390909D02*
X1071326Y390943D01*
G01X1071282Y390867D02*
X1071307Y390909D01*
G01Y388584D02*
G02X1071282Y390867I2015J1164D01*
G01X1071326Y387043D02*
G03X1071307Y388584I-1384J754D01*
G01Y387009D02*
X1071326Y387043D01*
G01X1071282Y386967D02*
X1071307Y387009D01*
G01Y384684D02*
G02X1071282Y386967I2015J1164D01*
G01X1071326Y383143D02*
G03X1071307Y384684I-1384J754D01*
G01Y383109D02*
X1071326Y383143D01*
G01X1071282Y383067D02*
X1071307Y383109D01*
G01Y380784D02*
G02X1071282Y383067I2015J1164D01*
G01X1071326Y379243D02*
G03X1071307Y380784I-1384J754D01*
G01Y379209D02*
X1071326Y379243D01*
G01X1071282Y379167D02*
X1071307Y379209D01*
G01Y376884D02*
G02X1071282Y379167I2015J1164D01*
G01X1071326Y375343D02*
G03X1071307Y376884I-1384J754D01*
G01Y375309D02*
X1071326Y375343D01*
G01X1071282Y373026D02*
G02X1071307Y375309I2040J1119D01*
G01Y372984D02*
X1071282Y373026D01*
G01X1071307Y371410D02*
G03Y372984I-1365J787D01*
G01X1071190Y369314D02*
G02X1071307Y371410I2132J932D01*
G01X1073322Y367922D02*
G02X1071190Y369314I-4J2322D01*
G01X1073366Y367922D02*
X1073322D01*
G01X1074687Y367134D02*
G03X1073366Y367922I-1365J-787D01*
G01X1074753Y367018D02*
X1074687Y367134D01*
G01X1076702Y364396D02*
X1074753Y367018D01*
G01X1093699Y391321D02*
G03X1095616Y394808I-98J2324D01*
G01X1093530Y391321D02*
X1093699D01*
G01X1092236Y390534D02*
G02X1093530Y391321I1365J-787D01*
G01X1090291Y389371D02*
G03X1092236Y390534I-70J2325D01*
G01X1090162Y389371D02*
X1090291D01*
G01X1088856Y388584D02*
G02X1090162Y389371I1365J-788D01*
G01X1086926Y387422D02*
G03X1088856Y388584I-85J2325D01*
G01X1086841Y387422D02*
X1086926D01*
G01X1085477Y385060D02*
G02X1086841Y387422I1364J787D01*
G01X1085512Y382794D02*
G03X1085477Y385060I-2050J1102D01*
G01Y382734D02*
X1085512Y382794D01*
G01X1085477Y381160D02*
G02Y382734I1364J787D01*
G01X1085512Y378894D02*
G03X1085477Y381160I-2050J1102D01*
G01Y378834D02*
X1085512Y378894D01*
G01X1085477Y377260D02*
G02Y378834I1364J787D01*
G01X1085502Y374975D02*
G03X1085477Y377260I-2040J1120D01*
G01Y374933D02*
X1085502Y374975D01*
G01X1085477Y373359D02*
G02Y374933I1364J787D01*
G01X1085502Y373317D02*
X1085477Y373359D01*
G01Y371034D02*
G03X1085502Y373317I-2017J1164D01*
G01X1086614Y368689D02*
G02X1085477Y371034I227J1558D01*
G01X1086841Y368916D02*
X1086614Y368689D01*
G01X1086841Y370247D02*
Y368916D01*
G01X1093686Y387422D02*
G03X1095616Y388584I-85J2325D01*
G01X1093557Y387422D02*
X1093686D01*
G01X1092236Y386634D02*
G02X1093557Y387422I1365J-787D01*
G01X1090291Y385471D02*
G03X1092236Y386634I-70J2325D01*
G01X1090162Y385471D02*
X1090291D01*
G01X1088837Y383143D02*
G02X1090162Y385471I1384J753D01*
G01X1088856Y383109D02*
X1088837Y383143D01*
G01X1088881Y383067D02*
X1088856Y383109D01*
G01Y380784D02*
G03X1088881Y383067I-2015J1164D01*
G01X1088837Y379243D02*
G02X1088856Y380784I1384J754D01*
G01Y379209D02*
X1088837Y379243D01*
G01X1088881Y379167D02*
X1088856Y379209D01*
G01Y376884D02*
G03X1088881Y379167I-2015J1164D01*
G01X1088837Y375343D02*
G02X1088856Y376884I1384J754D01*
G01Y375309D02*
X1088837Y375343D01*
G01X1088881Y373026D02*
G03X1088856Y375309I-2040J1119D01*
G01Y372984D02*
X1088881Y373026D01*
G01X1088856Y371410D02*
G02Y372984I1365J787D01*
G01Y369084D02*
G03Y371410I-2015J1163D01*
G01X1088837Y367543D02*
G02X1088856Y369084I1384J754D01*
G01Y367509D02*
X1088837Y367543D01*
G01X1088881Y367467D02*
X1088856Y367509D01*
G01Y365184D02*
G03X1088881Y367467I-2015J1164D01*
G01X1088837Y363643D02*
G02X1088856Y365184I1384J754D01*
G01X1088924Y363492D02*
X1088837Y363643D01*
G01X1090221Y360496D02*
X1088924Y363492D01*
G01X1071747Y398205D02*
Y408914D01*
G01X1068889Y395347D02*
X1071747Y398205D01*
G01X1068889Y393647D02*
Y395347D01*
G01X1068577Y392484D02*
G03X1068889Y393647I-2015J1164D01*
G01X1068558Y390943D02*
G02X1068577Y392484I1384J754D01*
G01Y390909D02*
X1068558Y390943D01*
G01X1068602Y390867D02*
X1068577Y390909D01*
G01Y388584D02*
G03X1068602Y390867I-2015J1164D01*
G01X1068558Y387043D02*
G02X1068577Y388584I1384J754D01*
G01Y387009D02*
X1068558Y387043D01*
G01X1068602Y386967D02*
X1068577Y387009D01*
G01Y384684D02*
G03X1068602Y386967I-2015J1164D01*
G01X1068558Y383143D02*
G02X1068577Y384684I1384J754D01*
G01Y383109D02*
X1068558Y383143D01*
G01X1068602Y383067D02*
X1068577Y383109D01*
G01Y380784D02*
G03X1068602Y383067I-2015J1164D01*
G01X1068558Y379243D02*
G02X1068577Y380784I1384J754D01*
G01Y379209D02*
X1068558Y379243D01*
G01X1068602Y379167D02*
X1068577Y379209D01*
G01Y376884D02*
G03X1068602Y379167I-2015J1164D01*
G01X1068558Y375343D02*
G02X1068577Y376884I1384J754D01*
G01Y375309D02*
X1068558Y375343D01*
G01X1068602Y373026D02*
G03X1068577Y375309I-2040J1119D01*
G01Y372984D02*
X1068602Y373026D01*
G01X1068577Y371410D02*
G02Y372984I1365J787D01*
G01Y369084D02*
G03Y371410I-2015J1163D01*
G01X1069898Y366722D02*
G02X1068577Y369084I44J1575D01*
G01X1070027Y366722D02*
X1069898D01*
G01X1073322Y366347D02*
G03X1070027Y366722I-3295J-14289D01*
G01X1090929Y405241D02*
X1089529Y406641D01*
G01X1091586Y404108D02*
X1090929Y405241D01*
G01X1077604Y412357D02*
X1078480Y413233D01*
G01X1077604Y410525D02*
Y412357D01*
G01X1075651Y408572D02*
X1077604Y410525D01*
G01X1095281Y406200D02*
X1094489Y406992D01*
G01X1094966Y404558D02*
X1095281Y405102D01*
G01X1091989Y404977D02*
Y406641D01*
G01X1092000Y404966D02*
X1091989Y404977D01*
G01X1092236Y404559D02*
X1092000Y404966D01*
G01X1076856Y412357D02*
X1075980Y413233D01*
G01X1076856Y410841D02*
Y412357D01*
G01X1074898Y408883D02*
X1076856Y410841D01*
G01X1034762Y410002D02*
Y411284D01*
G01X1071747Y408914D02*
X1073480Y410647D01*
G01X1131680Y194200D02*
X1133100D01*
G01X1127750Y198130D02*
X1131680Y194200D01*
G01X1127750Y198646D02*
Y198130D01*
G01X1127800Y198696D02*
X1127750Y198646D01*
G01X1127800Y200778D02*
Y198696D01*
G01X1125066Y203512D02*
X1127800Y200778D01*
G01X1125066Y211043D02*
Y203512D01*
G01X1124821Y211632D02*
X1125066Y211043D01*
G01X1124915Y213084D02*
G03X1124821Y211632I1423J-821D01*
G01X1124940Y215367D02*
G02X1124915Y213084I-2040J-1119D01*
G01Y215409D02*
X1124940Y215367D01*
G01X1124896Y215443D02*
X1124915Y215409D01*
G01Y216984D02*
G03X1124896Y215443I1365J-787D01*
G01X1124940Y219267D02*
G02X1124915Y216984I-2040J-1119D01*
G01X1103986Y217359D02*
G03X1104005Y218900I-1365J787D01*
G01X1103961Y215076D02*
G02X1103986Y217359I2040J1119D01*
G01Y215034D02*
X1103961Y215076D01*
G01X1104005Y215000D02*
X1103986Y215034D01*
G01Y213459D02*
G03X1104005Y215000I-1365J787D01*
G01X1103818Y213168D02*
X1103986Y213459D01*
G01X1103676Y213026D02*
X1103818Y213168D01*
G01X1103676Y210719D02*
Y213026D01*
G01X1102546Y209589D02*
X1103676Y210719D01*
G01X1102546Y187823D02*
Y209589D01*
G01X1103332Y187037D02*
X1102546Y187823D01*
G01X1103332Y186257D02*
Y187037D01*
G01X1103892Y185697D02*
X1103332Y186257D01*
G01X1144076Y205500D02*
X1145000D01*
G01X1139176Y210400D02*
X1144076Y205500D01*
G01X1139176Y211155D02*
Y210400D01*
G01X1138237Y212094D02*
X1139176Y211155D01*
G01X1138435Y213084D02*
G03X1138237Y212094I1365J-788D01*
G01X1138460Y215367D02*
G02X1138435Y213084I-2040J-1119D01*
G01Y215409D02*
X1138460Y215367D01*
G01X1138416Y215443D02*
X1138435Y215409D01*
G01Y216984D02*
G03X1138416Y215443I1365J-787D01*
G01X1138460Y219267D02*
G02X1138435Y216984I-2040J-1119D01*
G01X1114776Y217359D02*
G02X1114757Y218900I1365J787D01*
G01X1115088Y216196D02*
G03X1114776Y217359I-2327J-1D01*
G01X1115088Y214600D02*
Y216196D01*
G01X1114367Y213879D02*
X1115088Y214600D01*
G01X1114367Y202744D02*
Y213879D01*
G01X1115492Y201619D02*
X1114367Y202744D01*
G01X1115492Y193184D02*
Y201619D01*
G01X1118680Y189996D02*
X1115492Y193184D01*
G01X1118680Y187931D02*
Y189996D01*
G01X1119556Y187055D02*
X1118680Y187931D01*
G01X1140126Y202800D02*
X1142200D01*
G01X1136326Y206600D02*
X1140126Y202800D01*
G01X1136326Y207311D02*
Y206600D01*
G01X1135450Y209103D02*
G02X1136326Y207311I-1374J-1782D01*
G01X1135053Y209557D02*
G03X1135450Y209103I1347J778D01*
G01X1135055Y209558D02*
X1135053Y209557D01*
G01X1135055Y211133D02*
G03Y209558I1364J-788D01*
G01Y213459D02*
G02Y211133I-2015J-1163D01*
G01X1135036Y215000D02*
G03X1135055Y213459I1384J-754D01*
G01Y215034D02*
X1135036Y215000D01*
G01X1135080Y215076D02*
X1135055Y215034D01*
G01Y217359D02*
G02X1135080Y215076I-2015J-1164D01*
G01X1135036Y218900D02*
G03X1135055Y217359I1384J-754D01*
G01X1143300Y205215D02*
Y204500D01*
G01X1138426Y210089D02*
X1143300Y205215D01*
G01X1138426Y210780D02*
Y210089D01*
G01X1137568Y211638D02*
X1138426Y210780D01*
G01X1137785Y213459D02*
G03X1137568Y211638I2015J-1164D01*
G01X1137804Y215000D02*
G02X1137785Y213459I-1384J-754D01*
G01Y215034D02*
X1137804Y215000D01*
G01X1137760Y215076D02*
X1137785Y215034D01*
G01Y217359D02*
G03X1137760Y215076I2015J-1164D01*
G01X1137804Y218900D02*
G02X1137785Y217359I-1384J-754D01*
G01X1121536Y217360D02*
G02Y218934I1364J787D01*
G01X1121571Y215094D02*
G03X1121536Y217360I-2050J1102D01*
G01X1121504Y214978D02*
X1121571Y215094D01*
G01X1121536Y213459D02*
G02X1121504Y214978I1364J789D01*
G01X1121849Y212294D02*
G03X1121536Y213459I-2328J-1D01*
G01X1121849Y208297D02*
Y212294D01*
G01X1122048Y208098D02*
X1121849Y208297D01*
G01X1122048Y199456D02*
Y208098D01*
G01X1129952Y191552D02*
X1122048Y199456D01*
G01X1129952Y191548D02*
Y191552D01*
G01X1130750Y190750D02*
X1129952Y191548D01*
G01X1118156Y216984D02*
G03X1118181Y219267I-2015J1164D01*
G01X1117946Y216620D02*
X1118156Y216984D01*
G01X1117946Y208828D02*
Y216620D01*
G01X1118518Y208256D02*
X1117946Y208828D01*
G01X1118518Y194432D02*
Y208256D01*
G01X1123678Y189272D02*
X1118518Y194432D01*
G01X1123678Y187933D02*
Y189272D01*
G01X1124556Y187055D02*
X1123678Y187933D01*
G01X1114126Y216984D02*
G02X1114101Y219267I2015J1164D01*
G01X1114337Y216196D02*
G03X1114126Y216984I-1577J0D01*
G01X1114337Y214912D02*
Y216196D01*
G01X1113617Y214192D02*
X1114337Y214912D01*
G01X1113617Y202424D02*
Y214192D01*
G01X1114742Y201299D02*
X1113617Y202424D01*
G01X1114742Y192873D02*
Y201299D01*
G01X1117930Y189685D02*
X1114742Y192873D01*
G01X1117930Y187929D02*
Y189685D01*
G01X1117056Y187055D02*
X1117930Y187929D01*
G01X1141409Y200450D02*
X1141450D01*
G01X1135572Y206287D02*
X1141409Y200450D01*
G01X1135572Y207311D02*
Y206287D01*
G01X1134985Y208516D02*
G02X1135572Y207311I-936J-1202D01*
G01X1134405Y209183D02*
G03X1134985Y208516I1996J1150D01*
G01X1134424Y211543D02*
G03X1134405Y209183I2000J-1196D01*
G01Y213084D02*
G02X1134424Y211543I-1365J-787D01*
G01X1134380Y215367D02*
G03X1134405Y213084I2040J-1119D01*
G01Y215409D02*
X1134380Y215367D01*
G01X1134424Y215443D02*
X1134405Y215409D01*
G01Y216984D02*
G02X1134424Y215443I-1365J-787D01*
G01X1134380Y219267D02*
G03X1134405Y216984I2040J-1119D01*
G01X1101256Y217359D02*
G02X1101237Y218900I1365J787D01*
G01X1101281Y215076D02*
G03X1101256Y217359I-2040J1119D01*
G01Y215034D02*
X1101281Y215076D01*
G01X1101237Y215000D02*
X1101256Y215034D01*
G01Y213459D02*
G02X1101237Y215000I1365J787D01*
G01X1101568Y212294D02*
G03X1101256Y213459I-2327J1D01*
G01X1101568Y210658D02*
Y212294D01*
G01X1100276Y209366D02*
X1101568Y210658D01*
G01X1100276Y186593D02*
Y209366D01*
G01X1101200Y185669D02*
X1100276Y186593D01*
G01X1120885Y216983D02*
G02X1120850Y219249I2015J1164D01*
G01X1120885Y215409D02*
G03Y216983I-1364J787D01*
G01X1120843Y215336D02*
X1120885Y215409D01*
G01Y213082D02*
G02X1120843Y215336I2015J1165D01*
G01X1121096Y212294D02*
G03X1120885Y213082I-1575J0D01*
G01X1121096Y207989D02*
Y212294D01*
G01X1121298Y207787D02*
X1121096Y207989D01*
G01X1121298Y199145D02*
Y207787D01*
G01X1129200Y191243D02*
X1121298Y199145D01*
G01X1129200Y189700D02*
Y191243D01*
G01X1129400Y189500D02*
X1129200Y189700D01*
G01X1117506Y217359D02*
G03X1117525Y218900I-1365J787D01*
G01X1117196Y216821D02*
X1117506Y217359D01*
G01X1117196Y208517D02*
Y216821D01*
G01X1117768Y207945D02*
X1117196Y208517D01*
G01X1117768Y194121D02*
Y207945D01*
G01X1122928Y188961D02*
X1117768Y194121D01*
G01X1122928Y187927D02*
Y188961D01*
G01X1122056Y187055D02*
X1122928Y187927D01*
G01X1100606Y216984D02*
G02X1100581Y219267I2015J1164D01*
G01X1100625Y215443D02*
G03X1100606Y216984I-1384J754D01*
G01Y215409D02*
X1100625Y215443D01*
G01X1100581Y215367D02*
X1100606Y215409D01*
G01Y213084D02*
G02X1100581Y215367I2015J1164D01*
G01X1100817Y212294D02*
G03X1100606Y213084I-1576J2D01*
G01X1100817Y210968D02*
Y212294D01*
G01X1099526Y209677D02*
X1100817Y210968D01*
G01X1099526Y186374D02*
Y209677D01*
G01X1099000Y185848D02*
X1099526Y186374D01*
G01X1104636Y216984D02*
G03X1104661Y219267I-2015J1164D01*
G01X1104617Y215443D02*
G02X1104636Y216984I1384J754D01*
G01Y215409D02*
X1104617Y215443D01*
G01X1104661Y215367D02*
X1104636Y215409D01*
G01Y213084D02*
G03X1104661Y215367I-2015J1164D01*
G01X1104634Y213085D02*
X1104636Y213084D01*
G01X1104426Y212725D02*
X1104634Y213085D01*
G01X1104426Y210403D02*
Y212725D01*
G01X1103296Y209273D02*
X1104426Y210403D01*
G01X1103296Y188204D02*
Y209273D01*
G01X1106100Y185400D02*
X1103296Y188204D01*
G01X1123997Y211735D02*
X1124317Y210266D01*
G01X1124265Y213459D02*
G03X1123997Y211735I2093J-1208D01*
G01X1124284Y215000D02*
G02X1124265Y213459I-1384J-754D01*
G01Y215034D02*
X1124284Y215000D01*
G01X1124240Y215076D02*
X1124265Y215034D01*
G01Y217359D02*
G03X1124240Y215076I2015J-1164D01*
G01X1124284Y218900D02*
G02X1124265Y217359I-1384J-754D01*
G01X1131200Y193615D02*
Y193300D01*
G01X1127000Y197815D02*
X1131200Y193615D01*
G01X1127000Y200517D02*
Y197815D01*
G01X1124317Y203200D02*
X1127000Y200517D01*
G01X1124317Y210266D02*
Y203200D01*
G01X1124915Y219309D02*
X1124940Y219267D01*
G01X1124896Y219343D02*
X1124915Y219309D01*
G01Y220884D02*
G03X1124896Y219343I1365J-787D01*
G01X1124940Y223167D02*
G02X1124915Y220884I-2040J-1119D01*
G01Y223209D02*
X1124940Y223167D01*
G01X1124896Y223243D02*
X1124915Y223209D01*
G01Y224784D02*
G03X1124896Y223243I1365J-787D01*
G01X1124940Y227067D02*
G02X1124915Y224784I-2040J-1119D01*
G01Y227109D02*
X1124940Y227067D01*
G01X1124896Y227143D02*
X1124915Y227109D01*
G01Y228684D02*
G03X1124896Y227143I1365J-787D01*
G01X1124915Y231010D02*
G02Y228684I-2015J-1163D01*
G01Y232584D02*
G03Y231010I1365J-787D01*
G01X1124940Y232626D02*
X1124915Y232584D01*
G01Y234909D02*
G02X1124940Y232626I-2015J-1164D01*
G01X1124896Y234943D02*
X1124915Y234909D01*
G01Y236484D02*
G03X1124896Y234943I1365J-787D01*
G01X1124940Y238767D02*
G02X1124915Y236484I-2040J-1119D01*
G01Y238809D02*
X1124940Y238767D01*
G01X1124896Y238843D02*
X1124915Y238809D01*
G01Y240384D02*
G03X1124896Y238843I1365J-787D01*
G01X1124915Y242710D02*
G02Y240384I-2017J-1163D01*
G01Y244284D02*
G03Y242710I1365J-787D01*
G01X1126854Y245930D02*
G03X1124915Y244284I1328J-3530D01*
G01X1127530Y248356D02*
G02X1126854Y245930I-1250J-959D01*
G01X1125676Y249842D02*
G02X1127530Y248356I-1636J-3940D01*
G01X1124915Y252084D02*
G03X1125676Y249842I1365J-787D01*
G01X1125206Y252749D02*
X1124915Y252084D01*
G01X1126280Y255196D02*
X1125206Y252749D01*
G01X1104052Y244775D02*
X1106001Y247396D01*
G01X1103986Y244659D02*
X1104052Y244775D01*
G01X1103961Y242376D02*
G02X1103986Y244659I2040J1119D01*
G01Y242334D02*
X1103961Y242376D01*
G01X1104005Y242300D02*
X1103986Y242334D01*
G01Y240759D02*
G03X1104005Y242300I-1365J787D01*
G01X1103961Y238476D02*
G02X1103986Y240759I2040J1119D01*
G01Y238434D02*
X1103961Y238476D01*
G01X1104005Y238400D02*
X1103986Y238434D01*
G01Y236859D02*
G03X1104005Y238400I-1365J787D01*
G01X1103986Y234533D02*
G02Y236859I2015J1163D01*
G01Y232959D02*
G03Y234533I-1365J787D01*
G01X1103961Y232917D02*
X1103986Y232959D01*
G01Y230634D02*
G02X1103961Y232917I2015J1164D01*
G01X1104005Y230600D02*
X1103986Y230634D01*
G01Y229059D02*
G03X1104005Y230600I-1365J787D01*
G01X1103961Y226776D02*
G02X1103986Y229059I2040J1119D01*
G01Y226734D02*
X1103961Y226776D01*
G01X1104005Y226700D02*
X1103986Y226734D01*
G01Y225159D02*
G03X1104005Y226700I-1365J787D01*
G01X1103961Y222876D02*
G02X1103986Y225159I2040J1119D01*
G01Y222834D02*
X1103961Y222876D01*
G01X1104005Y222800D02*
X1103986Y222834D01*
G01Y221259D02*
G03X1104005Y222800I-1365J787D01*
G01X1103961Y218976D02*
G02X1103986Y221259I2040J1119D01*
G01Y218934D02*
X1103961Y218976D01*
G01X1104005Y218900D02*
X1103986Y218934D01*
G01X1138435Y219309D02*
X1138460Y219267D01*
G01X1138416Y219343D02*
X1138435Y219309D01*
G01Y220884D02*
G03X1138416Y219343I1365J-787D01*
G01X1138460Y223167D02*
G02X1138435Y220884I-2040J-1119D01*
G01Y223209D02*
X1138460Y223167D01*
G01X1138416Y223243D02*
X1138435Y223209D01*
G01Y224784D02*
G03X1138416Y223243I1365J-787D01*
G01X1138460Y227067D02*
G02X1138435Y224784I-2040J-1119D01*
G01Y227109D02*
X1138460Y227067D01*
G01X1138416Y227143D02*
X1138435Y227109D01*
G01Y228684D02*
G03X1138416Y227143I1365J-787D01*
G01X1138435Y231010D02*
G02Y228684I-2015J-1163D01*
G01Y232584D02*
G03Y231010I1365J-787D01*
G01X1138460Y232626D02*
X1138435Y232584D01*
G01Y234909D02*
G02X1138460Y232626I-2015J-1164D01*
G01X1138416Y234943D02*
X1138435Y234909D01*
G01Y236484D02*
G03X1138416Y234943I1365J-787D01*
G01X1138460Y238767D02*
G02X1138435Y236484I-2040J-1119D01*
G01Y238809D02*
X1138460Y238767D01*
G01X1138443Y240172D02*
G03X1138435Y238809I1199J-689D01*
G01X1138478Y240233D02*
X1138443Y240172D01*
G01X1138551Y242781D02*
G02X1138478Y240233I-2423J-1206D01*
G01X1138400Y243085D02*
X1138551Y242781D01*
G01X1138435Y244227D02*
G03X1138400Y243085I1048J-604D01*
G01X1138476Y244298D02*
X1138435Y244227D01*
G01X1138476Y246618D02*
G02Y244298I-2010J-1160D01*
G01X1138448Y246665D02*
X1138476Y246618D01*
G01X1138435Y248127D02*
G03X1138448Y246665I1249J-720D01*
G01X1138253Y250723D02*
G02X1138435Y248127I-1833J-1433D01*
G01X1137995Y250981D02*
X1138253Y250723D01*
G01X1137565Y251600D02*
X1137995Y250981D01*
G01X1136420Y253247D02*
X1137565Y251600D01*
G01X1114126Y252084D02*
G02X1114313Y251027I-1365J-787D01*
G01X1112761Y255196D02*
X1114126Y252084D01*
G01X1114776Y248560D02*
G02X1114313Y251027I3278J1892D01*
G01X1114776Y246234D02*
G03Y248560I-2015J1163D01*
G01Y244660D02*
G02Y246234I1365J787D01*
G01Y242334D02*
G03Y244660I-2015J1163D01*
G01X1114757Y240794D02*
G02X1114776Y242334I1382J753D01*
G01Y240760D02*
X1114757Y240794D01*
G01X1114801Y240718D02*
X1114776Y240760D01*
G01Y238435D02*
G03X1114801Y240718I-2015J1164D01*
G01X1114757Y236894D02*
G02X1114776Y238435I1384J754D01*
G01Y236860D02*
X1114757Y236894D01*
G01X1114801Y236818D02*
X1114776Y236860D01*
G01Y234535D02*
G03X1114801Y236818I-2015J1164D01*
G01X1114757Y232994D02*
G02X1114776Y234535I1384J754D01*
G01Y232960D02*
X1114757Y232994D01*
G01X1114801Y232918D02*
X1114776Y232960D01*
G01Y230635D02*
G03X1114801Y232918I-2015J1164D01*
G01X1114757Y229094D02*
G02X1114776Y230635I1384J754D01*
G01Y229060D02*
X1114757Y229094D01*
G01X1114801Y229018D02*
X1114776Y229060D01*
G01Y226735D02*
G03X1114801Y229018I-2015J1164D01*
G01X1114776Y225159D02*
G02Y226735I1365J788D01*
G01Y222833D02*
G03Y225159I-2015J1163D01*
G01Y221257D02*
G02Y222833I1365J788D01*
G01Y218931D02*
G03Y221257I-2015J1163D01*
G01X1114757Y218900D02*
G03X1114776Y218931I-578J375D01*
G01X1135055Y218934D02*
X1135036Y218900D01*
G01X1135080Y218976D02*
X1135055Y218934D01*
G01Y221259D02*
G02X1135080Y218976I-2015J-1164D01*
G01X1135036Y222800D02*
G03X1135055Y221259I1384J-754D01*
G01Y222834D02*
X1135036Y222800D01*
G01X1135080Y222876D02*
X1135055Y222834D01*
G01Y225159D02*
G02X1135080Y222876I-2015J-1164D01*
G01X1135036Y226700D02*
G03X1135055Y225159I1384J-754D01*
G01Y226734D02*
X1135036Y226700D01*
G01X1135080Y226776D02*
X1135055Y226734D01*
G01Y229059D02*
G02X1135080Y226776I-2015J-1164D01*
G01X1135036Y230600D02*
G03X1135055Y229059I1384J-754D01*
G01Y230634D02*
X1135036Y230600D01*
G01X1135080Y232917D02*
G02X1135055Y230634I-2040J-1119D01*
G01Y232959D02*
X1135080Y232917D01*
G01X1135055Y234533D02*
G03Y232959I1365J-787D01*
G01Y236859D02*
G02Y234533I-2015J-1163D01*
G01X1135036Y238400D02*
G03X1135055Y236859I1384J-754D01*
G01Y238434D02*
X1135036Y238400D01*
G01X1135080Y238476D02*
X1135055Y238434D01*
G01Y240759D02*
G02X1135080Y238476I-2015J-1164D01*
G01X1135055Y242334D02*
G03Y240759I1364J-787D01*
G01Y244660D02*
G02Y242334I-2015J-1163D01*
G01Y246234D02*
G03Y244660I1365J-787D01*
G01Y248560D02*
G02Y246234I-2015J-1163D01*
G01X1134592Y251027D02*
G03X1135055Y248560I3741J-575D01*
G01X1134405Y252084D02*
G02X1134592Y251027I-1365J-787D01*
G01X1133040Y255196D02*
X1134405Y252084D01*
G01X1137785Y218934D02*
X1137804Y218900D01*
G01X1137760Y218976D02*
X1137785Y218934D01*
G01Y221259D02*
G03X1137760Y218976I2015J-1164D01*
G01X1137804Y222800D02*
G02X1137785Y221259I-1384J-754D01*
G01Y222834D02*
X1137804Y222800D01*
G01X1137760Y222876D02*
X1137785Y222834D01*
G01Y225159D02*
G03X1137760Y222876I2015J-1164D01*
G01X1137804Y226700D02*
G02X1137785Y225159I-1384J-754D01*
G01Y226734D02*
X1137804Y226700D01*
G01X1137760Y226776D02*
X1137785Y226734D01*
G01Y229059D02*
G03X1137760Y226776I2015J-1164D01*
G01X1137804Y230600D02*
G02X1137785Y229059I-1384J-754D01*
G01Y230634D02*
X1137804Y230600D01*
G01X1137760Y232917D02*
G03X1137785Y230634I2040J-1119D01*
G01Y232959D02*
X1137760Y232917D01*
G01X1137785Y234533D02*
G02Y232959I-1365J-787D01*
G01Y236859D02*
G03Y234533I2015J-1163D01*
G01X1137804Y238400D02*
G02X1137785Y236859I-1384J-754D01*
G01Y238434D02*
X1137804Y238400D01*
G01X1137760Y238476D02*
X1137785Y238434D01*
G01X1137857Y240739D02*
G03X1137760Y238476I1818J-1211D01*
G01X1137877Y240768D02*
X1137857Y240739D01*
G01X1137876Y242230D02*
G02X1137877Y240768I-1268J-732D01*
G01X1137785Y242388D02*
X1137876Y242230D01*
G01X1137785Y244603D02*
G03Y242388I1919J-1108D01*
G01X1137970Y245844D02*
G02X1137785Y244603I-1667J-386D01*
G01Y246234D02*
G02X1137970Y245844I-799J-618D01*
G01X1137760Y246276D02*
X1137785Y246234D01*
G01X1137668Y248329D02*
G03X1137760Y246276I2131J-933D01*
G01X1137574Y248681D02*
X1137668Y248329D01*
G01X1136420Y249347D02*
X1137574Y248681D01*
G01X1123558Y251600D02*
X1122900Y253247D01*
G01X1124011Y250465D02*
X1123558Y251600D01*
G01X1123838Y248081D02*
G03X1124011Y250465I-938J1266D01*
G01X1123750Y247995D02*
X1123838Y248081D01*
G01X1122365Y247116D02*
X1123750Y247995D01*
G01X1121549Y246257D02*
G02X1122365Y247116I2122J-1199D01*
G01X1121536Y246234D02*
X1121549Y246257D01*
G01X1121536Y244660D02*
G02Y246234I1364J787D01*
G01Y242334D02*
G03Y244660I-2015J1163D01*
G01Y240760D02*
G02Y242334I1364J787D01*
G01X1121571Y238494D02*
G03X1121536Y240760I-2050J1102D01*
G01Y238434D02*
X1121571Y238494D01*
G01X1121536Y236860D02*
G02Y238434I1364J787D01*
G01X1121561Y234575D02*
G03X1121536Y236860I-2040J1120D01*
G01Y234533D02*
X1121561Y234575D01*
G01X1121536Y232959D02*
G02Y234533I1364J787D01*
G01X1121561Y232917D02*
X1121536Y232959D01*
G01Y230634D02*
G03X1121561Y232917I-2015J1164D01*
G01X1121536Y229060D02*
G02Y230634I1364J787D01*
G01X1121571Y226794D02*
G03X1121536Y229060I-2050J1102D01*
G01Y226734D02*
X1121571Y226794D01*
G01X1121536Y225160D02*
G02Y226734I1364J787D01*
G01X1121571Y222894D02*
G03X1121536Y225160I-2050J1102D01*
G01Y222834D02*
X1121571Y222894D01*
G01X1121536Y221260D02*
G02Y222834I1364J787D01*
G01X1121571Y218994D02*
G03X1121536Y221260I-2050J1102D01*
G01Y218934D02*
X1121571Y218994D01*
G01X1117039Y252039D02*
X1116141Y253247D01*
G01X1118034Y250700D02*
X1117039Y252039D01*
G01X1118156Y248184D02*
G03X1118034Y250700I-2015J1163D01*
G01X1118137Y246643D02*
G02X1118156Y248184I1384J754D01*
G01Y246609D02*
X1118137Y246643D01*
G01X1118181Y246567D02*
X1118156Y246609D01*
G01Y244284D02*
G03X1118181Y246567I-2015J1164D01*
G01X1118137Y242743D02*
G02X1118156Y244284I1384J754D01*
G01Y242709D02*
X1118137Y242743D01*
G01X1118181Y242667D02*
X1118156Y242709D01*
G01Y240384D02*
G03X1118181Y242667I-2015J1164D01*
G01X1118137Y238843D02*
G02X1118156Y240384I1384J754D01*
G01Y238809D02*
X1118137Y238843D01*
G01X1118181Y238767D02*
X1118156Y238809D01*
G01Y236484D02*
G03X1118181Y238767I-2015J1164D01*
G01X1118137Y234943D02*
G02X1118156Y236484I1384J754D01*
G01Y234909D02*
X1118137Y234943D01*
G01X1118181Y232626D02*
G03X1118156Y234909I-2040J1119D01*
G01Y232584D02*
X1118181Y232626D01*
G01X1118156Y231010D02*
G02Y232584I1365J787D01*
G01Y228684D02*
G03Y231010I-2015J1163D01*
G01X1118137Y227143D02*
G02X1118156Y228684I1384J754D01*
G01Y227109D02*
X1118137Y227143D01*
G01X1118181Y227067D02*
X1118156Y227109D01*
G01Y224784D02*
G03X1118181Y227067I-2015J1164D01*
G01X1118137Y223243D02*
G02X1118156Y224784I1384J754D01*
G01Y223209D02*
X1118137Y223243D01*
G01X1118181Y223167D02*
X1118156Y223209D01*
G01Y220884D02*
G03X1118181Y223167I-2015J1164D01*
G01X1118137Y219343D02*
G02X1118156Y220884I1384J754D01*
G01Y219309D02*
X1118137Y219343D01*
G01X1118181Y219267D02*
X1118156Y219309D01*
G01X1113915Y246731D02*
X1112761Y247396D01*
G01X1114009Y246380D02*
X1113915Y246731D01*
G01X1114126Y244284D02*
G02X1114009Y246380I2015J1164D01*
G01X1114126Y242710D02*
G03Y244284I-1365J787D01*
G01X1114101Y240427D02*
G02X1114126Y242710I2043J1119D01*
G01Y240385D02*
X1114101Y240427D01*
G01X1114145Y240351D02*
X1114126Y240385D01*
G01Y238810D02*
G03X1114145Y240351I-1365J787D01*
G01X1114101Y236527D02*
G02X1114126Y238810I2040J1119D01*
G01Y236485D02*
X1114101Y236527D01*
G01X1114145Y236451D02*
X1114126Y236485D01*
G01Y234910D02*
G03X1114145Y236451I-1365J787D01*
G01X1114101Y232627D02*
G02X1114126Y234910I2040J1119D01*
G01Y232585D02*
X1114101Y232627D01*
G01X1114145Y232551D02*
X1114126Y232585D01*
G01Y231010D02*
G03X1114145Y232551I-1365J787D01*
G01X1114101Y228727D02*
G02X1114126Y231010I2040J1119D01*
G01Y228685D02*
X1114101Y228727D01*
G01X1114145Y228651D02*
X1114126Y228685D01*
G01Y227110D02*
G03X1114145Y228651I-1365J787D01*
G01X1114126Y224784D02*
G02Y227110I2015J1163D01*
G01Y223208D02*
G03Y224784I-1365J788D01*
G01Y220882D02*
G02Y223208I2015J1163D01*
G01Y219306D02*
G03Y220882I-1365J788D01*
G01X1114101Y219267D02*
G02X1114126Y219306I297J-163D01*
G01X1155805Y268059D02*
G02X1157735Y269221I2015J-1163D01*
G01X1155823Y265699D02*
G02X1155805Y268059I2000J1195D01*
G01X1154440Y263372D02*
G03X1155804Y264160I0J1575D01*
G01X1154370Y263372D02*
X1154440D01*
G01X1152566Y262426D02*
G02X1154370Y263372I1873J-1379D01*
G01X1152214Y262331D02*
X1152566Y262426D01*
G01X1151060Y262996D02*
X1152214Y262331D01*
G01X1153600Y251296D02*
X1157820D01*
G01X1153376Y251072D02*
X1153600Y251296D01*
G01X1153100Y250176D02*
G03X1153376Y251072I-2040J1119D01*
G01X1153075Y250134D02*
X1153100Y250176D01*
G01X1153056Y250100D02*
X1153075Y250134D01*
G01Y248559D02*
G02X1153056Y250100I1365J787D01*
G01X1153100Y246276D02*
G03X1153075Y248559I-2040J1119D01*
G01Y246234D02*
X1153100Y246276D01*
G01X1153056Y246200D02*
X1153075Y246234D01*
G01X1154381Y243872D02*
G02X1153056Y246200I59J1575D01*
G01X1154510Y243872D02*
X1154381D01*
G01X1156455Y240384D02*
G03X1154510Y243872I-2015J1163D01*
G01X1156436Y238843D02*
G02X1156455Y240384I1384J754D01*
G01Y238809D02*
X1156436Y238843D01*
G01X1156480Y238767D02*
X1156455Y238809D01*
G01Y236484D02*
G03X1156480Y238767I-2015J1164D01*
G01X1156436Y234943D02*
G02X1156455Y236484I1384J754D01*
G01Y234909D02*
X1156436Y234943D01*
G01X1156480Y232626D02*
G03X1156455Y234909I-2040J1119D01*
G01Y232584D02*
X1156480Y232626D01*
G01X1157776Y230222D02*
G02X1156455Y232584I44J1575D01*
G01X1134405Y219309D02*
X1134380Y219267D01*
G01X1134424Y219343D02*
X1134405Y219309D01*
G01Y220884D02*
G02X1134424Y219343I-1365J-787D01*
G01X1134380Y223167D02*
G03X1134405Y220884I2040J-1119D01*
G01Y223209D02*
X1134380Y223167D01*
G01X1134424Y223243D02*
X1134405Y223209D01*
G01Y224784D02*
G02X1134424Y223243I-1365J-787D01*
G01X1134380Y227067D02*
G03X1134405Y224784I2040J-1119D01*
G01Y227109D02*
X1134380Y227067D01*
G01X1134424Y227143D02*
X1134405Y227109D01*
G01Y228684D02*
G02X1134424Y227143I-1365J-787D01*
G01X1134405Y231010D02*
G03Y228684I2015J-1163D01*
G01Y232584D02*
G02Y231010I-1365J-787D01*
G01X1134380Y232626D02*
X1134405Y232584D01*
G01Y234909D02*
G03X1134380Y232626I2015J-1164D01*
G01X1134424Y234943D02*
X1134405Y234909D01*
G01Y236484D02*
G02X1134424Y234943I-1365J-787D01*
G01X1134380Y238767D02*
G03X1134405Y236484I2040J-1119D01*
G01Y238809D02*
X1134380Y238767D01*
G01X1134424Y238843D02*
X1134405Y238809D01*
G01Y240384D02*
G02X1134424Y238843I-1365J-787D01*
G01X1134405Y242710D02*
G03Y240384I2017J-1163D01*
G01Y244284D02*
G02Y242710I-1365J-787D01*
G01X1134288Y246380D02*
G03X1134405Y244284I2132J-932D01*
G01X1134194Y246731D02*
X1134288Y246380D01*
G01X1133040Y247396D02*
X1134194Y246731D01*
G01X1113853Y264947D02*
X1109381D01*
G01X1116183Y262617D02*
X1113853Y264947D01*
G01X1117083Y262617D02*
X1116183D01*
G01X1118600Y261100D02*
X1117083Y262617D01*
G01X1120626Y261100D02*
X1118600D01*
G01X1122526Y259200D02*
X1120626Y261100D01*
G01X1123700Y259200D02*
X1122526D01*
G01X1125200Y260700D02*
X1123700Y259200D01*
G01X1127500Y260700D02*
X1125200D01*
G01X1129200Y259000D02*
X1127500Y260700D01*
G01X1130300Y259000D02*
X1129200D01*
G01X1132100Y260800D02*
X1130300Y259000D01*
G01X1134446Y260800D02*
X1132100D01*
G01X1135846Y259400D02*
X1134446Y260800D01*
G01X1139200Y259400D02*
X1135846D01*
G01X1140800Y261000D02*
X1139200Y259400D01*
G01X1145400Y261000D02*
X1140800D01*
G01X1147600Y258800D02*
X1145400Y261000D01*
G01X1148500Y258800D02*
X1147600D01*
G01X1150366Y260666D02*
X1148500Y258800D01*
G01X1151834Y260666D02*
X1150366D01*
G01X1153500Y259000D02*
X1151834Y260666D01*
G01X1155340Y259000D02*
X1153500D01*
G01X1158940Y255400D02*
X1155340Y259000D01*
G01X1103986Y248559D02*
X1103774Y248192D01*
G01X1104005Y250100D02*
G02X1103986Y248559I-1384J-754D01*
G01X1103918Y250251D02*
X1104005Y250100D01*
G01X1103853Y250400D02*
X1103918Y250251D01*
G01X1103334Y251600D02*
X1103853Y250400D01*
G01X1102621Y253247D02*
X1103334Y251600D01*
G01X1102023Y246905D02*
X1103774Y248192D01*
G01X1101256Y244659D02*
G02X1102023Y246905I1365J788D01*
G01X1101281Y242376D02*
G03X1101256Y244659I-2040J1119D01*
G01Y242334D02*
X1101281Y242376D01*
G01X1101237Y242300D02*
X1101256Y242334D01*
G01Y240759D02*
G02X1101237Y242300I1365J787D01*
G01X1101281Y238476D02*
G03X1101256Y240759I-2040J1119D01*
G01Y238434D02*
X1101281Y238476D01*
G01X1101237Y238400D02*
X1101256Y238434D01*
G01Y236859D02*
G02X1101237Y238400I1365J787D01*
G01X1101256Y234533D02*
G03Y236859I-2015J1163D01*
G01Y232959D02*
G02Y234533I1365J787D01*
G01X1101281Y232917D02*
X1101256Y232959D01*
G01Y230634D02*
G03X1101281Y232917I-2015J1164D01*
G01X1101237Y230600D02*
X1101256Y230634D01*
G01Y229059D02*
G02X1101237Y230600I1365J787D01*
G01X1101281Y226776D02*
G03X1101256Y229059I-2040J1119D01*
G01Y226734D02*
X1101281Y226776D01*
G01X1101237Y226700D02*
X1101256Y226734D01*
G01Y225159D02*
G02X1101237Y226700I1365J787D01*
G01X1101281Y222876D02*
G03X1101256Y225159I-2040J1119D01*
G01Y222834D02*
X1101281Y222876D01*
G01X1101237Y222800D02*
X1101256Y222834D01*
G01Y221259D02*
G02X1101237Y222800I1365J787D01*
G01X1101281Y218976D02*
G03X1101256Y221259I-2040J1119D01*
G01Y218934D02*
X1101281Y218976D01*
G01X1101237Y218900D02*
X1101256Y218934D01*
G01X1156455Y267684D02*
G02X1157761Y268471I1365J-788D01*
G01X1156481Y266068D02*
G02X1156455Y267684I1336J830D01*
G01X1154440Y262622D02*
G03X1156456Y263783I0J2331D01*
G01X1154396Y262622D02*
X1154440D01*
G01X1153203Y262022D02*
G02X1154396Y262622I1238J-975D01*
G01X1153286Y261712D02*
X1153203Y262022D01*
G01X1154440Y261047D02*
X1153286Y261712D01*
G01X1154440Y255816D02*
Y257147D01*
G01X1154183Y255559D02*
X1154440Y255816D01*
G01X1152425Y254409D02*
G02X1154183Y255559I2015J-1162D01*
G01X1152400Y254367D02*
X1152425Y254409D01*
G01Y252084D02*
G02X1152400Y254367I2015J1164D01*
G01X1152444Y250543D02*
G03X1152425Y252084I-1384J754D01*
G01Y250509D02*
X1152444Y250543D01*
G01X1152400Y250467D02*
X1152425Y250509D01*
G01Y248184D02*
G02X1152400Y250467I2015J1164D01*
G01X1152444Y246643D02*
G03X1152425Y248184I-1384J754D01*
G01Y246609D02*
X1152444Y246643D01*
G01X1152400Y246567D02*
X1152425Y246609D01*
G01Y244284D02*
G02X1152400Y246567I2015J1164D01*
G01X1154355Y243122D02*
G02X1152425Y244284I85J2325D01*
G01X1154484Y243122D02*
X1154355D01*
G01X1155805Y242334D02*
G03X1154484Y243122I-1365J-787D01*
G01X1155824Y242300D02*
X1155805Y242334D01*
G01Y240759D02*
G03X1155824Y242300I-1365J787D01*
G01X1155780Y238476D02*
G02X1155805Y240759I2040J1119D01*
G01Y238434D02*
X1155780Y238476D01*
G01X1155824Y238400D02*
X1155805Y238434D01*
G01Y236859D02*
G03X1155824Y238400I-1365J787D01*
G01X1155805Y234533D02*
G02Y236859I2015J1163D01*
G01Y232959D02*
G03Y234533I-1365J787D01*
G01X1155780Y232917D02*
X1155805Y232959D01*
G01Y230634D02*
G02X1155780Y232917I2015J1164D01*
G01X1157769Y229471D02*
G02X1155805Y230634I51J2326D01*
G01X1122669Y249098D02*
X1122900Y249347D01*
G01X1120901Y246638D02*
G02X1122669Y249098I13168J-7599D01*
G01X1120885Y246610D02*
X1120901Y246638D01*
G01X1120885Y244284D02*
G02Y246610I2015J1163D01*
G01Y242710D02*
G03Y244284I-1364J787D01*
G01Y240383D02*
G02Y242710I2017J1164D01*
G01Y238809D02*
G03Y240383I-1364J787D01*
G01X1120850Y238749D02*
X1120885Y238809D01*
G01Y236483D02*
G02X1120850Y238749I2015J1164D01*
G01X1120885Y234909D02*
G03Y236483I-1364J787D01*
G01X1120860Y232626D02*
G02X1120885Y234909I2040J1119D01*
G01Y232584D02*
X1120860Y232626D01*
G01X1120885Y231010D02*
G03Y232584I-1364J787D01*
G01X1120860Y230968D02*
X1120885Y231010D01*
G01Y228683D02*
G02X1120860Y230968I2015J1165D01*
G01X1120885Y227109D02*
G03Y228683I-1364J787D01*
G01X1120850Y227049D02*
X1120885Y227109D01*
G01Y224783D02*
G02X1120850Y227049I2015J1164D01*
G01X1120885Y223209D02*
G03Y224783I-1364J787D01*
G01X1120850Y223149D02*
X1120885Y223209D01*
G01Y220883D02*
G02X1120850Y223149I2015J1164D01*
G01X1120885Y219309D02*
G03Y220883I-1364J787D01*
G01X1120850Y219249D02*
X1120885Y219309D01*
G01X1117295Y248681D02*
X1116141Y249347D01*
G01X1117389Y248329D02*
X1117295Y248681D01*
G01X1117481Y246276D02*
G02X1117389Y248329I2039J1120D01*
G01X1117506Y246234D02*
X1117481Y246276D01*
G01X1117525Y246200D02*
G03X1117506Y246234I-632J-331D01*
G01Y244659D02*
G03X1117525Y246200I-1365J787D01*
G01X1117481Y242376D02*
G02X1117506Y244659I2040J1119D01*
G01Y242334D02*
X1117481Y242376D01*
G01X1117525Y242300D02*
X1117506Y242334D01*
G01Y240759D02*
G03X1117525Y242300I-1365J787D01*
G01X1117481Y238476D02*
G02X1117506Y240759I2040J1119D01*
G01Y238434D02*
X1117481Y238476D01*
G01X1117525Y238400D02*
X1117506Y238434D01*
G01Y236859D02*
G03X1117525Y238400I-1365J787D01*
G01X1117506Y234533D02*
G02Y236859I2015J1163D01*
G01Y232959D02*
G03Y234533I-1365J787D01*
G01X1117481Y232917D02*
X1117506Y232959D01*
G01Y230634D02*
G02X1117481Y232917I2015J1164D01*
G01X1117525Y230600D02*
X1117506Y230634D01*
G01Y229059D02*
G03X1117525Y230600I-1365J787D01*
G01X1117481Y226776D02*
G02X1117506Y229059I2040J1119D01*
G01Y226734D02*
X1117481Y226776D01*
G01X1117525Y226700D02*
X1117506Y226734D01*
G01Y225159D02*
G03X1117525Y226700I-1365J787D01*
G01X1117481Y222876D02*
G02X1117506Y225159I2040J1119D01*
G01Y222834D02*
X1117481Y222876D01*
G01X1117525Y222800D02*
X1117506Y222834D01*
G01Y221259D02*
G03X1117525Y222800I-1365J787D01*
G01X1117481Y218976D02*
G02X1117506Y221259I2040J1119D01*
G01Y218934D02*
X1117481Y218976D01*
G01X1117525Y218900D02*
X1117506Y218934D01*
G01X1146526Y265612D02*
X1147680Y264947D01*
G01X1146443Y265922D02*
X1146526Y265612D01*
G01X1147636Y266522D02*
G03X1146443Y265922I45J-1575D01*
G01X1147765Y266522D02*
X1147636D01*
G01X1149720Y269967D02*
G02X1147765Y266522I-2040J-1120D01*
G01X1149695Y270009D02*
X1149720Y269967D01*
G01X1149676Y270043D02*
X1149695Y270009D01*
G01X1151001Y272371D02*
G03X1149676Y270043I59J-1575D01*
G01X1151130Y272371D02*
X1151001D01*
G01X1153075Y273534D02*
G02X1151130Y272371I-2015J1162D01*
G01X1154169Y274299D02*
G03X1153075Y273534I271J-1552D01*
G01X1154510Y274322D02*
G03X1154169Y274299I138J-4587D01*
G01X1156455Y275485D02*
G02X1154510Y274322I-2015J1162D01*
G01X1159185Y275483D02*
G03X1156455Y275485I-1366J-788D01*
G01X1147373Y264640D02*
X1147680Y264947D01*
G01X1145981Y264640D02*
X1147373D01*
G01X1145294Y265327D02*
X1145981Y264640D01*
G01X1143650Y265327D02*
X1145294D01*
G01X1143613Y265364D02*
X1143650Y265327D01*
G01X1143605Y265364D02*
X1143613D01*
G01X1143349Y265620D02*
X1143605Y265364D01*
G01X1101014Y247128D02*
X1102621Y249347D01*
G01X1100606Y246609D02*
G02X1101014Y247128I2014J-1163D01*
G01X1100581Y246567D02*
X1100606Y246609D01*
G01Y244284D02*
G02X1100581Y246567I2015J1164D01*
G01X1100625Y242743D02*
G03X1100606Y244284I-1384J754D01*
G01Y242709D02*
X1100625Y242743D01*
G01X1100581Y242667D02*
X1100606Y242709D01*
G01Y240384D02*
G02X1100581Y242667I2015J1164D01*
G01X1100625Y238843D02*
G03X1100606Y240384I-1384J754D01*
G01Y238809D02*
X1100625Y238843D01*
G01X1100581Y238767D02*
X1100606Y238809D01*
G01Y236484D02*
G02X1100581Y238767I2015J1164D01*
G01X1100625Y234943D02*
G03X1100606Y236484I-1384J754D01*
G01Y234909D02*
X1100625Y234943D01*
G01X1100581Y232626D02*
G02X1100606Y234909I2040J1119D01*
G01Y232584D02*
X1100581Y232626D01*
G01X1100606Y231010D02*
G03Y232584I-1365J787D01*
G01Y228684D02*
G02Y231010I2015J1163D01*
G01X1100625Y227143D02*
G03X1100606Y228684I-1384J754D01*
G01Y227109D02*
X1100625Y227143D01*
G01X1100581Y227067D02*
X1100606Y227109D01*
G01Y224784D02*
G02X1100581Y227067I2015J1164D01*
G01X1100625Y223243D02*
G03X1100606Y224784I-1384J754D01*
G01Y223209D02*
X1100625Y223243D01*
G01X1100581Y223167D02*
X1100606Y223209D01*
G01Y220884D02*
G02X1100581Y223167I2015J1164D01*
G01X1100625Y219343D02*
G03X1100606Y220884I-1384J754D01*
G01Y219309D02*
X1100625Y219343D01*
G01X1100581Y219267D02*
X1100606Y219309D01*
G01X1155627Y246619D02*
G03X1154440Y249347I-20075J-7113D01*
G01X1157750Y245071D02*
G02X1155627Y246619I70J2325D01*
G01X1104702Y252197D02*
X1106001Y255196D01*
G01X1104636Y252084D02*
X1104702Y252197D01*
G01X1104617Y250543D02*
G02X1104636Y252084I1384J754D01*
G01Y250509D02*
X1104617Y250543D01*
G01X1105271Y249899D02*
G02X1104636Y250509I731J1396D01*
G01X1106820Y248819D02*
X1105271Y249899D01*
G01X1107243Y248397D02*
X1106820Y248819D01*
G01X1107366Y248184D02*
X1107243Y248397D01*
G01X1107385Y246643D02*
G03X1107366Y248184I-1384J754D01*
G01X1107204Y246328D02*
X1107385Y246643D01*
G01X1106426Y245640D02*
X1107204Y246328D01*
G01X1105362Y244937D02*
X1106426Y245640D01*
G01X1104617Y242743D02*
G02X1105362Y244937I1384J753D01*
G01X1104636Y242709D02*
X1104617Y242743D01*
G01X1104661Y242667D02*
X1104636Y242709D01*
G01Y240384D02*
G03X1104661Y242667I-2015J1164D01*
G01X1104617Y238843D02*
G02X1104636Y240384I1384J754D01*
G01Y238809D02*
X1104617Y238843D01*
G01X1104661Y238767D02*
X1104636Y238809D01*
G01Y236484D02*
G03X1104661Y238767I-2015J1164D01*
G01X1104617Y234943D02*
G02X1104636Y236484I1384J754D01*
G01Y234909D02*
X1104617Y234943D01*
G01X1104661Y232626D02*
G03X1104636Y234909I-2040J1119D01*
G01Y232584D02*
X1104661Y232626D01*
G01X1104636Y231010D02*
G02Y232584I1365J787D01*
G01Y228684D02*
G03Y231010I-2015J1163D01*
G01X1104617Y227143D02*
G02X1104636Y228684I1384J754D01*
G01Y227109D02*
X1104617Y227143D01*
G01X1104661Y227067D02*
X1104636Y227109D01*
G01Y224784D02*
G03X1104661Y227067I-2015J1164D01*
G01X1104617Y223243D02*
G02X1104636Y224784I1384J754D01*
G01Y223209D02*
X1104617Y223243D01*
G01X1104661Y223167D02*
X1104636Y223209D01*
G01Y220884D02*
G03X1104661Y223167I-2015J1164D01*
G01X1104617Y219343D02*
G02X1104636Y220884I1384J754D01*
G01Y219309D02*
X1104617Y219343D01*
G01X1104661Y219267D02*
X1104636Y219309D01*
G01X1124265Y218934D02*
X1124284Y218900D01*
G01X1124240Y218976D02*
X1124265Y218934D01*
G01Y221259D02*
G03X1124240Y218976I2015J-1164D01*
G01X1124284Y222800D02*
G02X1124265Y221259I-1384J-754D01*
G01Y222834D02*
X1124284Y222800D01*
G01X1124240Y222876D02*
X1124265Y222834D01*
G01Y225159D02*
G03X1124240Y222876I2015J-1164D01*
G01X1124284Y226700D02*
G02X1124265Y225159I-1384J-754D01*
G01Y226734D02*
X1124284Y226700D01*
G01X1124240Y226776D02*
X1124265Y226734D01*
G01Y229059D02*
G03X1124240Y226776I2015J-1164D01*
G01X1124284Y230600D02*
G02X1124265Y229059I-1384J-754D01*
G01Y230634D02*
X1124284Y230600D01*
G01X1124240Y232917D02*
G03X1124265Y230634I2040J-1119D01*
G01Y232959D02*
X1124240Y232917D01*
G01X1124265Y234533D02*
G02Y232959I-1365J-787D01*
G01Y236859D02*
G03Y234533I2015J-1163D01*
G01X1124284Y238400D02*
G02X1124265Y236859I-1384J-754D01*
G01Y238434D02*
X1124284Y238400D01*
G01X1124240Y238476D02*
X1124265Y238434D01*
G01Y240759D02*
G03X1124240Y238476I2015J-1164D01*
G01X1124265Y242334D02*
G02Y240759I-1364J-787D01*
G01Y244660D02*
G03Y242334I2015J-1163D01*
G01X1124281Y244688D02*
X1124265Y244660D01*
G01X1126114Y247220D02*
G03X1124281Y244688I11333J-10134D01*
G01X1126280Y247396D02*
X1126114Y247220D01*
G01X1139766Y304612D02*
X1140920Y303947D01*
G01X1139683Y304922D02*
X1139766Y304612D01*
G01X1140876Y305522D02*
G03X1139683Y304922I45J-1575D01*
G01X1140964Y305522D02*
X1140876D01*
G01X1142285Y304734D02*
G03X1140964Y305522I-1365J-787D01*
G01X1144230Y303571D02*
G02X1142285Y304734I70J2325D01*
G01X1144359Y303571D02*
X1144230D01*
G01X1145665Y302784D02*
G03X1144359Y303571I-1365J-788D01*
G01X1147595Y301622D02*
G02X1145665Y302784I85J2325D01*
G01X1147724Y301622D02*
X1147595D01*
G01X1149045Y300834D02*
G03X1147724Y301622I-1365J-787D01*
G01X1150990Y299671D02*
G02X1149045Y300834I70J2325D01*
G01X1151119Y299671D02*
X1150990D01*
G01X1152425Y298884D02*
G03X1151119Y299671I-1365J-788D01*
G01X1154355Y297722D02*
G02X1152425Y298884I85J2325D01*
G01X1154484Y297722D02*
X1154355D01*
G01X1155805Y296934D02*
G03X1154484Y297722I-1365J-787D01*
G01X1157750Y295771D02*
G02X1155805Y296934I70J2325D01*
G01X1138694Y305231D02*
X1137540Y305896D01*
G01X1139046Y305326D02*
X1138694Y305231D01*
G01X1140850Y306272D02*
G03X1139046Y305326I69J-2325D01*
G01X1140990Y306272D02*
X1140850D01*
G01X1142935Y305109D02*
G03X1140990Y306272I-2015J-1162D01*
G01X1144256Y304321D02*
G02X1142935Y305109I44J1575D01*
G01X1144385Y304321D02*
X1144256D01*
G01X1146315Y303159D02*
G03X1144385Y304321I-2015J-1163D01*
G01X1147621Y302372D02*
G02X1146315Y303159I59J1575D01*
G01X1147750Y302372D02*
X1147621D01*
G01X1149695Y301209D02*
G03X1147750Y302372I-2015J-1162D01*
G01X1151016Y300421D02*
G02X1149695Y301209I44J1575D01*
G01X1151145Y300421D02*
X1151016D01*
G01X1153075Y299259D02*
G03X1151145Y300421I-2015J-1163D01*
G01X1154381Y298472D02*
G02X1153075Y299259I59J1575D01*
G01X1154510Y298472D02*
X1154381D01*
G01X1156455Y297309D02*
G03X1154510Y298472I-2015J-1162D01*
G01X1157776Y296521D02*
G02X1156455Y297309I44J1575D01*
G01X1128300Y286700D02*
X1123415D01*
G01X1129570Y287970D02*
X1128300Y286700D01*
G01X1130784Y287970D02*
X1129570D01*
G01X1132145Y287184D02*
G03X1130784Y287970I-1361J-785D01*
G01X1134075Y286022D02*
G02X1132145Y287184I85J2325D01*
G01X1134204Y286022D02*
X1134075D01*
G01X1135397Y285422D02*
G03X1134204Y286022I-1238J-975D01*
G01X1135314Y285112D02*
X1135397Y285422D01*
G01X1134160Y284447D02*
X1135314Y285112D01*
G01X1138694Y294862D02*
X1137540Y294196D01*
G01X1139046Y294767D02*
X1138694Y294862D01*
G01X1140835Y293822D02*
G02X1139046Y294767I84J2325D01*
G01X1140964Y293822D02*
X1140835D01*
G01X1142285Y293034D02*
G03X1140964Y293822I-1365J-787D01*
G01X1144230Y291871D02*
G02X1142285Y293034I70J2325D01*
G01X1144359Y291871D02*
X1144230D01*
G01X1145665Y291084D02*
G03X1144359Y291871I-1365J-788D01*
G01X1147595Y289922D02*
G02X1145665Y291084I85J2325D01*
G01X1147724Y289922D02*
X1147595D01*
G01X1149045Y289134D02*
G03X1147724Y289922I-1365J-787D01*
G01X1150990Y287971D02*
G02X1149045Y289134I70J2325D01*
G01X1151119Y287971D02*
X1150990D01*
G01X1152425Y287184D02*
G03X1151119Y287971I-1365J-788D01*
G01X1154355Y286022D02*
G02X1152425Y287184I85J2325D01*
G01X1154484Y286022D02*
X1154355D01*
G01X1155805Y285234D02*
G03X1154484Y286022I-1365J-787D01*
G01X1157750Y284071D02*
G02X1155805Y285234I70J2325D01*
G01X1143146Y297430D02*
X1144300Y298096D01*
G01X1143063Y297120D02*
X1143146Y297430D01*
G01X1144241Y296521D02*
G02X1143063Y297120I60J1575D01*
G01X1144370Y296521D02*
X1144241D01*
G01X1146315Y295358D02*
G03X1144370Y296521I-2015J-1162D01*
G01X1147632Y294573D02*
G02X1146315Y295358I43J1569D01*
G01X1139766Y295481D02*
X1140920Y296147D01*
G01X1139683Y295171D02*
X1139766Y295481D01*
G01X1140861Y294572D02*
G02X1139683Y295171I60J1575D01*
G01X1140990Y294572D02*
X1140861D01*
G01X1142935Y293409D02*
G03X1140990Y294572I-2015J-1162D01*
G01X1144256Y292621D02*
G02X1142935Y293409I44J1575D01*
G01X1144385Y292621D02*
X1144256D01*
G01X1146315Y291459D02*
G03X1144385Y292621I-2015J-1163D01*
G01X1147621Y290672D02*
G02X1146315Y291459I59J1575D01*
G01X1147750Y290672D02*
X1147621D01*
G01X1149695Y289509D02*
G03X1147750Y290672I-2015J-1162D01*
G01X1151016Y288721D02*
G02X1149695Y289509I44J1575D01*
G01X1151145Y288721D02*
X1151016D01*
G01X1153075Y287559D02*
G03X1151145Y288721I-2015J-1163D01*
G01X1154381Y286772D02*
G02X1153075Y287559I59J1575D01*
G01X1154510Y286772D02*
X1154381D01*
G01X1156455Y285609D02*
G03X1154510Y286772I-2015J-1162D01*
G01X1157776Y284821D02*
G02X1156455Y285609I44J1575D01*
G01X1129415Y309010D02*
G03X1127656Y310160I-2015J-1162D01*
G01X1130736Y308222D02*
G02X1129415Y309010I44J1575D01*
G01X1130831Y308222D02*
X1130736D01*
G01X1132795Y307059D02*
G03X1130831Y308222I-2015J-1163D01*
G01X1134101Y306272D02*
G02X1132795Y307059I59J1575D01*
G01X1134219Y306272D02*
X1134101D01*
G01X1135525Y307059D02*
G02X1134219Y306272I-1365J788D01*
G01X1137539Y308222D02*
G03X1135525Y307059I0J-2325D01*
G01X1137541Y308222D02*
X1137539D01*
G01X1138905Y309010D02*
G02X1137541Y308222I-1364J787D01*
G01X1140917Y310172D02*
G03X1138905Y309010I0J-2323D01*
G01X1140923Y310172D02*
X1140917D01*
G01X1142935Y309010D02*
G03X1140923Y310172I-2012J-1161D01*
G01X1144299Y308222D02*
G02X1142935Y309010I0J1575D01*
G01X1144301Y308222D02*
X1144299D01*
G01X1146315Y307059D02*
G03X1144301Y308222I-2014J-1162D01*
G01X1149045Y307059D02*
G02X1146315I-1365J788D01*
G01X1153075D02*
G03X1149045I-2015J-1163D01*
G01X1154381Y306272D02*
G02X1153075Y307059I59J1575D01*
G01X1154510Y306272D02*
X1154381D01*
G01X1156455Y305109D02*
G03X1154510Y306272I-2015J-1162D01*
G01X1159185Y305109D02*
G02X1156455I-1365J787D01*
G01X1152214Y306562D02*
X1151060Y305896D01*
G01X1152566Y306467D02*
X1152214Y306562D01*
G01X1154355Y305522D02*
G02X1152566Y306467I84J2325D01*
G01X1154484Y305522D02*
X1154355D01*
G01X1155805Y304734D02*
G03X1154484Y305522I-1365J-787D01*
G01X1159835Y304734D02*
G02X1155805I-2015J1162D01*
G01X1136386Y285731D02*
X1137540Y286396D01*
G01X1136034Y285826D02*
X1136386Y285731D01*
G01X1134230Y286772D02*
G02X1136034Y285826I-69J-2325D01*
G01X1134101Y286772D02*
X1134230D01*
G01X1132795Y287559D02*
G03X1134101Y286772I1365J788D01*
G01X1130865Y288721D02*
G02X1132795Y287559I-85J-2325D01*
G01X1118645Y402643D02*
G03X1118626Y404184I-1384J754D01*
G01Y402609D02*
X1118645Y402643D01*
G01X1118601Y402567D02*
X1118626Y402609D01*
G01Y400284D02*
G02X1118601Y402567I2015J1164D01*
G01X1118645Y398743D02*
G03X1118626Y400284I-1384J754D01*
G01Y398709D02*
X1118645Y398743D01*
G01X1118601Y398667D02*
X1118626Y398709D01*
G01Y396384D02*
G02X1118601Y398667I2015J1164D01*
G01X1118645Y394843D02*
G03X1118626Y396384I-1384J754D01*
G01Y394809D02*
X1118645Y394843D01*
G01X1118601Y394767D02*
X1118626Y394809D01*
G01Y392484D02*
G02X1118601Y394767I2015J1164D01*
G01X1118645Y390943D02*
G03X1118626Y392484I-1384J754D01*
G01Y390909D02*
X1118645Y390943D01*
G01X1118601Y390867D02*
X1118626Y390909D01*
G01Y388584D02*
G02X1118601Y390867I2015J1164D01*
G01X1117305Y386221D02*
G03X1118626Y388584I-44J1575D01*
G01X1117176Y386221D02*
X1117305D01*
G01X1115246Y385059D02*
G02X1117176Y386221I2015J-1163D01*
G01X1113940Y384272D02*
G03X1115246Y385059I-59J1575D01*
G01X1113811Y384272D02*
X1113940D01*
G01X1111866Y383109D02*
G02X1113811Y384272I2015J-1162D01*
G01X1110545Y382321D02*
G03X1111866Y383109I-44J1575D01*
G01X1110416Y382321D02*
X1110545D01*
G01X1108486Y381159D02*
G02X1110416Y382321I2015J-1163D01*
G01X1107180Y380372D02*
G03X1108486Y381159I-59J1575D01*
G01X1107051Y380372D02*
X1107180D01*
G01X1105106Y379209D02*
G02X1107051Y380372I2015J-1162D01*
G01X1103785Y378421D02*
G03X1105106Y379209I-44J1575D01*
G01X1103656Y378421D02*
X1103785D01*
G01X1101726Y374933D02*
G02X1103656Y378421I2015J1163D01*
G01X1101726Y373359D02*
G03Y374933I-1365J787D01*
G01X1101701Y373317D02*
X1101726Y373359D01*
G01Y371034D02*
G02X1101701Y373317I2015J1164D01*
G01X1101745Y371000D02*
X1101726Y371034D01*
G01Y369459D02*
G03X1101745Y371000I-1365J787D01*
G01X1101701Y367176D02*
G02X1101726Y369459I2040J1119D01*
G01Y367134D02*
X1101701Y367176D01*
G01X1101745Y367100D02*
X1101726Y367134D01*
G01X1100992Y364903D02*
G03X1101745Y367100I-631J1444D01*
G01X1100026Y364181D02*
G02X1100992Y364903I2026J-1703D01*
G01X1099498Y363765D02*
G03X1100026Y364181I-2096J3203D01*
G01X1098996Y361659D02*
G02X1099498Y363765I1365J787D01*
G01X1099021Y359376D02*
G03X1098996Y361659I-2040J1119D01*
G01Y359334D02*
X1099021Y359376D01*
G01X1098977Y359300D02*
X1098996Y359334D01*
G01Y357759D02*
G02X1098977Y359300I1365J787D01*
G01X1099062Y357646D02*
X1098996Y357759D01*
G01X1100361Y354647D02*
X1099062Y357646D01*
G01X1132164Y402643D02*
G03X1132145Y404184I-1384J754D01*
G01Y402609D02*
X1132164Y402643D01*
G01X1132120Y402567D02*
X1132145Y402609D01*
G01Y400284D02*
G02X1132120Y402567I2015J1164D01*
G01X1132164Y398743D02*
G03X1132145Y400284I-1384J754D01*
G01Y398709D02*
X1132164Y398743D01*
G01X1132120Y398667D02*
X1132145Y398709D01*
G01Y396384D02*
G02X1132120Y398667I2015J1164D01*
G01X1132164Y394843D02*
G03X1132145Y396384I-1384J754D01*
G01Y394809D02*
X1132164Y394843D01*
G01X1132120Y394767D02*
X1132145Y394809D01*
G01Y392484D02*
G02X1132120Y394767I2015J1164D01*
G01X1132164Y390943D02*
G03X1132145Y392484I-1384J754D01*
G01Y390909D02*
X1132164Y390943D01*
G01X1132120Y390867D02*
X1132145Y390909D01*
G01Y388584D02*
G02X1132120Y390867I2015J1164D01*
G01X1132145Y387012D02*
G03Y388584I-1362J786D01*
G01Y384684D02*
G02Y387012I2017J1164D01*
G01X1130824Y382321D02*
G03X1132145Y384684I-44J1575D01*
G01X1130695Y382321D02*
X1130824D01*
G01X1128765Y381159D02*
G02X1130695Y382321I2015J-1163D01*
G01X1127459Y380372D02*
G03X1128765Y381159I-59J1575D01*
G01X1127330Y380372D02*
X1127459D01*
G01X1125385Y379209D02*
G02X1127330Y380372I2015J-1162D01*
G01X1125372Y379186D02*
X1125385Y379209D01*
G01X1124021Y378421D02*
G03X1125372Y379186I0J1575D01*
G01X1123936Y378421D02*
X1124021D01*
G01X1122006Y377259D02*
G02X1123936Y378421I2015J-1163D01*
G01X1120700Y376472D02*
G03X1122006Y377259I-59J1575D01*
G01X1120590Y376472D02*
X1120700D01*
G01X1118626Y375309D02*
G02X1120590Y376472I2015J-1163D01*
G01X1117332Y374522D02*
G03X1118626Y375309I-71J1574D01*
G01X1117191Y374522D02*
X1117332D01*
G01X1115246Y373359D02*
G02X1117191Y374522I2015J-1162D01*
G01X1113952Y372572D02*
G03X1115246Y373359I-71J1574D01*
G01X1113796Y372572D02*
X1113952D01*
G01X1111866Y369084D02*
G02X1113796Y372572I2015J1163D01*
G01X1111885Y367543D02*
G03X1111866Y369084I-1384J754D01*
G01Y367509D02*
X1111885Y367543D01*
G01X1111841Y367467D02*
X1111866Y367509D01*
G01Y365184D02*
G02X1111841Y367467I2015J1164D01*
G01X1111885Y363643D02*
G03X1111866Y365184I-1384J754D01*
G01Y363609D02*
X1111885Y363643D01*
G01X1111841Y363567D02*
X1111866Y363609D01*
G01Y361284D02*
G02X1111841Y363567I2015J1164D01*
G01X1111885Y359743D02*
G03X1111866Y361284I-1384J754D01*
G01Y359709D02*
X1111885Y359743D01*
G01X1111841Y359667D02*
X1111866Y359709D01*
G01Y357384D02*
G02X1111841Y359667I2015J1164D01*
G01X1111932Y357268D02*
X1111866Y357384D01*
G01X1112023Y357146D02*
X1111932Y357268D01*
G01X1113881Y354647D02*
X1112023Y357146D01*
G01X1109109Y402657D02*
G02X1109136Y404183I1392J739D01*
G01X1109171Y402549D02*
X1109109Y402657D01*
G01X1109136Y400283D02*
G03X1109171Y402549I-2015J1164D01*
G01X1109109Y398757D02*
G02X1109136Y400283I1392J739D01*
G01X1109161Y398666D02*
X1109109Y398757D01*
G01X1109171Y398649D02*
X1109161Y398666D01*
G01X1109136Y396383D02*
G03X1109171Y398649I-2015J1164D01*
G01X1109109Y394857D02*
G02X1109136Y396383I1392J739D01*
G01Y394809D02*
X1109109Y394857D01*
G01X1109161Y394767D02*
X1109136Y394809D01*
G01X1107206Y391322D02*
G03X1109161Y394767I-85J2325D01*
G01X1107077Y391322D02*
X1107206D01*
G01X1105756Y390534D02*
G02X1107077Y391322I1365J-787D01*
G01X1103811Y389371D02*
G03X1105756Y390534I-70J2325D01*
G01X1103682Y389371D02*
X1103811D01*
G01X1102376Y388584D02*
G02X1103682Y389371I1365J-788D01*
G01X1100446Y387422D02*
G03X1102376Y388584I-85J2325D01*
G01X1100317Y387422D02*
X1100446D01*
G01X1098996Y386634D02*
G02X1100317Y387422I1365J-787D01*
G01X1097051Y385471D02*
G03X1098996Y386634I-70J2325D01*
G01X1096922Y385471D02*
X1097051D01*
G01X1095616Y384684D02*
G02X1096922Y385471I1365J-788D01*
G01X1108451Y402293D02*
G02X1108486Y404559I2050J1102D01*
G01X1108513Y402185D02*
X1108451Y402293D01*
G01X1108486Y400659D02*
G03X1108513Y402185I-1365J787D01*
G01X1108451Y398393D02*
G02X1108486Y400659I2050J1102D01*
G01X1108513Y398285D02*
X1108451Y398393D01*
G01X1108486Y396759D02*
G03X1108513Y398285I-1365J787D01*
G01X1108451Y394493D02*
G02X1108486Y396759I2050J1102D01*
G01X1108513Y394385D02*
X1108451Y394493D01*
G01X1107180Y392072D02*
G03X1108513Y394385I-59J1575D01*
G01X1107051Y392072D02*
X1107180D01*
G01X1105106Y390909D02*
G02X1107051Y392072I2015J-1162D01*
G01X1103785Y390121D02*
G03X1105106Y390909I-44J1575D01*
G01X1103656Y390121D02*
X1103785D01*
G01X1101726Y388959D02*
G02X1103656Y390121I2015J-1163D01*
G01X1100420Y388172D02*
G03X1101726Y388959I-59J1575D01*
G01X1100291Y388172D02*
X1100420D01*
G01X1098346Y387009D02*
G02X1100291Y388172I2015J-1162D01*
G01X1097025Y386221D02*
G03X1098346Y387009I-44J1575D01*
G01X1096896Y386221D02*
X1097025D01*
G01X1132820Y402276D02*
G03X1132795Y404559I-2040J1119D01*
G01Y402234D02*
X1132820Y402276D01*
G01X1132776Y402200D02*
X1132795Y402234D01*
G01Y400659D02*
G02X1132776Y402200I1365J787D01*
G01X1132820Y398376D02*
G03X1132795Y400659I-2040J1119D01*
G01Y398334D02*
X1132820Y398376D01*
G01X1132776Y398300D02*
X1132795Y398334D01*
G01Y396759D02*
G02X1132776Y398300I1365J787D01*
G01X1132820Y394476D02*
G03X1132795Y396759I-2040J1119D01*
G01Y394434D02*
X1132820Y394476D01*
G01X1132776Y394400D02*
X1132795Y394434D01*
G01Y392859D02*
G02X1132776Y394400I1365J787D01*
G01X1132820Y390576D02*
G03X1132795Y392859I-2040J1119D01*
G01Y390534D02*
X1132820Y390576D01*
G01X1132776Y390500D02*
X1132795Y390534D01*
G01Y388959D02*
G02X1132776Y390500I1365J787D01*
G01X1132795Y386636D02*
G03Y388959I-2015J1161D01*
G01Y385059D02*
G02Y386636I1368J788D01*
G01X1130850Y381571D02*
G03X1132795Y385059I-70J2325D01*
G01X1130721Y381571D02*
X1130850D01*
G01X1129415Y380784D02*
G02X1130721Y381571I1365J-788D01*
G01X1127485Y379622D02*
G03X1129415Y380784I-85J2325D01*
G01X1127400Y379622D02*
X1127485D01*
G01X1126049Y378857D02*
G02X1127400Y379622I1351J-810D01*
G01X1126036Y378834D02*
X1126049Y378857D01*
G01X1124091Y377671D02*
G03X1126036Y378834I-70J2325D01*
G01X1123962Y377671D02*
X1124091D01*
G01X1122656Y376884D02*
G02X1123962Y377671I1365J-788D01*
G01X1120692Y375721D02*
G03X1122656Y376884I-51J2326D01*
G01X1120597Y375721D02*
X1120692D01*
G01X1119276Y374933D02*
G02X1120597Y375721I1365J-787D01*
G01X1117346Y373771D02*
G03X1119276Y374933I-85J2325D01*
G01X1117190Y373771D02*
X1117346D01*
G01X1115896Y372984D02*
G02X1117190Y373771I1365J-787D01*
G01X1113951Y371821D02*
G03X1115896Y372984I-70J2325D01*
G01X1113810Y371821D02*
X1113951D01*
G01X1112516Y369459D02*
G02X1113810Y371821I1365J788D01*
G01X1112541Y367176D02*
G03X1112516Y369459I-2040J1119D01*
G01Y367134D02*
X1112541Y367176D01*
G01X1112497Y367100D02*
X1112516Y367134D01*
G01Y365559D02*
G02X1112497Y367100I1365J787D01*
G01X1112582Y365446D02*
X1112516Y365559D01*
G01X1113881Y362447D02*
X1112582Y365446D01*
G01X1122637Y402643D02*
G02X1122656Y404184I1384J754D01*
G01Y402609D02*
X1122637Y402643D01*
G01X1122681Y402567D02*
X1122656Y402609D01*
G01Y400284D02*
G03X1122681Y402567I-2015J1164D01*
G01X1122637Y398743D02*
G02X1122656Y400284I1384J754D01*
G01Y398709D02*
X1122637Y398743D01*
G01X1122681Y398667D02*
X1122656Y398709D01*
G01Y396384D02*
G03X1122681Y398667I-2015J1164D01*
G01X1122637Y394843D02*
G02X1122656Y396384I1384J754D01*
G01Y394809D02*
X1122637Y394843D01*
G01X1122681Y394767D02*
X1122656Y394809D01*
G01Y392484D02*
G03X1122681Y394767I-2015J1164D01*
G01X1122637Y390943D02*
G02X1122656Y392484I1384J754D01*
G01Y390909D02*
X1122637Y390943D01*
G01X1122681Y390867D02*
X1122656Y390909D01*
G01Y388584D02*
G03X1122681Y390867I-2015J1164D01*
G01X1122637Y387043D02*
G02X1122656Y388584I1384J754D01*
G01Y387009D02*
X1122637Y387043D01*
G01X1122681Y386967D02*
X1122656Y387009D01*
G01X1120726Y383522D02*
G03X1122681Y386967I-85J2325D01*
G01X1120597Y383522D02*
X1120726D01*
G01X1119276Y382734D02*
G02X1120597Y383522I1365J-787D01*
G01X1117331Y381571D02*
G03X1119276Y382734I-70J2325D01*
G01X1117202Y381571D02*
X1117331D01*
G01X1115896Y380784D02*
G02X1117202Y381571I1365J-788D01*
G01X1113966Y379622D02*
G03X1115896Y380784I-85J2325D01*
G01X1113837Y379622D02*
X1113966D01*
G01X1112516Y378834D02*
G02X1113837Y379622I1365J-787D01*
G01X1110571Y377671D02*
G03X1112516Y378834I-70J2325D01*
G01X1110442Y377671D02*
X1110571D01*
G01X1109136Y376884D02*
G02X1110442Y377671I1365J-788D01*
G01X1107172Y375721D02*
G03X1109136Y376884I-51J2326D01*
G01X1107077Y375721D02*
X1107172D01*
G01X1105756Y373359D02*
G02X1107077Y375721I1365J787D01*
G01X1105781Y373317D02*
X1105756Y373359D01*
G01Y371034D02*
G03X1105781Y373317I-2015J1164D01*
G01X1105737Y371000D02*
X1105756Y371034D01*
G01Y369459D02*
G02X1105737Y371000I1365J787D01*
G01X1105781Y367176D02*
G03X1105756Y369459I-2040J1119D01*
G01Y367134D02*
X1105781Y367176D01*
G01X1105737Y367100D02*
X1105756Y367134D01*
G01Y365559D02*
G02X1105737Y367100I1365J787D01*
G01X1105781Y363276D02*
G03X1105756Y365559I-2040J1119D01*
G01Y363234D02*
X1105781Y363276D01*
G01X1105690Y363118D02*
X1105756Y363234D01*
G01X1103741Y360496D02*
X1105690Y363118D01*
G01X1121981Y402276D02*
G02X1122006Y404559I2040J1119D01*
G01Y402234D02*
X1121981Y402276D01*
G01X1122025Y402200D02*
X1122006Y402234D01*
G01Y400659D02*
G03X1122025Y402200I-1365J787D01*
G01X1121981Y398376D02*
G02X1122006Y400659I2040J1119D01*
G01Y398334D02*
X1121981Y398376D01*
G01X1122025Y398300D02*
X1122006Y398334D01*
G01Y396759D02*
G03X1122025Y398300I-1365J787D01*
G01X1121981Y394476D02*
G02X1122006Y396759I2040J1119D01*
G01Y394434D02*
X1121981Y394476D01*
G01X1122025Y394400D02*
X1122006Y394434D01*
G01Y392859D02*
G03X1122025Y394400I-1365J787D01*
G01X1121981Y390576D02*
G02X1122006Y392859I2040J1119D01*
G01Y390534D02*
X1121981Y390576D01*
G01X1122025Y390500D02*
X1122006Y390534D01*
G01Y388959D02*
G03X1122025Y390500I-1365J787D01*
G01X1121981Y386676D02*
G02X1122006Y388959I2040J1119D01*
G01Y386634D02*
X1121981Y386676D01*
G01X1122025Y386600D02*
X1122006Y386634D01*
G01X1120700Y384272D02*
G03X1122025Y386600I-59J1575D01*
G01X1120571Y384272D02*
X1120700D01*
G01X1118626Y383109D02*
G02X1120571Y384272I2015J-1162D01*
G01X1117305Y382321D02*
G03X1118626Y383109I-44J1575D01*
G01X1117176Y382321D02*
X1117305D01*
G01X1115246Y381159D02*
G02X1117176Y382321I2015J-1163D01*
G01X1113940Y380372D02*
G03X1115246Y381159I-59J1575D01*
G01X1113811Y380372D02*
X1113940D01*
G01X1111866Y379209D02*
G02X1113811Y380372I2015J-1162D01*
G01X1110545Y378421D02*
G03X1111866Y379209I-44J1575D01*
G01X1110416Y378421D02*
X1110545D01*
G01X1108486Y377259D02*
G02X1110416Y378421I2015J-1163D01*
G01X1107180Y376472D02*
G03X1108486Y377259I-59J1575D01*
G01X1107070Y376472D02*
X1107180D01*
G01X1105081Y373026D02*
G02X1107070Y376472I2040J1120D01*
G01X1105106Y372984D02*
X1105081Y373026D01*
G01X1105106Y371410D02*
G03Y372984I-1365J787D01*
G01Y369084D02*
G02Y371410I2015J1163D01*
G01X1105125Y367543D02*
G03X1105106Y369084I-1384J754D01*
G01Y367509D02*
X1105125Y367543D01*
G01X1105081Y367467D02*
X1105106Y367509D01*
G01Y365184D02*
G02X1105081Y367467I2015J1164D01*
G01X1104242Y362902D02*
G03X1105106Y365184I-501J1494D01*
G01X1102026Y360681D02*
G02X1104242Y362902I3333J-1109D01*
G01X1102145Y358743D02*
G02X1102026Y360681I2349J1117D01*
G01X1103741Y356596D02*
X1102145Y358743D01*
G01X1129396Y402643D02*
G02X1129415Y404184I1384J754D01*
G01Y402609D02*
X1129396Y402643D01*
G01X1129440Y402567D02*
X1129415Y402609D01*
G01Y400284D02*
G03X1129440Y402567I-2015J1164D01*
G01X1129396Y398743D02*
G02X1129415Y400284I1384J754D01*
G01Y398709D02*
X1129396Y398743D01*
G01X1129440Y398667D02*
X1129415Y398709D01*
G01Y396384D02*
G03X1129440Y398667I-2015J1164D01*
G01X1129396Y394843D02*
G02X1129415Y396384I1384J754D01*
G01Y394809D02*
X1129396Y394843D01*
G01X1129440Y394767D02*
X1129415Y394809D01*
G01Y392484D02*
G03X1129440Y394767I-2015J1164D01*
G01X1129396Y390943D02*
G02X1129415Y392484I1384J754D01*
G01Y390909D02*
X1129396Y390943D01*
G01X1129440Y390867D02*
X1129415Y390909D01*
G01X1129489Y388723D02*
G03X1129440Y390867I-2089J1025D01*
G01X1129415Y388586D02*
G03X1129489Y388723I-2430J1401D01*
G01X1129415Y387012D02*
G02Y388586I1365J787D01*
G01Y384686D02*
G03Y387012I-2015J1163D01*
G01X1127485Y383522D02*
G03X1129415Y384686I-89J2329D01*
G01X1127400Y383522D02*
X1127485D01*
G01X1126049Y382757D02*
G02X1127400Y383522I1351J-810D01*
G01X1126036Y382734D02*
X1126049Y382757D01*
G01X1124091Y381571D02*
G03X1126036Y382734I-70J2325D01*
G01X1123962Y381571D02*
X1124091D01*
G01X1122656Y380784D02*
G02X1123962Y381571I1365J-788D01*
G01X1120726Y379622D02*
G03X1122656Y380784I-85J2325D01*
G01X1120597Y379622D02*
X1120726D01*
G01X1119276Y378834D02*
G02X1120597Y379622I1365J-787D01*
G01X1117331Y377671D02*
G03X1119276Y378834I-70J2325D01*
G01X1117202Y377671D02*
X1117331D01*
G01X1115896Y376884D02*
G02X1117202Y377671I1365J-788D01*
G01X1113932Y375721D02*
G03X1115896Y376884I-51J2326D01*
G01X1113837Y375721D02*
X1113932D01*
G01X1112516Y374933D02*
G02X1113837Y375721I1365J-787D01*
G01X1110586Y373771D02*
G03X1112516Y374933I-85J2325D01*
G01X1110430Y373771D02*
X1110586D01*
G01X1109136Y371410D02*
G02X1110430Y373771I1365J787D01*
G01X1109136Y369084D02*
G03Y371410I-2015J1163D01*
G01X1109117Y367543D02*
G02X1109136Y369084I1384J754D01*
G01Y367509D02*
X1109117Y367543D01*
G01X1109161Y367467D02*
X1109136Y367509D01*
G01Y365184D02*
G03X1109161Y367467I-2015J1164D01*
G01X1109117Y363643D02*
G02X1109136Y365184I1384J754D01*
G01X1109204Y363492D02*
X1109117Y363643D01*
G01X1110501Y360496D02*
X1109204Y363492D01*
G01X1105125Y402643D02*
G03X1105106Y404184I-1384J754D01*
G01Y402609D02*
X1105125Y402643D01*
G01X1105081Y402567D02*
X1105106Y402609D01*
G01Y400284D02*
G02X1105081Y402567I2015J1164D01*
G01X1105125Y398743D02*
G03X1105106Y400284I-1384J754D01*
G01Y398709D02*
X1105125Y398743D01*
G01X1105081Y398667D02*
X1105106Y398709D01*
G01Y396384D02*
G02X1105081Y398667I2015J1164D01*
G01X1103785Y394021D02*
G03X1105106Y396384I-44J1575D01*
G01X1103656Y394021D02*
X1103785D01*
G01X1101726Y392859D02*
G02X1103656Y394021I2015J-1163D01*
G01X1100420Y392072D02*
G03X1101726Y392859I-59J1575D01*
G01X1100291Y392072D02*
X1100420D01*
G01X1098346Y390909D02*
G02X1100291Y392072I2015J-1162D01*
G01X1097025Y390121D02*
G03X1098346Y390909I-44J1575D01*
G01X1096896Y390121D02*
X1097025D01*
G01X1119301Y402276D02*
G03X1119276Y404559I-2040J1119D01*
G01Y402234D02*
X1119301Y402276D01*
G01X1119257Y402200D02*
X1119276Y402234D01*
G01Y400659D02*
G02X1119257Y402200I1365J787D01*
G01X1119301Y398376D02*
G03X1119276Y400659I-2040J1119D01*
G01Y398334D02*
X1119301Y398376D01*
G01X1119257Y398300D02*
X1119276Y398334D01*
G01Y396759D02*
G02X1119257Y398300I1365J787D01*
G01X1119301Y394476D02*
G03X1119276Y396759I-2040J1119D01*
G01Y394434D02*
X1119301Y394476D01*
G01X1119257Y394400D02*
X1119276Y394434D01*
G01Y392859D02*
G02X1119257Y394400I1365J787D01*
G01X1119301Y390576D02*
G03X1119276Y392859I-2040J1119D01*
G01Y390534D02*
X1119301Y390576D01*
G01X1119257Y390500D02*
X1119276Y390534D01*
G01Y388959D02*
G02X1119257Y390500I1365J787D01*
G01X1117331Y385471D02*
G03X1119276Y388959I-70J2325D01*
G01X1117202Y385471D02*
X1117331D01*
G01X1115896Y384684D02*
G02X1117202Y385471I1365J-788D01*
G01X1113966Y383522D02*
G03X1115896Y384684I-85J2325D01*
G01X1113837Y383522D02*
X1113966D01*
G01X1112516Y382734D02*
G02X1113837Y383522I1365J-787D01*
G01X1110571Y381571D02*
G03X1112516Y382734I-70J2325D01*
G01X1110442Y381571D02*
X1110571D01*
G01X1109136Y380784D02*
G02X1110442Y381571I1365J-788D01*
G01X1107206Y379622D02*
G03X1109136Y380784I-85J2325D01*
G01X1107077Y379622D02*
X1107206D01*
G01X1105756Y378834D02*
G02X1107077Y379622I1365J-787D01*
G01X1103811Y377671D02*
G03X1105756Y378834I-70J2325D01*
G01X1103682Y377671D02*
X1103811D01*
G01X1102357Y375343D02*
G02X1103682Y377671I1384J753D01*
G01X1102376Y375309D02*
X1102357Y375343D01*
G01X1102401Y373026D02*
G03X1102376Y375309I-2040J1119D01*
G01Y372984D02*
X1102401Y373026D01*
G01X1102376Y371410D02*
G02Y372984I1365J787D01*
G01Y369084D02*
G03Y371410I-2015J1163D01*
G01X1102357Y367543D02*
G02X1102376Y369084I1384J754D01*
G01Y367509D02*
X1102357Y367543D01*
G01X1102401Y367467D02*
X1102376Y367509D01*
G01Y365184D02*
G03X1102401Y367467I-2015J1164D01*
G01X1102310Y365068D02*
X1102376Y365184D01*
G01X1100361Y362447D02*
X1102310Y365068D01*
G01X1145665Y402609D02*
G02X1147595Y403771I2015J-1163D01*
G01X1144344Y401821D02*
G03X1145665Y402609I-44J1575D01*
G01X1144215Y401821D02*
X1144344D01*
G01X1142285Y398333D02*
G02X1144215Y401821I2015J1163D01*
G01X1142285Y396759D02*
G03Y398333I-1365J787D01*
G01X1142260Y396717D02*
X1142285Y396759D01*
G01Y394434D02*
G02X1142260Y396717I2015J1164D01*
G01X1142304Y394400D02*
X1142285Y394434D01*
G01Y392859D02*
G03X1142304Y394400I-1365J787D01*
G01X1142260Y390576D02*
G02X1142285Y392859I2040J1119D01*
G01Y390534D02*
X1142260Y390576D01*
G01X1142304Y390500D02*
X1142285Y390534D01*
G01Y388959D02*
G03X1142304Y390500I-1365J787D01*
G01X1142260Y386676D02*
G02X1142285Y388959I2040J1119D01*
G01Y385062D02*
G03X1142260Y386676I-1362J786D01*
G01X1142285Y382736D02*
G02Y385062I2015J1163D01*
G01X1142304Y381194D02*
G03X1142285Y382736I-1384J754D01*
G01Y381160D02*
X1142304Y381194D01*
G01X1142260Y381118D02*
X1142285Y381160D01*
G01Y378835D02*
G02X1142260Y381118I2015J1164D01*
G01X1140991Y376473D02*
G03X1142285Y378835I-71J1574D01*
G01X1140850Y376473D02*
G03X1140991I70J1563D01*
G01X1138905Y375309D02*
G02X1140850Y376473I2017J-1163D01*
G01X1137611Y374522D02*
G03X1138905Y375309I-71J1574D01*
G01X1137470Y374522D02*
X1137611D01*
G01X1135525Y373359D02*
G02X1137470Y374522I2015J-1162D01*
G01X1134231Y372572D02*
G03X1135525Y373359I-71J1574D01*
G01X1134075Y372572D02*
X1134231D01*
G01X1132145Y371410D02*
G02X1134075Y372572I2015J-1163D01*
G01X1130824Y370622D02*
G03X1132145Y371410I-44J1575D01*
G01X1130729Y370622D02*
X1130824D01*
G01X1128765Y369459D02*
G02X1130729Y370622I2015J-1163D01*
G01X1127459Y368672D02*
G03X1128765Y369459I-59J1575D01*
G01X1127330Y368672D02*
X1127459D01*
G01X1125385Y367509D02*
G02X1127330Y368672I2015J-1162D01*
G01X1125372Y367486D02*
X1125385Y367509D01*
G01X1124021Y366721D02*
G03X1125372Y367486I0J1575D01*
G01X1123936Y366721D02*
X1124021D01*
G01X1122006Y365559D02*
G02X1123936Y366721I2015J-1163D01*
G01X1121128Y364848D02*
G03X1122006Y365559I-487J1499D01*
G01X1120576Y364571D02*
G02X1121128Y364848I1186J-1675D01*
G01X1119784Y363769D02*
G03X1120576Y364571I-1424J2198D01*
G01X1119276Y361659D02*
G02X1119784Y363769I1365J787D01*
G01X1119301Y359376D02*
G03X1119276Y361659I-2040J1119D01*
G01Y359334D02*
X1119301Y359376D01*
G01X1119257Y359300D02*
X1119276Y359334D01*
G01Y357759D02*
G02X1119257Y359300I1365J787D01*
G01X1119342Y357646D02*
X1119276Y357759D01*
G01X1120641Y354647D02*
X1119342Y357646D01*
G01X1146315Y402233D02*
G02X1147273Y402968I1365J-787D01*
G01X1144385Y401071D02*
G03X1146315Y402233I-85J2325D01*
G01X1144241Y401071D02*
X1144385D01*
G01X1142916Y398743D02*
G02X1144241Y401071I1384J753D01*
G01X1142935Y398709D02*
X1142916Y398743D01*
G01X1142960Y396426D02*
G03X1142935Y398709I-2040J1119D01*
G01Y396384D02*
X1142960Y396426D01*
G01X1142935Y394810D02*
G02Y396384I1365J787D01*
G01Y392484D02*
G03Y394810I-2015J1163D01*
G01X1142916Y390943D02*
G02X1142935Y392484I1384J754D01*
G01Y390909D02*
X1142916Y390943D01*
G01X1142960Y390867D02*
X1142935Y390909D01*
G01Y388584D02*
G03X1142960Y390867I-2015J1164D01*
G01X1142916Y387043D02*
G02X1142935Y388584I1384J754D01*
G01Y387009D02*
X1142916Y387043D01*
G01X1142935Y384686D02*
G03Y387009I-2015J1161D01*
G01Y383112D02*
G02Y384686I1365J787D01*
G01X1142960Y380827D02*
G03X1142935Y383112I-2045J1120D01*
G01Y380785D02*
X1142960Y380827D01*
G01X1142916Y380751D02*
X1142935Y380785D01*
G01Y379210D02*
G02X1142916Y380751I1365J787D01*
G01X1141005Y375722D02*
G03X1142935Y379210I-85J2325D01*
G01X1140876Y375721D02*
G03X1141005Y375722I47J2240D01*
G01X1139555Y374933D02*
G02X1140876Y375721I1365J-787D01*
G01X1137625Y373771D02*
G03X1139555Y374933I-85J2325D01*
G01X1137469Y373771D02*
X1137625D01*
G01X1136175Y372984D02*
G02X1137469Y373771I1365J-787D01*
G01X1134230Y371821D02*
G03X1136175Y372984I-70J2325D01*
G01X1134089Y371821D02*
X1134230D01*
G01X1132795Y371034D02*
G02X1134089Y371821I1365J-787D01*
G01X1130831Y369871D02*
G03X1132795Y371034I-51J2326D01*
G01X1130721Y369871D02*
X1130831D01*
G01X1129415Y369084D02*
G02X1130721Y369871I1365J-788D01*
G01X1127485Y367922D02*
G03X1129415Y369084I-85J2325D01*
G01X1127400Y367922D02*
X1127485D01*
G01X1126049Y367157D02*
G02X1127400Y367922I1351J-810D01*
G01X1126036Y367134D02*
X1126049Y367157D01*
G01X1124091Y365971D02*
G03X1126036Y367134I-70J2325D01*
G01X1123962Y365971D02*
X1124091D01*
G01X1122656Y365184D02*
G02X1123962Y365971I1365J-788D01*
G01X1122590Y365068D02*
X1122656Y365184D01*
G01X1120641Y362447D02*
X1122590Y365068D01*
G01X1095582Y402666D02*
G02X1095616Y404182I1399J727D01*
G01X1095641Y402565D02*
X1095582Y402666D01*
G01X1095616Y400282D02*
G03X1095641Y402565I-2015J1164D01*
G01X1095597Y398741D02*
G02X1095616Y400282I1384J754D01*
G01Y398707D02*
X1095597Y398741D01*
G01X1095641Y396424D02*
G03X1095616Y398707I-2040J1119D01*
G01Y396382D02*
X1095641Y396424D01*
G01X1095616Y394808D02*
G02Y396382I1365J787D01*
G01X1105781Y402276D02*
G03X1105756Y404559I-2040J1119D01*
G01Y402234D02*
X1105781Y402276D01*
G01X1105737Y402200D02*
X1105756Y402234D01*
G01Y400659D02*
G02X1105737Y402200I1365J787D01*
G01X1105781Y398376D02*
G03X1105756Y400659I-2040J1119D01*
G01Y398334D02*
X1105781Y398376D01*
G01X1105737Y398300D02*
X1105756Y398334D01*
G01Y396759D02*
G02X1105737Y398300I1365J787D01*
G01X1103811Y393271D02*
G03X1105756Y396759I-70J2325D01*
G01X1103682Y393271D02*
X1103811D01*
G01X1102376Y392484D02*
G02X1103682Y393271I1365J-788D01*
G01X1100446Y391322D02*
G03X1102376Y392484I-85J2325D01*
G01X1100317Y391322D02*
X1100446D01*
G01X1098996Y390534D02*
G02X1100317Y391322I1365J-787D01*
G01X1097051Y389371D02*
G03X1098996Y390534I-70J2325D01*
G01X1096922Y389371D02*
X1097051D01*
G01X1095616Y388584D02*
G02X1096922Y389371I1365J-788D01*
G01X1128740Y402276D02*
G02X1128765Y404559I2040J1119D01*
G01Y402234D02*
X1128740Y402276D01*
G01X1128784Y402200D02*
X1128765Y402234D01*
G01Y400659D02*
G03X1128784Y402200I-1365J787D01*
G01X1128740Y398376D02*
G02X1128765Y400659I2040J1119D01*
G01Y398334D02*
X1128740Y398376D01*
G01X1128784Y398300D02*
X1128765Y398334D01*
G01Y396759D02*
G03X1128784Y398300I-1365J787D01*
G01X1128740Y394476D02*
G02X1128765Y396759I2040J1119D01*
G01Y394434D02*
X1128740Y394476D01*
G01X1128784Y394400D02*
X1128765Y394434D01*
G01Y392859D02*
G03X1128784Y394400I-1365J787D01*
G01X1128740Y390576D02*
G02X1128765Y392859I2040J1119D01*
G01Y390534D02*
X1128740Y390576D01*
G01X1128784Y390500D02*
X1128765Y390534D01*
G01X1128869Y389175D02*
G03X1128784Y390500I-1469J571D01*
G01X1128765Y388962D02*
G03X1128869Y389175I-1221J728D01*
G01X1128765Y386636D02*
G02Y388962I2015J1163D01*
G01Y385062D02*
G03Y386636I-1365J787D01*
G01X1127459Y384272D02*
G03X1128765Y385062I-64J1580D01*
G01X1127330Y384272D02*
X1127459D01*
G01X1125385Y383109D02*
G02X1127330Y384272I2015J-1162D01*
G01X1125372Y383086D02*
X1125385Y383109D01*
G01X1124021Y382321D02*
G03X1125372Y383086I0J1575D01*
G01X1123936Y382321D02*
X1124021D01*
G01X1122006Y381159D02*
G02X1123936Y382321I2015J-1163D01*
G01X1120700Y380372D02*
G03X1122006Y381159I-59J1575D01*
G01X1120571Y380372D02*
X1120700D01*
G01X1118626Y379209D02*
G02X1120571Y380372I2015J-1162D01*
G01X1117305Y378421D02*
G03X1118626Y379209I-44J1575D01*
G01X1117176Y378421D02*
X1117305D01*
G01X1115246Y377259D02*
G02X1117176Y378421I2015J-1163D01*
G01X1113940Y376472D02*
G03X1115246Y377259I-59J1575D01*
G01X1113830Y376472D02*
X1113940D01*
G01X1111866Y375309D02*
G02X1113830Y376472I2015J-1163D01*
G01X1110572Y374522D02*
G03X1111866Y375309I-71J1574D01*
G01X1110431Y374522D02*
X1110572D01*
G01X1108486Y371034D02*
G02X1110431Y374522I2015J1163D01*
G01X1108505Y371000D02*
X1108486Y371034D01*
G01Y369459D02*
G03X1108505Y371000I-1365J787D01*
G01X1108461Y367176D02*
G02X1108486Y369459I2040J1119D01*
G01Y367134D02*
X1108461Y367176D01*
G01X1108505Y367100D02*
X1108486Y367134D01*
G01Y365559D02*
G03X1108505Y367100I-1365J787D01*
G01X1108461Y363276D02*
G02X1108486Y365559I2040J1119D01*
G01Y363234D02*
X1108461Y363276D01*
G01X1108505Y363200D02*
X1108486Y363234D01*
G01Y361659D02*
G03X1108505Y363200I-1365J787D01*
G01X1108461Y359376D02*
G02X1108486Y361659I2040J1119D01*
G01Y359334D02*
X1108461Y359376D01*
G01X1108552Y359218D02*
X1108486Y359334D01*
G01X1110501Y356596D02*
X1108552Y359218D01*
G01X1151971Y402308D02*
Y404889D01*
G01X1151485Y401822D02*
X1151971Y402308D01*
G01X1150990Y401822D02*
X1151485D01*
G01X1149045Y400659D02*
G02X1150990Y401822I2015J-1162D01*
G01X1147724Y399871D02*
G03X1149045Y400659I-44J1575D01*
G01X1147595Y399871D02*
X1147724D01*
G01X1145640Y396426D02*
G02X1147595Y399871I2040J1120D01*
G01X1145665Y396384D02*
X1145640Y396426D01*
G01X1145665Y394810D02*
G03Y396384I-1365J787D01*
G01Y392484D02*
G02Y394810I2015J1163D01*
G01X1145684Y390943D02*
G03X1145665Y392484I-1384J754D01*
G01Y388586D02*
G02X1145684Y390943I2016J1162D01*
G01X1145665Y387012D02*
G03Y388586I-1365J787D01*
G01Y384686D02*
G02Y387012I2015J1163D01*
G01Y383112D02*
G03Y384686I-1365J787D01*
G01Y380786D02*
G02Y383112I2015J1163D01*
G01Y379209D02*
G03Y380786I-1366J788D01*
G01X1145640Y379167D02*
X1145665Y379209D01*
G01Y376884D02*
G02X1145640Y379167I2015J1164D01*
G01X1144371Y374522D02*
G03X1145665Y376884I-71J1574D01*
G01X1144230Y374522D02*
X1144371D01*
G01X1142285Y373359D02*
G02X1144230Y374522I2015J-1162D01*
G01X1140991Y372572D02*
G03X1142285Y373359I-71J1574D01*
G01X1140835Y372572D02*
X1140991D01*
G01X1138905Y371410D02*
G02X1140835Y372572I2015J-1163D01*
G01X1137584Y370622D02*
G03X1138905Y371410I-44J1575D01*
G01X1137489Y370622D02*
X1137584D01*
G01X1135525Y369459D02*
G02X1137489Y370622I2015J-1163D01*
G01X1134219Y368672D02*
G03X1135525Y369459I-59J1575D01*
G01X1134090Y368672D02*
X1134219D01*
G01X1132145Y367509D02*
G02X1134090Y368672I2015J-1162D01*
G01X1130824Y366721D02*
G03X1132145Y367509I-44J1575D01*
G01X1130695Y366721D02*
X1130824D01*
G01X1128765Y365559D02*
G02X1130695Y366721I2015J-1163D01*
G01X1127459Y364772D02*
G03X1128765Y365559I-59J1575D01*
G01X1127330Y364772D02*
X1127459D01*
G01X1125385Y363609D02*
G02X1127330Y364772I2015J-1162D01*
G01X1125372Y363586D02*
X1125385Y363609D01*
G01X1124021Y362821D02*
G03X1125372Y363586I0J1575D01*
G01X1123936Y362821D02*
X1124021D01*
G01X1121981Y359376D02*
G02X1123936Y362821I2040J1120D01*
G01X1122006Y359334D02*
X1121981Y359376D01*
G01X1122072Y359218D02*
X1122006Y359334D01*
G01X1124021Y356596D02*
X1122072Y359218D01*
G01X1152721Y401997D02*
Y404578D01*
G01X1151796Y401072D02*
X1152721Y401997D01*
G01X1151016Y401072D02*
X1151796D01*
G01X1149695Y400284D02*
G02X1151016Y401072I1365J-787D01*
G01X1147750Y399121D02*
G03X1149695Y400284I-70J2325D01*
G01X1147636Y399121D02*
X1147750D01*
G01X1146315Y396759D02*
G02X1147636Y399121I1365J787D01*
G01X1146340Y396717D02*
X1146315Y396759D01*
G01Y394434D02*
G03X1146340Y396717I-2015J1164D01*
G01X1146296Y394400D02*
X1146315Y394434D01*
G01Y392859D02*
G02X1146296Y394400I1365J787D01*
G01X1146340Y390576D02*
G03X1146315Y392859I-2040J1119D01*
G01Y390534D02*
X1146340Y390576D01*
G01X1146315Y388962D02*
G02Y390534I1362J786D01*
G01Y386636D02*
G03Y388962I-2015J1163D01*
G01Y385062D02*
G02Y386636I1365J787D01*
G01Y382736D02*
G03Y385062I-2015J1163D01*
G01Y381162D02*
G02Y382736I1365J787D01*
G01X1146340Y378876D02*
G03X1146315Y381162I-2046J1121D01*
G01Y378834D02*
X1146340Y378876D01*
G01X1146296Y378800D02*
X1146315Y378834D01*
G01Y377259D02*
G02X1146296Y378800I1365J787D01*
G01X1144385Y373771D02*
G03X1146315Y377259I-85J2325D01*
G01X1144229Y373771D02*
X1144385D01*
G01X1142935Y372984D02*
G02X1144229Y373771I1365J-787D01*
G01X1140990Y371821D02*
G03X1142935Y372984I-70J2325D01*
G01X1140849Y371821D02*
X1140990D01*
G01X1139555Y371034D02*
G02X1140849Y371821I1365J-787D01*
G01X1137591Y369871D02*
G03X1139555Y371034I-51J2326D01*
G01X1137481Y369871D02*
X1137591D01*
G01X1136175Y369084D02*
G02X1137481Y369871I1365J-788D01*
G01X1134245Y367922D02*
G03X1136175Y369084I-85J2325D01*
G01X1134116Y367922D02*
X1134245D01*
G01X1132795Y367134D02*
G02X1134116Y367922I1365J-787D01*
G01X1130850Y365971D02*
G03X1132795Y367134I-70J2325D01*
G01X1130721Y365971D02*
X1130850D01*
G01X1129415Y365184D02*
G02X1130721Y365971I1365J-788D01*
G01X1127485Y364022D02*
G03X1129415Y365184I-85J2325D01*
G01X1127400Y364022D02*
X1127485D01*
G01X1126049Y363257D02*
G02X1127400Y364022I1351J-810D01*
G01X1125972Y363121D02*
X1126049Y363257D01*
G01X1124021Y360496D02*
X1125972Y363121D01*
G01X1119556Y420156D02*
X1118687Y421025D01*
G01X1119556Y419441D02*
Y420156D01*
G01X1118314Y418199D02*
X1119556Y419441D01*
G01X1118314Y417047D02*
Y418199D01*
G01X1118626Y415884D02*
G02X1118314Y417047I2015J1164D01*
G01X1118645Y414343D02*
G03X1118626Y415884I-1384J754D01*
G01Y414309D02*
X1118645Y414343D01*
G01X1118601Y414267D02*
X1118626Y414309D01*
G01Y411984D02*
G02X1118601Y414267I2015J1164D01*
G01X1118645Y410443D02*
G03X1118626Y411984I-1384J754D01*
G01Y410409D02*
X1118645Y410443D01*
G01X1118601Y410367D02*
X1118626Y410409D01*
G01Y408084D02*
G02X1118601Y410367I2015J1164D01*
G01X1118645Y406543D02*
G03X1118626Y408084I-1384J754D01*
G01Y406509D02*
X1118645Y406543D01*
G01X1118601Y406467D02*
X1118626Y406509D01*
G01Y404184D02*
G02X1118601Y406467I2015J1164D01*
G01X1136665Y411732D02*
X1135756Y412641D01*
G01X1136665Y409545D02*
Y411732D01*
G01X1135236Y408116D02*
X1136665Y409545D01*
G01X1134219Y407672D02*
G03X1135236Y408116I-57J1517D01*
G01X1134090Y407672D02*
X1134219D01*
G01X1132145Y404184D02*
G02X1134090Y407672I2015J1163D01*
G01X1108581Y419509D02*
Y420405D01*
G01X1108869Y418582D02*
X1108581Y419509D01*
G01X1109136Y418209D02*
G03X1108869Y418582I-2015J-1160D01*
G01X1109171Y418149D02*
X1109136Y418209D01*
G01Y415883D02*
G03X1109171Y418149I-2015J1164D01*
G01X1109109Y414357D02*
G02X1109136Y415883I1392J739D01*
G01Y414309D02*
X1109109Y414357D01*
G01X1109171Y414249D02*
X1109136Y414309D01*
G01Y411983D02*
G03X1109171Y414249I-2015J1164D01*
G01X1109109Y410457D02*
G02X1109136Y411983I1392J739D01*
G01X1109171Y410349D02*
X1109109Y410457D01*
G01X1109136Y408083D02*
G03X1109171Y410349I-2015J1164D01*
G01X1109109Y406557D02*
G02X1109136Y408083I1392J739D01*
G01X1109171Y406449D02*
X1109109Y406557D01*
G01X1109136Y404183D02*
G03X1109171Y406449I-2015J1164D01*
G01X1107006Y419480D02*
X1106081Y420405D01*
G01X1107992Y418360D02*
X1107006Y419480D01*
G01X1108486Y416259D02*
G03X1107992Y418360I-1365J788D01*
G01X1108451Y413993D02*
G02X1108486Y416259I2050J1102D01*
G01X1108513Y413885D02*
X1108451Y413993D01*
G01X1108486Y412359D02*
G03X1108513Y413885I-1365J787D01*
G01X1108451Y410093D02*
G02X1108486Y412359I2050J1102D01*
G01X1108513Y409985D02*
X1108451Y410093D01*
G01X1108486Y408459D02*
G03X1108513Y409985I-1365J787D01*
G01X1108451Y406193D02*
G02X1108486Y408459I2050J1102D01*
G01X1108513Y406085D02*
X1108451Y406193D01*
G01X1108486Y404559D02*
G03X1108513Y406085I-1365J787D01*
G01X1137422Y413499D02*
X1138256Y414333D01*
G01X1137422Y409242D02*
Y413499D01*
G01X1135597Y407417D02*
X1137422Y409242D01*
G01X1134245Y406922D02*
G03X1135597Y407417I-85J2325D01*
G01X1134116Y406922D02*
X1134245D01*
G01X1132795Y404559D02*
G02X1134116Y406922I1365J788D01*
G01X1125204Y418958D02*
X1126187Y419941D01*
G01X1125204Y418507D02*
Y418958D01*
G01X1122907Y416210D02*
X1125204Y418507D01*
G01X1122637Y414343D02*
G02X1122907Y416210I1383J753D01*
G01X1122656Y414309D02*
X1122637Y414343D01*
G01X1122681Y414267D02*
X1122656Y414309D01*
G01Y411984D02*
G03X1122681Y414267I-2015J1164D01*
G01X1122637Y410443D02*
G02X1122656Y411984I1384J754D01*
G01Y410409D02*
X1122637Y410443D01*
G01X1122681Y410367D02*
X1122656Y410409D01*
G01Y408084D02*
G03X1122681Y410367I-2015J1164D01*
G01X1122637Y406543D02*
G02X1122656Y408084I1384J754D01*
G01Y406509D02*
X1122637Y406543D01*
G01X1122681Y406467D02*
X1122656Y406509D01*
G01Y404184D02*
G03X1122681Y406467I-2015J1164D01*
G01X1124454Y419174D02*
X1123687Y419941D01*
G01X1124454Y418817D02*
Y419174D01*
G01X1122375Y416738D02*
X1124454Y418817D01*
G01X1121981Y413976D02*
G02X1122375Y416738I2038J1118D01*
G01X1122006Y413934D02*
X1121981Y413976D01*
G01X1122025Y413900D02*
X1122006Y413934D01*
G01Y412359D02*
G03X1122025Y413900I-1365J787D01*
G01X1121981Y410076D02*
G02X1122006Y412359I2040J1119D01*
G01Y410034D02*
X1121981Y410076D01*
G01X1122025Y410000D02*
X1122006Y410034D01*
G01Y408459D02*
G03X1122025Y410000I-1365J787D01*
G01X1121981Y406176D02*
G02X1122006Y408459I2040J1119D01*
G01Y406134D02*
X1121981Y406176D01*
G01X1122025Y406100D02*
X1122006Y406134D01*
G01Y404559D02*
G03X1122025Y406100I-1365J787D01*
G01X1095281Y405102D02*
Y406200D01*
G01X1132488Y413819D02*
X1133600Y414931D01*
G01X1132488Y412891D02*
Y413819D01*
G01X1132795Y412359D02*
X1132488Y412891D01*
G01X1130850Y408871D02*
G03X1132795Y412359I-70J2325D01*
G01X1130721Y408871D02*
X1130850D01*
G01X1129396Y406543D02*
G02X1130721Y408871I1384J753D01*
G01X1129415Y406509D02*
X1129396Y406543D01*
G01X1129440Y406467D02*
X1129415Y406509D01*
G01Y404184D02*
G03X1129440Y406467I-2015J1164D01*
G01X1102137Y418885D02*
X1101081Y419941D01*
G01X1102137Y416760D02*
Y418885D01*
G01X1104794Y414103D02*
X1102137Y416760D01*
G01X1104794Y413147D02*
Y414103D01*
G01X1105106Y411984D02*
G02X1104794Y413147I2015J1164D01*
G01X1105125Y410443D02*
G03X1105106Y411984I-1384J754D01*
G01Y410409D02*
X1105125Y410443D01*
G01X1105081Y410367D02*
X1105106Y410409D01*
G01Y408084D02*
G02X1105081Y410367I2015J1164D01*
G01X1105125Y406543D02*
G03X1105106Y408084I-1384J754D01*
G01Y406509D02*
X1105125Y406543D01*
G01X1105081Y406467D02*
X1105106Y406509D01*
G01Y404184D02*
G02X1105081Y406467I2015J1164D01*
G01X1120306Y420144D02*
X1121187Y421025D01*
G01X1120306Y419128D02*
Y420144D01*
G01X1119065Y417887D02*
X1120306Y419128D01*
G01X1119065Y417047D02*
Y417887D01*
G01X1119276Y416259D02*
G02X1119065Y417047I1365J788D01*
G01X1119301Y413976D02*
G03X1119276Y416259I-2040J1119D01*
G01Y413934D02*
X1119301Y413976D01*
G01X1119257Y413900D02*
X1119276Y413934D01*
G01Y412359D02*
G02X1119257Y413900I1365J787D01*
G01X1119301Y410076D02*
G03X1119276Y412359I-2040J1119D01*
G01Y410034D02*
X1119301Y410076D01*
G01X1119257Y410000D02*
X1119276Y410034D01*
G01Y408459D02*
G02X1119257Y410000I1365J787D01*
G01X1119301Y406176D02*
G03X1119276Y408459I-2040J1119D01*
G01Y406134D02*
X1119301Y406176D01*
G01X1119257Y406100D02*
X1119276Y406134D01*
G01Y404559D02*
G02X1119257Y406100I1365J787D01*
G01X1148959Y409135D02*
Y410343D01*
G01X1148339Y408515D02*
X1148959Y409135D01*
G01X1148339Y404515D02*
Y408515D01*
G01X1147595Y403771D02*
X1148339Y404515D01*
G01X1149453Y408568D02*
X1150734D01*
G01X1149089Y408204D02*
X1149453Y408568D01*
G01X1149089Y404204D02*
Y408204D01*
G01X1147917Y403032D02*
X1149089Y404204D01*
G01X1147622Y403021D02*
X1147917Y403032D01*
G01X1147272Y402968D02*
G02X1147622Y403021I409J-1522D01*
G01X1147273Y402968D02*
X1147272D01*
G01X1097856Y405716D02*
X1098631Y406491D01*
G01X1096623Y405716D02*
X1097856D01*
G01X1096338Y405431D02*
X1096623Y405716D01*
G01X1095616Y404182D02*
X1096338Y405431D01*
G01X1102887Y419247D02*
X1103800Y420160D01*
G01X1102887Y417073D02*
Y419247D01*
G01X1105545Y414415D02*
X1102887Y417073D01*
G01X1105545Y413147D02*
Y414415D01*
G01X1105756Y412359D02*
G02X1105545Y413147I1365J788D01*
G01X1105781Y410076D02*
G03X1105756Y412359I-2040J1119D01*
G01Y410034D02*
X1105781Y410076D01*
G01X1105737Y410000D02*
X1105756Y410034D01*
G01Y408459D02*
G02X1105737Y410000I1365J787D01*
G01X1105781Y406176D02*
G03X1105756Y408459I-2040J1119D01*
G01Y406134D02*
X1105781Y406176D01*
G01X1105737Y406100D02*
X1105756Y406134D01*
G01Y404559D02*
G02X1105737Y406100I1365J787D01*
G01X1131700Y413643D02*
X1130756Y414587D01*
G01X1131700Y412429D02*
Y413643D01*
G01X1132145Y411984D02*
X1131700Y412429D01*
G01X1130824Y409621D02*
G03X1132145Y411984I-44J1575D01*
G01X1130695Y409621D02*
X1130824D01*
G01X1128740Y406176D02*
G02X1130695Y409621I2040J1120D01*
G01X1128765Y406134D02*
X1128740Y406176D01*
G01X1128784Y406100D02*
X1128765Y406134D01*
G01Y404559D02*
G03X1128784Y406100I-1365J787D01*
G01X1152559Y405477D02*
Y406743D01*
G01X1151971Y404889D02*
X1152559Y405477D01*
G01X1153046Y404903D02*
X1154399D01*
G01X1152721Y404578D02*
X1153046Y404903D01*
G01X1200215Y213871D02*
X1201013Y213073D01*
G01X1198309Y213871D02*
X1200215D01*
G01X1196364Y215034D02*
G03X1198309Y213871I2015J1162D01*
G01X1195043Y215822D02*
G02X1196364Y215034I-44J-1575D01*
G01X1194914Y215822D02*
X1195043D01*
G01X1192984Y216984D02*
G03X1194914Y215822I2015J1163D01*
G01X1191678Y217771D02*
G02X1192984Y216984I-59J-1575D01*
G01X1191549Y217771D02*
X1191678D01*
G01X1189604Y218934D02*
G03X1191549Y217771I2015J1162D01*
G01X1200545Y214621D02*
X1202179Y212987D01*
G01X1198335Y214621D02*
X1200545D01*
G01X1197014Y215409D02*
G03X1198335Y214621I1365J787D01*
G01X1195069Y216572D02*
G02X1197014Y215409I-70J-2325D01*
G01X1194940Y216572D02*
X1195069D01*
G01X1193634Y217359D02*
G03X1194940Y216572I1365J788D01*
G01X1191704Y218521D02*
G02X1193634Y217359I-85J-2325D01*
G01X1186874D02*
G03X1184944Y218521I-2015J-1163D01*
G01X1188180Y216572D02*
G02X1186874Y217359I59J1575D01*
G01X1188309Y216572D02*
X1188180D01*
G01X1190254Y215409D02*
G03X1188309Y216572I-2015J-1162D01*
G01X1191575Y214621D02*
G02X1190254Y215409I44J1575D01*
G01X1191704Y214621D02*
X1191575D01*
G01X1193634Y213459D02*
G03X1191704Y214621I-2015J-1163D01*
G01X1194940Y212672D02*
G02X1193634Y213459I59J1575D01*
G01X1195050Y212672D02*
X1194940D01*
G01X1197014Y211509D02*
G03X1195050Y212672I-2015J-1163D01*
G01X1197495Y210992D02*
G02X1197014Y211509I884J1305D01*
G01X1197678Y210812D02*
X1197495Y210992D01*
G01X1197812Y210814D02*
X1197678Y210812D01*
G01X1199815Y208816D02*
X1197812Y210814D01*
G01X1180114Y217359D02*
G03X1178184Y218521I-2015J-1163D01*
G01X1181420Y216572D02*
G02X1180114Y217359I59J1575D01*
G01X1181549Y216572D02*
X1181420D01*
G01X1183494Y215409D02*
G03X1181549Y216572I-2015J-1162D01*
G01X1184815Y214621D02*
G02X1183494Y215409I44J1575D01*
G01X1184944Y214621D02*
X1184815D01*
G01X1186874Y213459D02*
G03X1184944Y214621I-2015J-1163D01*
G01X1188180Y212672D02*
G02X1186874Y213459I59J1575D01*
G01X1188290Y212672D02*
X1188180D01*
G01X1190254Y211509D02*
G03X1188290Y212672I-2015J-1163D01*
G01X1191548Y210722D02*
G02X1190254Y211509I71J1574D01*
G01X1191689Y210722D02*
X1191548D01*
G01X1193634Y209559D02*
G03X1191689Y210722I-2015J-1162D01*
G01X1193885Y209232D02*
G02X1193634Y209559I1114J1115D01*
G01X1193964Y209159D02*
G02X1193885Y209232I885J1037D01*
G01X1194115Y209043D02*
G02X1193964Y209159I883J1305D01*
G01X1194298Y208863D02*
X1194115Y209043D01*
G01X1194432Y208865D02*
X1194298Y208863D01*
G01X1196435Y206867D02*
X1194432Y208865D01*
G01X1202500Y200802D02*
X1196435Y206867D01*
G01X1202500Y194343D02*
Y200802D01*
G01X1238448Y144006D02*
X1202500Y179954D01*
G01X1178029Y217771D02*
G02X1176084Y218934I70J2325D01*
G01X1178158Y217771D02*
X1178029D01*
G01X1179464Y216984D02*
G03X1178158Y217771I-1365J-788D01*
G01X1181394Y215822D02*
G02X1179464Y216984I85J2325D01*
G01X1181523Y215822D02*
X1181394D01*
G01X1182844Y215034D02*
G03X1181523Y215822I-1365J-787D01*
G01X1184789Y213871D02*
G02X1182844Y215034I70J2325D01*
G01X1184918Y213871D02*
X1184789D01*
G01X1186224Y213084D02*
G03X1184918Y213871I-1365J-788D01*
G01X1188188Y211921D02*
G02X1186224Y213084I51J2326D01*
G01X1188283Y211921D02*
X1188188D01*
G01X1189604Y211133D02*
G03X1188283Y211921I-1365J-787D01*
G01X1191534Y209971D02*
G02X1189604Y211133I85J2325D01*
G01X1191690Y209971D02*
X1191534D01*
G01X1192984Y209184D02*
G03X1191690Y209971I-1365J-787D01*
G01X1193582Y208501D02*
G02X1192984Y209184I1417J1844D01*
G01X1193764Y208321D02*
X1193582Y208501D01*
G01X1193764Y207908D02*
Y208321D01*
G01X1196149Y205523D02*
X1193764Y207908D01*
G01X1184789Y217771D02*
G02X1182844Y218934I70J2325D01*
G01X1184918Y217771D02*
X1184789D01*
G01X1186224Y216984D02*
G03X1184918Y217771I-1365J-788D01*
G01X1188154Y215822D02*
G02X1186224Y216984I85J2325D01*
G01X1188283Y215822D02*
X1188154D01*
G01X1189604Y215034D02*
G03X1188283Y215822I-1365J-787D01*
G01X1191549Y213871D02*
G02X1189604Y215034I70J2325D01*
G01X1191678Y213871D02*
X1191549D01*
G01X1192984Y213084D02*
G03X1191678Y213871I-1365J-788D01*
G01X1194948Y211921D02*
G02X1192984Y213084I51J2326D01*
G01X1195043Y211921D02*
X1194948D01*
G01X1196364Y211133D02*
G03X1195043Y211921I-1365J-787D01*
G01X1196962Y210450D02*
G02X1196364Y211133I1417J1844D01*
G01X1197144Y210270D02*
X1196962Y210450D01*
G01X1197145Y210136D02*
X1197144Y210270D01*
G01X1197943Y209344D02*
X1197145Y210136D01*
G01X1170186Y238931D02*
X1171339Y239596D01*
G01X1170103Y238621D02*
X1170186Y238931D01*
G01X1171339Y238021D02*
G02X1170103Y238621I1J1575D01*
G01X1171424Y238021D02*
X1171339D01*
G01X1173354Y236859D02*
G03X1171424Y238021I-2015J-1163D01*
G01X1174660Y236072D02*
G02X1173354Y236859I59J1575D01*
G01X1174770Y236072D02*
X1174660D01*
G01X1176734Y234909D02*
G03X1174770Y236072I-2015J-1163D01*
G01X1178028Y234122D02*
G02X1176734Y234909I71J1574D01*
G01X1178170Y234122D02*
X1178028D01*
G01X1179464Y234909D02*
G02X1178170Y234122I-1365J787D01*
G01X1183494Y234909D02*
G03X1179464I-2015J-1163D01*
G01X1184788Y234122D02*
G02X1183494Y234909I71J1574D01*
G01X1184930Y234122D02*
X1184788D01*
G01X1186224Y234909D02*
G02X1184930Y234122I-1365J787D01*
G01X1188188Y236072D02*
G03X1186224Y234909I51J-2326D01*
G01X1188290Y236072D02*
X1188188D01*
G01X1190254Y234909D02*
G03X1188290Y236072I-2015J-1163D01*
G01X1191548Y234122D02*
G02X1190254Y234909I71J1574D01*
G01X1191690Y234122D02*
X1191548D01*
G01X1192984Y234909D02*
G02X1191690Y234122I-1365J787D01*
G01X1197014Y234909D02*
G03X1192984I-2015J-1163D01*
G01X1198308Y234122D02*
G02X1197014Y234909I71J1574D01*
G01X1198450Y234122D02*
X1198308D01*
G01X1199744Y234909D02*
G02X1198450Y234122I-1365J787D01*
G01X1203774Y234909D02*
G03X1199744I-2015J-1163D01*
G01X1205068Y234122D02*
G02X1203774Y234909I71J1574D01*
G01X1205210Y234122D02*
X1205068D01*
G01X1206504Y234909D02*
G02X1205210Y234122I-1365J787D01*
G01X1208468Y236072D02*
G03X1206504Y234909I51J-2326D01*
G01X1214438Y236072D02*
X1208468D01*
G01X1215180Y235330D02*
X1214438Y236072D01*
G01X1226760Y235330D02*
X1215180D01*
G01X1180325Y256481D02*
X1181479Y257147D01*
G01X1180242Y256171D02*
X1180325Y256481D01*
G01X1181420Y255572D02*
G02X1180242Y256171I60J1575D01*
G01X1181549Y255572D02*
X1181420D01*
G01X1183494Y254409D02*
G03X1181549Y255572I-2015J-1162D01*
G01X1184815Y253621D02*
G02X1183494Y254409I44J1575D01*
G01X1184944Y253621D02*
X1184815D01*
G01X1186874Y252459D02*
G03X1184944Y253621I-2015J-1163D01*
G01X1188180Y251672D02*
G02X1186874Y252459I59J1575D01*
G01X1188298Y251672D02*
X1188180D01*
G01X1189604Y252459D02*
G02X1188298Y251672I-1365J788D01*
G01X1191534Y253621D02*
G03X1189604Y252459I85J-2325D01*
G01X1191704Y253621D02*
X1191534D01*
G01X1193634Y252459D02*
G03X1191704Y253621I-2015J-1163D01*
G01X1194940Y251672D02*
G02X1193634Y252459I59J1575D01*
G01X1195058Y251672D02*
X1194940D01*
G01X1196364Y252459D02*
G02X1195058Y251672I-1365J788D01*
G01X1198294Y253621D02*
G03X1196364Y252459I85J-2325D01*
G01X1198464Y253621D02*
X1198294D01*
G01X1200394Y252459D02*
G03X1198464Y253621I-2015J-1163D01*
G01X1201700Y251672D02*
G02X1200394Y252459I59J1575D01*
G01X1201829Y251672D02*
X1201700D01*
G01X1203774Y250509D02*
G03X1201829Y251672I-2015J-1162D01*
G01X1205068Y249722D02*
G02X1203774Y250509I71J1574D01*
G01X1205795Y249722D02*
X1205068D01*
G01X1206254Y250181D02*
X1205795Y249722D01*
G01X1206504Y250509D02*
G02X1206254Y250181I-1368J783D01*
G01X1208449Y251672D02*
G03X1206504Y250509I70J-2325D01*
G01X1209317Y251672D02*
X1208449D01*
G01X1210691Y250498D02*
G03X1209317Y251672I-2172J-1151D01*
G01X1211544Y249721D02*
G02X1210691Y250498I655J1575D01*
G01X1213760Y249721D02*
X1211544D01*
G01X1214459Y250420D02*
X1213760Y249721D01*
G01X1224080Y250420D02*
X1214459D01*
G01X1176945Y258431D02*
X1178099Y259096D01*
G01X1176862Y258121D02*
X1176945Y258431D01*
G01X1179464Y258309D02*
G02X1176862Y258121I-1365J787D01*
G01X1183494Y258309D02*
G03X1179464I-2015J-1162D01*
G01X1184815Y257521D02*
G02X1183494Y258309I44J1575D01*
G01X1184944Y257521D02*
X1184815D01*
G01X1186874Y256359D02*
G03X1184944Y257521I-2015J-1163D01*
G01X1189604Y256359D02*
G02X1186874I-1365J788D01*
G01X1193634D02*
G03X1189604I-2015J-1163D01*
G01X1196364D02*
G02X1193634I-1365J788D01*
G01X1200394D02*
G03X1196364I-2015J-1163D01*
G01X1201700Y255572D02*
G02X1200394Y256359I59J1575D01*
G01X1201829Y255572D02*
X1201700D01*
G01X1203774Y254409D02*
G03X1201829Y255572I-2015J-1162D01*
G01X1206504Y254409D02*
G02X1203774I-1365J787D01*
G01X1208521Y255574D02*
G03X1206504Y254409I0J-2328D01*
G01X1209936Y255574D02*
X1208521D01*
G01X1175873Y257812D02*
X1174719Y257147D01*
G01X1176225Y257717D02*
X1175873Y257812D01*
G01X1178029Y256771D02*
G02X1176225Y257717I69J2325D01*
G01X1180114Y257934D02*
G02X1178029Y256771I-2016J1164D01*
G01X1182844Y257934D02*
G03X1180114I-1365J-787D01*
G01X1184789Y256771D02*
G02X1182844Y257934I70J2325D01*
G01X1184918Y256771D02*
X1184789D01*
G01X1186224Y255984D02*
G03X1184918Y256771I-1365J-788D01*
G01X1190254Y255984D02*
G02X1186224I-2015J1163D01*
G01X1192984D02*
G03X1190254I-1365J-788D01*
G01X1197014D02*
G02X1192984I-2015J1163D01*
G01X1199744D02*
G03X1197014I-1365J-788D01*
G01X1201674Y254822D02*
G02X1199744Y255984I85J2325D01*
G01X1201803Y254822D02*
X1201674D01*
G01X1203124Y254034D02*
G03X1201803Y254822I-1365J-787D01*
G01X1207154Y254034D02*
G02X1203124I-2015J1162D01*
G01X1208475Y254822D02*
G03X1207154Y254034I44J-1575D01*
G01X1221387Y254822D02*
X1208475D01*
G01X1214094Y271303D02*
X1216362Y273571D01*
G01X1211182Y236940D02*
X1226250D01*
G01X1210424Y237698D02*
X1211182Y236940D01*
G01X1210027Y238445D02*
X1210424Y237698D01*
G01X1209174Y239222D02*
G02X1210027Y238445I-655J-1575D01*
G01X1208475Y239222D02*
X1209174D01*
G01X1207154Y238434D02*
G02X1208475Y239222I1365J-787D01*
G01X1205209Y237271D02*
G03X1207154Y238434I-70J2325D01*
G01X1205069Y237271D02*
X1205209D01*
G01X1203124Y238434D02*
G03X1205069Y237271I2015J1162D01*
G01X1201803Y239222D02*
G02X1203124Y238434I-44J-1575D01*
G01X1201715Y239222D02*
X1201803D01*
G01X1200394Y238434D02*
G02X1201715Y239222I1365J-787D01*
G01X1198449Y237271D02*
G03X1200394Y238434I-70J2325D01*
G01X1198309Y237271D02*
X1198449D01*
G01X1196364Y238434D02*
G03X1198309Y237271I2015J1162D01*
G01X1193634Y238434D02*
G02X1196364I1365J-787D01*
G01X1191689Y237271D02*
G03X1193634Y238434I-70J2325D01*
G01X1191549Y237271D02*
X1191689D01*
G01X1189604Y238434D02*
G03X1191549Y237271I2015J1162D01*
G01X1186874Y238434D02*
G02X1189604I1365J-787D01*
G01X1184929Y237271D02*
G03X1186874Y238434I-70J2325D01*
G01X1184789Y237271D02*
X1184929D01*
G01X1182844Y238434D02*
G03X1184789Y237271I2015J1162D01*
G01X1180114Y238434D02*
G02X1182844I1365J-787D01*
G01X1178169Y237271D02*
G03X1180114Y238434I-70J2325D01*
G01X1178029Y237271D02*
X1178169D01*
G01X1176084Y238434D02*
G03X1178029Y237271I2015J1162D01*
G01X1174763Y239222D02*
G02X1176084Y238434I-44J-1575D01*
G01X1174634Y239222D02*
X1174763D01*
G01X1172704Y240384D02*
G03X1174634Y239222I2015J1163D01*
G01X1171398Y241171D02*
G02X1172704Y240384I-59J-1575D01*
G01X1171269Y241171D02*
X1171398D01*
G01X1169324Y242334D02*
G03X1171269Y241171I2015J1162D01*
G01X1169311Y242357D02*
X1169324Y242334D01*
G01X1168187Y243105D02*
G02X1169311Y242357I-226J-1559D01*
G01X1167960Y242878D02*
X1168187Y243105D01*
G01X1167960Y241547D02*
Y242878D01*
G01X1211401Y248971D02*
X1224258D01*
G01X1210027Y250145D02*
G03X1211401Y248971I2172J1151D01*
G01X1209174Y250922D02*
G02X1210027Y250145I-655J-1575D01*
G01X1208475Y250922D02*
X1209174D01*
G01X1207154Y250134D02*
G02X1208475Y250922I1365J-787D01*
G01X1206757Y249616D02*
G03X1207154Y250134I-1761J1761D01*
G01X1206113Y248972D02*
X1206757Y249616D01*
G01X1205041Y248972D02*
X1206113D01*
G01X1203124Y250134D02*
G03X1205041Y248972I2015J1162D01*
G01X1201803Y250922D02*
G02X1203124Y250134I-44J-1575D01*
G01X1201674Y250922D02*
X1201803D01*
G01X1199744Y252084D02*
G03X1201674Y250922I2015J1163D01*
G01X1198438Y252871D02*
G02X1199744Y252084I-59J-1575D01*
G01X1198320Y252871D02*
X1198438D01*
G01X1197014Y252084D02*
G02X1198320Y252871I1365J-788D01*
G01X1195084Y250922D02*
G03X1197014Y252084I-85J2325D01*
G01X1194914Y250922D02*
X1195084D01*
G01X1192984Y252084D02*
G03X1194914Y250922I2015J1163D01*
G01X1191678Y252871D02*
G02X1192984Y252084I-59J-1575D01*
G01X1191560Y252871D02*
X1191678D01*
G01X1190254Y252084D02*
G02X1191560Y252871I1365J-788D01*
G01X1188324Y250922D02*
G03X1190254Y252084I-85J2325D01*
G01X1188154Y250922D02*
X1188324D01*
G01X1186224Y252084D02*
G03X1188154Y250922I2015J1163D01*
G01X1184918Y252871D02*
G02X1186224Y252084I-59J-1575D01*
G01X1184789Y252871D02*
X1184918D01*
G01X1182844Y254034D02*
G03X1184789Y252871I2015J1162D01*
G01X1181523Y254822D02*
G02X1182844Y254034I-44J-1575D01*
G01X1181394Y254822D02*
X1181523D01*
G01X1179605Y255767D02*
G03X1181394Y254822I1873J1380D01*
G01X1179253Y255862D02*
X1179605Y255767D01*
G01X1178099Y255196D02*
X1179253Y255862D01*
G01X1215602Y241116D02*
X1224295D01*
G01X1214797Y241921D02*
X1215602Y241116D01*
G01X1214220Y241921D02*
X1214797D01*
G01X1214219Y241922D02*
X1214220Y241921D01*
G01X1211455Y241922D02*
X1214219D01*
G01X1209412Y243965D02*
X1211455Y241922D01*
G01X1209411Y243965D02*
X1209412D01*
G01X1209349Y244027D02*
X1209411Y243965D01*
G01X1207708Y244027D02*
X1209349D01*
G01X1206873Y243192D02*
X1207708Y244027D01*
G01X1206608Y242874D02*
G02X1206873Y243192I1912J-1324D01*
G01X1206504Y242709D02*
G02X1206608Y242874I2018J-1157D01*
G01X1205183Y241921D02*
G03X1206504Y242709I-44J1575D01*
G01X1205095Y241921D02*
X1205183D01*
G01X1203774Y242709D02*
G03X1205095Y241921I1365J787D01*
G01X1199744Y242709D02*
G02X1203774I2015J-1162D01*
G01X1198423Y241921D02*
G03X1199744Y242709I-44J1575D01*
G01X1198335Y241921D02*
X1198423D01*
G01X1197014Y242709D02*
G03X1198335Y241921I1365J787D01*
G01X1192984Y242709D02*
G02X1197014I2015J-1162D01*
G01X1191663Y241921D02*
G03X1192984Y242709I-44J1575D01*
G01X1191575Y241921D02*
X1191663D01*
G01X1190254Y242709D02*
G03X1191575Y241921I1365J787D01*
G01X1186224Y242709D02*
G02X1190254I2015J-1162D01*
G01X1184903Y241921D02*
G03X1186224Y242709I-44J1575D01*
G01X1184815Y241921D02*
X1184903D01*
G01X1183494Y242709D02*
G03X1184815Y241921I1365J787D01*
G01X1181549Y243872D02*
G02X1183494Y242709I-70J-2325D01*
G01X1181409Y243872D02*
X1181549D01*
G01X1179464Y242709D02*
G02X1181409Y243872I2015J-1162D01*
G01X1178143Y241921D02*
G03X1179464Y242709I-44J1575D01*
G01X1178055Y241921D02*
X1178143D01*
G01X1176734Y242709D02*
G03X1178055Y241921I1365J787D01*
G01X1174976Y243859D02*
G02X1176734Y242709I-257J-2312D01*
G01X1174719Y244116D02*
X1174976Y243859D01*
G01X1174719Y245447D02*
Y244116D01*
G01X1169113Y238312D02*
X1167960Y237647D01*
G01X1169465Y238217D02*
X1169113Y238312D01*
G01X1171269Y237271D02*
G02X1169465Y238217I69J2325D01*
G01X1171398Y237271D02*
X1171269D01*
G01X1172704Y236484D02*
G03X1171398Y237271I-1365J-788D01*
G01X1174668Y235321D02*
G02X1172704Y236484I51J2326D01*
G01X1174763Y235321D02*
X1174668D01*
G01X1176084Y234533D02*
G03X1174763Y235321I-1365J-787D01*
G01X1178014Y233371D02*
G02X1176084Y234533I85J2325D01*
G01X1178184Y233371D02*
X1178014D01*
G01X1180114Y234533D02*
G02X1178184Y233371I-2015J1163D01*
G01X1182844Y234533D02*
G03X1180114I-1365J-787D01*
G01X1184774Y233371D02*
G02X1182844Y234533I85J2325D01*
G01X1184944Y233371D02*
X1184774D01*
G01X1186874Y234533D02*
G02X1184944Y233371I-2015J1163D01*
G01X1188195Y235321D02*
G03X1186874Y234533I44J-1575D01*
G01X1188283Y235321D02*
X1188195D01*
G01X1189604Y234533D02*
G03X1188283Y235321I-1365J-787D01*
G01X1191534Y233371D02*
G02X1189604Y234533I85J2325D01*
G01X1191704Y233371D02*
X1191534D01*
G01X1193634Y234533D02*
G02X1191704Y233371I-2015J1163D01*
G01X1196364Y234533D02*
G03X1193634I-1365J-787D01*
G01X1198294Y233371D02*
G02X1196364Y234533I85J2325D01*
G01X1198464Y233371D02*
X1198294D01*
G01X1200394Y234533D02*
G02X1198464Y233371I-2015J1163D01*
G01X1203124Y234533D02*
G03X1200394I-1365J-787D01*
G01X1205054Y233371D02*
G02X1203124Y234533I85J2325D01*
G01X1205224Y233371D02*
X1205054D01*
G01X1207154Y234533D02*
G02X1205224Y233371I-2015J1163D01*
G01X1208475Y235321D02*
G03X1207154Y234533I44J-1575D01*
G01X1211306Y235321D02*
X1208475D01*
G01X1211876Y234751D02*
X1211306Y235321D01*
G01X1214219Y234751D02*
X1211876D01*
G01X1215159Y233811D02*
X1214219Y234751D01*
G01X1227911Y233811D02*
X1215159D01*
G01X1188283Y219722D02*
G02X1189604Y218934I-44J-1575D01*
G01X1188154Y219722D02*
X1188283D01*
G01X1186224Y220884D02*
G03X1188154Y219722I2015J1163D01*
G01X1184918Y221671D02*
G02X1186224Y220884I-59J-1575D01*
G01X1184789Y221671D02*
X1184918D01*
G01X1182844Y222834D02*
G03X1184789Y221671I2015J1162D01*
G01X1181523Y223622D02*
G02X1182844Y222834I-44J-1575D01*
G01X1181394Y223622D02*
X1181523D01*
G01X1179464Y224784D02*
G03X1181394Y223622I2015J1163D01*
G01X1178158Y225571D02*
G02X1179464Y224784I-59J-1575D01*
G01X1178029Y225571D02*
X1178158D01*
G01X1176084Y226734D02*
G03X1178029Y225571I2015J1162D01*
G01X1174763Y227522D02*
G02X1176084Y226734I-44J-1575D01*
G01X1174634Y227522D02*
X1174763D01*
G01X1172704Y228684D02*
G03X1174634Y227522I2015J1163D01*
G01X1171398Y229471D02*
G02X1172704Y228684I-59J-1575D01*
G01X1171288Y229471D02*
X1171398D01*
G01X1169324Y230634D02*
G03X1171288Y229471I2015J1163D01*
G01X1168008Y231421D02*
G02X1169324Y230634I-48J-1574D01*
G01X1167890Y231421D02*
X1168008D01*
G01X1165945Y232584D02*
G03X1167890Y231421I2015J1162D01*
G01X1164651Y233371D02*
G02X1165945Y232584I-71J-1574D01*
G01X1164495Y233371D02*
X1164651D01*
G01X1162565Y234533D02*
G03X1164495Y233371I2015J1163D01*
G01X1162565Y236859D02*
G03Y234533I2015J-1163D01*
G01X1162584Y238400D02*
G02X1162565Y236859I-1384J-754D01*
G01Y238434D02*
X1162584Y238400D01*
G01X1162540Y238476D02*
X1162565Y238434D01*
G01Y240759D02*
G03X1162540Y238476I2015J-1164D01*
G01X1162584Y242300D02*
G02X1162565Y240759I-1384J-754D01*
G01Y242334D02*
X1162584Y242300D01*
G01X1162540Y242376D02*
X1162565Y242334D01*
G01X1162448Y244429D02*
G03X1162540Y242376I2131J-933D01*
G01X1162354Y244781D02*
X1162448Y244429D01*
G01X1161200Y245447D02*
X1162354Y244781D01*
G01X1191575Y218521D02*
X1191704D01*
G01X1190254Y219309D02*
G03X1191575Y218521I1365J787D01*
G01X1188309Y220472D02*
G02X1190254Y219309I-70J-2325D01*
G01X1188180Y220472D02*
X1188309D01*
G01X1186874Y221259D02*
G03X1188180Y220472I1365J788D01*
G01X1184944Y222421D02*
G02X1186874Y221259I-85J-2325D01*
G01X1184815Y222421D02*
X1184944D01*
G01X1183494Y223209D02*
G03X1184815Y222421I1365J787D01*
G01X1181549Y224372D02*
G02X1183494Y223209I-70J-2325D01*
G01X1181420Y224372D02*
X1181549D01*
G01X1180114Y225159D02*
G03X1181420Y224372I1365J788D01*
G01X1178184Y226321D02*
G02X1180114Y225159I-85J-2325D01*
G01X1178055Y226321D02*
X1178184D01*
G01X1176734Y227109D02*
G03X1178055Y226321I1365J787D01*
G01X1174789Y228272D02*
G02X1176734Y227109I-70J-2325D01*
G01X1174660Y228272D02*
X1174789D01*
G01X1173354Y229059D02*
G03X1174660Y228272I1365J788D01*
G01X1171390Y230222D02*
G02X1173354Y229059I-51J-2326D01*
G01X1171339Y230222D02*
X1171390D01*
G01X1169988Y230987D02*
G03X1171339Y230222I1351J810D01*
G01X1169975Y231010D02*
X1169988Y230987D01*
G01X1168045Y232172D02*
G02X1169975Y231010I-85J-2325D01*
G01X1167889Y232172D02*
X1168045D01*
G01X1166595Y232959D02*
G03X1167889Y232172I1365J787D01*
G01X1164650Y234122D02*
G02X1166595Y232959I-70J-2325D01*
G01X1164509Y234122D02*
X1164650D01*
G01X1163215Y236484D02*
G03X1164509Y234122I1365J-788D01*
G01X1163240Y238767D02*
G02X1163215Y236484I-2040J-1119D01*
G01Y238809D02*
X1163240Y238767D01*
G01X1163196Y238843D02*
X1163215Y238809D01*
G01Y240384D02*
G03X1163196Y238843I1365J-787D01*
G01X1163240Y242667D02*
G02X1163215Y240384I-2040J-1119D01*
G01Y242709D02*
X1163240Y242667D01*
G01X1163196Y242743D02*
X1163215Y242709D01*
G01X1163116Y244078D02*
G03X1163196Y242743I1465J-582D01*
G01X1163572Y244078D02*
X1163116D01*
G01X1164580Y243496D02*
X1163572Y244078D01*
G01X1159511Y245094D02*
G02X1157820Y247396I8398J7941D01*
G01X1159860Y242376D02*
G03X1159511Y245094I-2040J1119D01*
G01X1159835Y242334D02*
X1159860Y242376D01*
G01X1159816Y242300D02*
X1159835Y242334D01*
G01Y240759D02*
G02X1159816Y242300I1365J787D01*
G01X1159860Y238476D02*
G03X1159835Y240759I-2040J1119D01*
G01Y238434D02*
X1159860Y238476D01*
G01X1159816Y238400D02*
X1159835Y238434D01*
G01Y236859D02*
G02X1159816Y238400I1365J787D01*
G01X1159835Y234533D02*
G03Y236859I-2015J1163D01*
G01X1161129Y232172D02*
G02X1159835Y234533I71J1574D01*
G01X1161285Y232172D02*
X1161129D01*
G01X1163215Y231010D02*
G03X1161285Y232172I-2015J-1163D01*
G01X1164536Y230222D02*
G02X1163215Y231010I44J1575D01*
G01X1164631Y230222D02*
X1164536D01*
G01X1166595Y229059D02*
G03X1164631Y230222I-2015J-1163D01*
G01X1167901Y228272D02*
G02X1166595Y229059I59J1575D01*
G01X1168030Y228272D02*
X1167901D01*
G01X1169975Y227109D02*
G03X1168030Y228272I-2015J-1162D01*
G01X1169988Y227086D02*
X1169975Y227109D01*
G01X1171339Y226321D02*
G02X1169988Y227086I0J1575D01*
G01X1171424Y226321D02*
X1171339D01*
G01X1173354Y225159D02*
G03X1171424Y226321I-2015J-1163D01*
G01X1174660Y224372D02*
G02X1173354Y225159I59J1575D01*
G01X1174789Y224372D02*
X1174660D01*
G01X1176734Y223209D02*
G03X1174789Y224372I-2015J-1162D01*
G01X1178055Y222421D02*
G02X1176734Y223209I44J1575D01*
G01X1178184Y222421D02*
X1178055D01*
G01X1180114Y221259D02*
G03X1178184Y222421I-2015J-1163D01*
G01X1181420Y220472D02*
G02X1180114Y221259I59J1575D01*
G01X1181549Y220472D02*
X1181420D01*
G01X1183494Y219309D02*
G03X1181549Y220472I-2015J-1162D01*
G01X1184815Y218521D02*
G02X1183494Y219309I44J1575D01*
G01X1184944Y218521D02*
X1184815D01*
G01X1215319Y239761D02*
X1225061D01*
G01X1213908Y241172D02*
X1215319Y239761D01*
G01X1211144Y241172D02*
X1213908D01*
G01X1209101Y243215D02*
X1211144Y241172D01*
G01X1207957Y243215D02*
X1209101D01*
G01X1207404Y242662D02*
X1207957Y243215D01*
G01X1207154Y242334D02*
G02X1207404Y242662I1368J-783D01*
G01X1205209Y241171D02*
G03X1207154Y242334I-70J2325D01*
G01X1205069Y241171D02*
X1205209D01*
G01X1203124Y242334D02*
G03X1205069Y241171I2015J1162D01*
G01X1200394Y242334D02*
G02X1203124I1365J-787D01*
G01X1198449Y241171D02*
G03X1200394Y242334I-70J2325D01*
G01X1198309Y241171D02*
X1198449D01*
G01X1196364Y242334D02*
G03X1198309Y241171I2015J1162D01*
G01X1193634Y242334D02*
G02X1196364I1365J-787D01*
G01X1191689Y241171D02*
G03X1193634Y242334I-70J2325D01*
G01X1191549Y241171D02*
X1191689D01*
G01X1189604Y242334D02*
G03X1191549Y241171I2015J1162D01*
G01X1186874Y242334D02*
G02X1189604I1365J-787D01*
G01X1184929Y241171D02*
G03X1186874Y242334I-70J2325D01*
G01X1184789Y241171D02*
X1184929D01*
G01X1182844Y242334D02*
G03X1184789Y241171I2015J1162D01*
G01X1181523Y243122D02*
G02X1182844Y242334I-44J-1575D01*
G01X1181435Y243122D02*
X1181523D01*
G01X1180114Y242334D02*
G02X1181435Y243122I1365J-787D01*
G01X1178169Y241171D02*
G03X1180114Y242334I-70J2325D01*
G01X1178029Y241171D02*
X1178169D01*
G01X1176084Y242334D02*
G03X1178029Y241171I2015J1162D01*
G01X1174763Y243122D02*
G02X1176084Y242334I-44J-1575D01*
G01X1174634Y243122D02*
X1174763D01*
G01X1172704Y244284D02*
G03X1174634Y243122I2015J1163D01*
G01X1171398Y245071D02*
G02X1172704Y244284I-59J-1575D01*
G01X1171269Y245071D02*
X1171398D01*
G01X1169324Y246234D02*
G03X1171269Y245071I2015J1162D01*
G01X1169289Y246294D02*
X1169324Y246234D01*
G01X1169207Y248330D02*
G03X1169289Y246294I2131J-934D01*
G01X1169113Y248682D02*
X1169207Y248330D01*
G01X1167960Y249347D02*
X1169113Y248682D01*
G01X1210134Y271169D02*
X1210240Y271275D01*
G01X1208262Y271169D02*
X1210134D01*
G01X1206504Y270009D02*
G02X1208262Y271169I2036J-1174D01*
G01X1203774Y270009D02*
G03X1206504I1365J787D01*
G01X1199744D02*
G02X1203774I2015J-1162D01*
G01X1198450Y269222D02*
G03X1199744Y270009I-71J1574D01*
G01X1198308Y269222D02*
X1198450D01*
G01X1197014Y270009D02*
G03X1198308Y269222I1365J787D01*
G01X1195069Y271172D02*
G02X1197014Y270009I-70J-2325D01*
G01X1194940Y271172D02*
X1195069D01*
G01X1193634Y271959D02*
G03X1194940Y271172I1365J788D01*
G01X1191704Y273121D02*
G02X1193634Y271959I-85J-2325D01*
G01X1191575Y273121D02*
X1191704D01*
G01X1190254Y273909D02*
G03X1191575Y273121I1365J787D01*
G01X1188309Y275072D02*
G02X1190254Y273909I-70J-2325D01*
G01X1188169Y275072D02*
X1188309D01*
G01X1186224Y273909D02*
G02X1188169Y275072I2015J-1162D01*
G01X1183494Y273909D02*
G03X1186224I1365J787D01*
G01X1181549Y275072D02*
G02X1183494Y273909I-70J-2325D01*
G01X1181409Y275072D02*
X1181549D01*
G01X1179464Y273909D02*
G02X1181409Y275072I2015J-1162D01*
G01X1176734Y273909D02*
G03X1179464I1365J787D01*
G01X1174789Y275072D02*
G02X1176734Y273909I-70J-2325D01*
G01X1174649Y275072D02*
X1174789D01*
G01X1172704Y273909D02*
G02X1174649Y275072I2015J-1162D01*
G01X1171383Y273121D02*
G03X1172704Y273909I-44J1575D01*
G01X1171241Y273121D02*
X1171383D01*
G01X1169324Y271960D02*
G02X1171241Y273121I2015J-1164D01*
G01X1169311Y271937D02*
X1169324Y271960D01*
G01X1166595Y271959D02*
G03X1169311Y271937I1364J788D01*
G01X1164665Y273121D02*
G02X1166595Y271959I-85J-2325D01*
G01X1164495Y273121D02*
X1164665D01*
G01X1162565Y271959D02*
G02X1164495Y273121I2015J-1163D01*
G01X1161259Y271172D02*
G03X1162565Y271959I-59J1575D01*
G01X1161130Y271172D02*
X1161259D01*
G01X1159185Y270009D02*
G02X1161130Y271172I2015J-1162D01*
G01X1157864Y269221D02*
G03X1159185Y270009I-44J1575D01*
G01X1157735Y269221D02*
X1157864D01*
G01X1157871Y230222D02*
X1157776D01*
G01X1159835Y229059D02*
G03X1157871Y230222I-2015J-1163D01*
G01X1161141Y228272D02*
G02X1159835Y229059I59J1575D01*
G01X1161270Y228272D02*
X1161141D01*
G01X1163215Y227109D02*
G03X1161270Y228272I-2015J-1162D01*
G01X1164536Y226321D02*
G02X1163215Y227109I44J1575D01*
G01X1164665Y226321D02*
X1164536D01*
G01X1166595Y225159D02*
G03X1164665Y226321I-2015J-1163D01*
G01X1167901Y224372D02*
G02X1166595Y225159I59J1575D01*
G01X1168030Y224372D02*
X1167901D01*
G01X1169975Y223209D02*
G03X1168030Y224372I-2015J-1162D01*
G01X1169988Y223186D02*
X1169975Y223209D01*
G01X1171339Y222421D02*
G02X1169988Y223186I0J1575D01*
G01X1171424Y222421D02*
X1171339D01*
G01X1173354Y221259D02*
G03X1171424Y222421I-2015J-1163D01*
G01X1174660Y220472D02*
G02X1173354Y221259I59J1575D01*
G01X1174789Y220472D02*
X1174660D01*
G01X1176734Y219309D02*
G03X1174789Y220472I-2015J-1162D01*
G01X1178055Y218521D02*
G02X1176734Y219309I44J1575D01*
G01X1178184Y218521D02*
X1178055D01*
G01X1162112Y255400D02*
X1158940D01*
G01X1163332Y254180D02*
X1162112Y255400D01*
G01X1163215Y252084D02*
G03X1163332Y254180I-2015J1164D01*
G01X1163196Y250543D02*
G02X1163215Y252084I1384J754D01*
G01Y250509D02*
X1163196Y250543D01*
G01X1164536Y249721D02*
G02X1163215Y250509I44J1575D01*
G01X1164665Y249721D02*
X1164536D01*
G01X1166595Y248559D02*
G03X1164665Y249721I-2015J-1163D01*
G01X1166620Y246276D02*
G03X1166595Y248559I-2040J1119D01*
G01Y246234D02*
X1166620Y246276D01*
G01X1166576Y246200D02*
X1166595Y246234D01*
G01Y244659D02*
G02X1166576Y246200I1365J787D01*
G01X1166620Y242376D02*
G03X1166595Y244659I-2040J1119D01*
G01Y242334D02*
X1166620Y242376D01*
G01X1166576Y242300D02*
X1166595Y242334D01*
G01Y240759D02*
G02X1166576Y242300I1365J787D01*
G01X1166620Y238476D02*
G03X1166595Y240759I-2040J1119D01*
G01Y238434D02*
X1166620Y238476D01*
G01X1166576Y238400D02*
X1166595Y238434D01*
G01Y236859D02*
G02X1166576Y238400I1365J787D01*
G01X1167901Y236072D02*
G02X1166595Y236859I59J1575D01*
G01X1168011Y236072D02*
X1167901D01*
G01X1169975Y234909D02*
G03X1168011Y236072I-2015J-1163D01*
G01X1171291Y234122D02*
G02X1169975Y234909I48J1574D01*
G01X1171409Y234122D02*
X1171291D01*
G01X1173354Y232959D02*
G03X1171409Y234122I-2015J-1162D01*
G01X1174648Y232172D02*
G02X1173354Y232959I71J1574D01*
G01X1174804Y232172D02*
X1174648D01*
G01X1176734Y231010D02*
G03X1174804Y232172I-2015J-1163D01*
G01X1178055Y230222D02*
G02X1176734Y231010I44J1575D01*
G01X1178150Y230222D02*
X1178055D01*
G01X1180114Y229059D02*
G03X1178150Y230222I-2015J-1163D01*
G01X1181420Y228272D02*
G02X1180114Y229059I59J1575D01*
G01X1181549Y228272D02*
X1181420D01*
G01X1183494Y227109D02*
G03X1181549Y228272I-2015J-1162D01*
G01X1184815Y226321D02*
G02X1183494Y227109I44J1575D01*
G01X1184944Y226321D02*
X1184815D01*
G01X1186874Y225159D02*
G03X1184944Y226321I-2015J-1163D01*
G01X1189604Y225159D02*
G02X1186874I-1365J788D01*
G01X1193634D02*
G03X1189604I-2015J-1163D01*
G01X1194940Y224372D02*
G02X1193634Y225159I59J1575D01*
G01X1195058Y224372D02*
X1194940D01*
G01X1196364Y225159D02*
G02X1195058Y224372I-1365J788D01*
G01X1200394Y225159D02*
G03X1196364I-2015J-1163D01*
G01X1201700Y224372D02*
G02X1200394Y225159I59J1575D01*
G01X1201829Y224372D02*
X1201700D01*
G01X1203774Y223209D02*
G03X1201829Y224372I-2015J-1162D01*
G01X1205133Y222424D02*
G02X1203774Y223209I0J1568D01*
G01X1205968Y222424D02*
X1205133D01*
G01X1206970Y223426D02*
X1205968Y222424D01*
G01X1206970Y225277D02*
Y223426D01*
G01X1206950Y225297D02*
X1206970Y225277D01*
G01X1206950Y230497D02*
Y225297D01*
G01X1207869Y231416D02*
X1206950Y230497D01*
G01X1209116Y231416D02*
X1207869D01*
G01X1211300Y233600D02*
X1209116Y231416D01*
G01X1213640Y233600D02*
X1211300D01*
G01X1210157Y270418D02*
X1210250Y270325D01*
G01X1208511Y270418D02*
X1210157D01*
G01X1207154Y269634D02*
G02X1208511Y270418I1357J-783D01*
G01X1203124Y269634D02*
G03X1207154I2015J1162D01*
G01X1200394D02*
G02X1203124I1365J-787D01*
G01X1198477Y268472D02*
G03X1200394Y269634I-98J2324D01*
G01X1198281Y268472D02*
X1198477D01*
G01X1196364Y269634D02*
G03X1198281Y268472I2015J1162D01*
G01X1195043Y270422D02*
G02X1196364Y269634I-44J-1575D01*
G01X1194914Y270422D02*
X1195043D01*
G01X1192984Y271584D02*
G03X1194914Y270422I2015J1163D01*
G01X1191678Y272371D02*
G02X1192984Y271584I-59J-1575D01*
G01X1191549Y272371D02*
X1191678D01*
G01X1189604Y273534D02*
G03X1191549Y272371I2015J1162D01*
G01X1188310Y274321D02*
G02X1189604Y273534I-71J-1574D01*
G01X1188168Y274321D02*
X1188310D01*
G01X1186874Y273534D02*
G02X1188168Y274321I1365J-787D01*
G01X1182844Y273534D02*
G03X1186874I2015J1162D01*
G01X1181550Y274321D02*
G02X1182844Y273534I-71J-1574D01*
G01X1181408Y274321D02*
X1181550D01*
G01X1180114Y273534D02*
G02X1181408Y274321I1365J-787D01*
G01X1176084Y273534D02*
G03X1180114I2015J1162D01*
G01X1174790Y274321D02*
G02X1176084Y273534I-71J-1574D01*
G01X1174648Y274321D02*
X1174790D01*
G01X1173354Y273534D02*
G02X1174648Y274321I1365J-787D01*
G01X1171409Y272371D02*
G03X1173354Y273534I-70J2325D01*
G01X1171339Y272371D02*
X1171409D01*
G01X1169988Y271606D02*
G02X1171339Y272371I1351J-810D01*
G01X1165945Y271584D02*
G03X1169988Y271606I2015J1163D01*
G01X1164639Y272371D02*
G02X1165945Y271584I-59J-1575D01*
G01X1164521Y272371D02*
X1164639D01*
G01X1163215Y271584D02*
G02X1164521Y272371I1365J-788D01*
G01X1161285Y270422D02*
G03X1163215Y271584I-85J2325D01*
G01X1161156Y270422D02*
X1161285D01*
G01X1159835Y269634D02*
G02X1161156Y270422I1365J-787D01*
G01X1157890Y268471D02*
G03X1159835Y269634I-70J2325D01*
G01X1157761Y268471D02*
X1157890D01*
G01X1157879Y229471D02*
X1157769D01*
G01X1159185Y228684D02*
G03X1157879Y229471I-1365J-788D01*
G01X1161115Y227522D02*
G02X1159185Y228684I85J2325D01*
G01X1161244Y227522D02*
X1161115D01*
G01X1162565Y226734D02*
G03X1161244Y227522I-1365J-787D01*
G01X1164510Y225571D02*
G02X1162565Y226734I70J2325D01*
G01X1164639Y225571D02*
X1164510D01*
G01X1165945Y224784D02*
G03X1164639Y225571I-1365J-788D01*
G01X1167875Y223622D02*
G02X1165945Y224784I85J2325D01*
G01X1167960Y223622D02*
X1167875D01*
G01X1169311Y222857D02*
G03X1167960Y223622I-1351J-810D01*
G01X1169324Y222834D02*
X1169311Y222857D01*
G01X1171269Y221671D02*
G02X1169324Y222834I70J2325D01*
G01X1171398Y221671D02*
X1171269D01*
G01X1172704Y220884D02*
G03X1171398Y221671I-1365J-788D01*
G01X1174634Y219722D02*
G02X1172704Y220884I85J2325D01*
G01X1174763Y219722D02*
X1174634D01*
G01X1176084Y218934D02*
G03X1174763Y219722I-1365J-787D01*
G01X1161115Y274321D02*
G02X1159185Y275483I85J2325D01*
G01X1161285Y274321D02*
X1161115D01*
G01X1163215Y275483D02*
G02X1161285Y274321I-2015J1163D01*
G01X1164536Y276271D02*
G03X1163215Y275483I44J-1575D01*
G01X1164660Y276271D02*
X1164536D01*
G01X1164661Y276270D02*
X1164660Y276271D01*
G01X1216934Y238497D02*
X1225777D01*
G01X1216226Y237789D02*
X1216934Y238497D01*
G01X1211394Y237789D02*
X1216226D01*
G01X1211034Y238149D02*
X1211394Y237789D01*
G01X1210691Y238798D02*
X1211034Y238149D01*
G01X1209317Y239972D02*
G02X1210691Y238798I-798J-2325D01*
G01X1208449Y239972D02*
X1209317D01*
G01X1206504Y238809D02*
G02X1208449Y239972I2015J-1162D01*
G01X1205183Y238021D02*
G03X1206504Y238809I-44J1575D01*
G01X1205095Y238021D02*
X1205183D01*
G01X1203774Y238809D02*
G03X1205095Y238021I1365J787D01*
G01X1201829Y239972D02*
G02X1203774Y238809I-70J-2325D01*
G01X1201689Y239972D02*
X1201829D01*
G01X1199744Y238809D02*
G02X1201689Y239972I2015J-1162D01*
G01X1198423Y238021D02*
G03X1199744Y238809I-44J1575D01*
G01X1198335Y238021D02*
X1198423D01*
G01X1197014Y238809D02*
G03X1198335Y238021I1365J787D01*
G01X1192984Y238809D02*
G02X1197014I2015J-1162D01*
G01X1191663Y238021D02*
G03X1192984Y238809I-44J1575D01*
G01X1191575Y238021D02*
X1191663D01*
G01X1190254Y238809D02*
G03X1191575Y238021I1365J787D01*
G01X1186224Y238809D02*
G02X1190254I2015J-1162D01*
G01X1184903Y238021D02*
G03X1186224Y238809I-44J1575D01*
G01X1184815Y238021D02*
X1184903D01*
G01X1183494Y238809D02*
G03X1184815Y238021I1365J787D01*
G01X1179464Y238809D02*
G02X1183494I2015J-1162D01*
G01X1178143Y238021D02*
G03X1179464Y238809I-44J1575D01*
G01X1178055Y238021D02*
X1178143D01*
G01X1176734Y238809D02*
G03X1178055Y238021I1365J787D01*
G01X1174789Y239972D02*
G02X1176734Y238809I-70J-2325D01*
G01X1174660Y239972D02*
X1174789D01*
G01X1173354Y240759D02*
G03X1174660Y239972I1365J788D01*
G01X1171424Y241921D02*
G02X1173354Y240759I-85J-2325D01*
G01X1171339Y241921D02*
X1171424D01*
G01X1169988Y242686D02*
G03X1171339Y241921I1351J810D01*
G01X1169975Y242709D02*
X1169988Y242686D01*
G01X1168217Y243859D02*
G02X1169975Y242709I-257J-2312D01*
G01X1167960Y244116D02*
X1168217Y243859D01*
G01X1167960Y245447D02*
Y244116D01*
G01X1157879Y245071D02*
X1157750D01*
G01X1159204Y242743D02*
G03X1157879Y245071I-1384J753D01*
G01X1159185Y242709D02*
X1159204Y242743D01*
G01X1159160Y242667D02*
X1159185Y242709D01*
G01Y240384D02*
G02X1159160Y242667I2015J1164D01*
G01X1159204Y238843D02*
G03X1159185Y240384I-1384J754D01*
G01Y238809D02*
X1159204Y238843D01*
G01X1159160Y238767D02*
X1159185Y238809D01*
G01Y236484D02*
G02X1159160Y238767I2015J1164D01*
G01X1159204Y234943D02*
G03X1159185Y236484I-1384J754D01*
G01Y234909D02*
X1159204Y234943D01*
G01X1161130Y231421D02*
G02X1159185Y234909I70J2325D01*
G01X1161271Y231421D02*
X1161130D01*
G01X1162565Y230634D02*
G03X1161271Y231421I-1365J-787D01*
G01X1164529Y229471D02*
G02X1162565Y230634I51J2326D01*
G01X1164639Y229471D02*
X1164529D01*
G01X1165945Y228684D02*
G03X1164639Y229471I-1365J-788D01*
G01X1167875Y227522D02*
G02X1165945Y228684I85J2325D01*
G01X1167960Y227522D02*
X1167875D01*
G01X1169311Y226757D02*
G03X1167960Y227522I-1351J-810D01*
G01X1169324Y226734D02*
X1169311Y226757D01*
G01X1171269Y225571D02*
G02X1169324Y226734I70J2325D01*
G01X1171398Y225571D02*
X1171269D01*
G01X1172704Y224784D02*
G03X1171398Y225571I-1365J-788D01*
G01X1174634Y223622D02*
G02X1172704Y224784I85J2325D01*
G01X1174763Y223622D02*
X1174634D01*
G01X1176084Y222834D02*
G03X1174763Y223622I-1365J-787D01*
G01X1178029Y221671D02*
G02X1176084Y222834I70J2325D01*
G01X1178158Y221671D02*
X1178029D01*
G01X1179464Y220884D02*
G03X1178158Y221671I-1365J-788D01*
G01X1181394Y219722D02*
G02X1179464Y220884I85J2325D01*
G01X1181523Y219722D02*
X1181394D01*
G01X1182844Y218934D02*
G03X1181523Y219722I-1365J-787D01*
G01X1162262Y252185D02*
X1161200Y253247D01*
G01X1162262Y251503D02*
Y252185D01*
G01X1162540Y250176D02*
G02X1162262Y251503I2040J1120D01*
G01X1164510Y248971D02*
G02X1162540Y250176I69J2325D01*
G01X1164639Y248971D02*
X1164510D01*
G01X1165945Y248184D02*
G03X1164639Y248971I-1365J-788D01*
G01X1165964Y246643D02*
G03X1165945Y248184I-1384J754D01*
G01Y246609D02*
X1165964Y246643D01*
G01X1165920Y246567D02*
X1165945Y246609D01*
G01Y244284D02*
G02X1165920Y246567I2015J1164D01*
G01X1165964Y242743D02*
G03X1165945Y244284I-1384J754D01*
G01Y242709D02*
X1165964Y242743D01*
G01X1165920Y242667D02*
X1165945Y242709D01*
G01Y240384D02*
G02X1165920Y242667I2015J1164D01*
G01X1165964Y238843D02*
G03X1165945Y240384I-1384J754D01*
G01Y238809D02*
X1165964Y238843D01*
G01X1165920Y238767D02*
X1165945Y238809D01*
G01Y236484D02*
G02X1165920Y238767I2015J1164D01*
G01X1167909Y235321D02*
G02X1165945Y236484I51J2326D01*
G01X1167960Y235321D02*
X1167909D01*
G01X1169311Y234556D02*
G03X1167960Y235321I-1351J-810D01*
G01X1169324Y234533D02*
X1169311Y234556D01*
G01X1171254Y233371D02*
G02X1169324Y234533I85J2325D01*
G01X1171410Y233371D02*
X1171254D01*
G01X1172704Y232584D02*
G03X1171410Y233371I-1365J-787D01*
G01X1174649Y231421D02*
G02X1172704Y232584I70J2325D01*
G01X1174790Y231421D02*
X1174649D01*
G01X1176084Y230634D02*
G03X1174790Y231421I-1365J-787D01*
G01X1178048Y229471D02*
G02X1176084Y230634I51J2326D01*
G01X1178158Y229471D02*
X1178048D01*
G01X1179464Y228684D02*
G03X1178158Y229471I-1365J-788D01*
G01X1181394Y227522D02*
G02X1179464Y228684I85J2325D01*
G01X1181523Y227522D02*
X1181394D01*
G01X1182844Y226734D02*
G03X1181523Y227522I-1365J-787D01*
G01X1184789Y225571D02*
G02X1182844Y226734I70J2325D01*
G01X1184918Y225571D02*
X1184789D01*
G01X1186224Y224784D02*
G03X1184918Y225571I-1365J-788D01*
G01X1190254Y224784D02*
G02X1186224I-2015J1163D01*
G01X1192984D02*
G03X1190254I-1365J-788D01*
G01X1194914Y223622D02*
G02X1192984Y224784I85J2325D01*
G01X1195084Y223622D02*
X1194914D01*
G01X1197014Y224784D02*
G02X1195084Y223622I-2015J1163D01*
G01X1199744Y224784D02*
G03X1197014I-1365J-788D01*
G01X1201674Y223622D02*
G02X1199744Y224784I85J2325D01*
G01X1201803Y223622D02*
X1201674D01*
G01X1203124Y222834D02*
G03X1201803Y223622I-1365J-787D01*
G01X1205069Y221671D02*
G02X1203124Y222834I70J2325D01*
G01X1205139Y221671D02*
X1205069D01*
G01X1157890Y295771D02*
X1157750D01*
G01X1159835Y296934D02*
G02X1157890Y295771I-2015J1162D01*
G01X1161156Y297722D02*
G03X1159835Y296934I44J-1575D01*
G01X1161244Y297722D02*
X1161156D01*
G01X1162565Y296934D02*
G03X1161244Y297722I-1365J-787D01*
G01X1164510Y295771D02*
G02X1162565Y296934I70J2325D01*
G01X1164650Y295771D02*
X1164510D01*
G01X1166595Y296934D02*
G02X1164650Y295771I-2015J1162D01*
G01X1167916Y297722D02*
G03X1166595Y296934I44J-1575D01*
G01X1168058Y297722D02*
X1167916D01*
G01X1169975Y298883D02*
G02X1168058Y297722I-2015J1164D01*
G01X1169988Y298906D02*
X1169975Y298883D01*
G01X1171339Y299671D02*
G03X1169988Y298906I0J-1575D01*
G01X1171409Y299671D02*
X1171339D01*
G01X1173354Y300834D02*
G02X1171409Y299671I-2015J1162D01*
G01X1174675Y301622D02*
G03X1173354Y300834I44J-1575D01*
G01X1174763Y301622D02*
X1174675D01*
G01X1176084Y300834D02*
G03X1174763Y301622I-1365J-787D01*
G01X1178029Y299671D02*
G02X1176084Y300834I70J2325D01*
G01X1178169Y299671D02*
X1178029D01*
G01X1180114Y300834D02*
G02X1178169Y299671I-2015J1162D01*
G01X1181435Y301622D02*
G03X1180114Y300834I44J-1575D01*
G01X1181523Y301622D02*
X1181435D01*
G01X1182844Y300834D02*
G03X1181523Y301622I-1365J-787D01*
G01X1184789Y299671D02*
G02X1182844Y300834I70J2325D01*
G01X1184929Y299671D02*
X1184789D01*
G01X1186874Y300834D02*
G02X1184929Y299671I-2015J1162D01*
G01X1188195Y301622D02*
G03X1186874Y300834I44J-1575D01*
G01X1188283Y301622D02*
X1188195D01*
G01X1189604Y300834D02*
G03X1188283Y301622I-1365J-787D01*
G01X1191549Y299671D02*
G02X1189604Y300834I70J2325D01*
G01X1191689Y299671D02*
X1191549D01*
G01X1193634Y300834D02*
G02X1191689Y299671I-2015J1162D01*
G01X1194955Y301622D02*
G03X1193634Y300834I44J-1575D01*
G01X1197264Y301622D02*
X1194955D01*
G01X1199576Y301491D02*
X1199128D01*
G01X1199577Y301490D02*
X1199576Y301491D01*
G01X1199664Y301490D02*
X1199577D01*
G01X1157864Y296521D02*
X1157776D01*
G01X1159185Y297309D02*
G02X1157864Y296521I-1365J787D01*
G01X1161130Y298472D02*
G03X1159185Y297309I70J-2325D01*
G01X1161270Y298472D02*
X1161130D01*
G01X1163215Y297309D02*
G03X1161270Y298472I-2015J-1162D01*
G01X1164536Y296521D02*
G02X1163215Y297309I44J1575D01*
G01X1164624Y296521D02*
X1164536D01*
G01X1165945Y297309D02*
G02X1164624Y296521I-1365J787D01*
G01X1167890Y298472D02*
G03X1165945Y297309I70J-2325D01*
G01X1167960Y298472D02*
X1167890D01*
G01X1169311Y299237D02*
G02X1167960Y298472I-1351J810D01*
G01X1169324Y299260D02*
X1169311Y299237D01*
G01X1171241Y300421D02*
G03X1169324Y299260I98J-2325D01*
G01X1171383Y300421D02*
X1171241D01*
G01X1172704Y301209D02*
G02X1171383Y300421I-1365J787D01*
G01X1174649Y302372D02*
G03X1172704Y301209I70J-2325D01*
G01X1174789Y302372D02*
X1174649D01*
G01X1176734Y301209D02*
G03X1174789Y302372I-2015J-1162D01*
G01X1178055Y300421D02*
G02X1176734Y301209I44J1575D01*
G01X1178143Y300421D02*
X1178055D01*
G01X1179464Y301209D02*
G02X1178143Y300421I-1365J787D01*
G01X1181409Y302372D02*
G03X1179464Y301209I70J-2325D01*
G01X1181549Y302372D02*
X1181409D01*
G01X1183494Y301209D02*
G03X1181549Y302372I-2015J-1162D01*
G01X1184815Y300421D02*
G02X1183494Y301209I44J1575D01*
G01X1184903Y300421D02*
X1184815D01*
G01X1186224Y301209D02*
G02X1184903Y300421I-1365J787D01*
G01X1188169Y302372D02*
G03X1186224Y301209I70J-2325D01*
G01X1188309Y302372D02*
X1188169D01*
G01X1190254Y301209D02*
G03X1188309Y302372I-2015J-1162D01*
G01X1191575Y300421D02*
G02X1190254Y301209I44J1575D01*
G01X1191663Y300421D02*
X1191575D01*
G01X1192984Y301209D02*
G02X1191663Y300421I-1365J787D01*
G01X1194999Y302373D02*
G03X1192984Y301209I0J-2326D01*
G01X1197514Y302373D02*
X1194999D01*
G01X1197661Y302520D02*
X1197514Y302373D01*
G01X1199586Y302520D02*
X1197661D01*
G01X1305842Y280168D02*
X1217194D01*
G01X1157890Y284071D02*
X1157750D01*
G01X1159835Y285234D02*
G02X1157890Y284071I-2015J1162D01*
G01X1161156Y286022D02*
G03X1159835Y285234I44J-1575D01*
G01X1161244Y286022D02*
X1161156D01*
G01X1162565Y285234D02*
G03X1161244Y286022I-1365J-787D01*
G01X1164510Y284071D02*
G02X1162565Y285234I70J2325D01*
G01X1164650Y284071D02*
X1164510D01*
G01X1166595Y285234D02*
G02X1164650Y284071I-2015J1162D01*
G01X1167916Y286022D02*
G03X1166595Y285234I44J-1575D01*
G01X1168058Y286022D02*
X1167916D01*
G01X1169975Y287183D02*
G02X1168058Y286022I-2015J1164D01*
G01X1169988Y287206D02*
X1169975Y287183D01*
G01X1171339Y287971D02*
G03X1169988Y287206I0J-1575D01*
G01X1171409Y287971D02*
X1171339D01*
G01X1173354Y289134D02*
G02X1171409Y287971I-2015J1162D01*
G01X1174675Y289922D02*
G03X1173354Y289134I44J-1575D01*
G01X1174763Y289922D02*
X1174675D01*
G01X1176084Y289134D02*
G03X1174763Y289922I-1365J-787D01*
G01X1178029Y287971D02*
G02X1176084Y289134I70J2325D01*
G01X1178169Y287971D02*
X1178029D01*
G01X1180114Y289134D02*
G02X1178169Y287971I-2015J1162D01*
G01X1181435Y289922D02*
G03X1180114Y289134I44J-1575D01*
G01X1181523Y289922D02*
X1181435D01*
G01X1182844Y289134D02*
G03X1181523Y289922I-1365J-787D01*
G01X1184789Y287971D02*
G02X1182844Y289134I70J2325D01*
G01X1184929Y287971D02*
X1184789D01*
G01X1186874Y289134D02*
G02X1184929Y287971I-2015J1162D01*
G01X1188195Y289922D02*
G03X1186874Y289134I44J-1575D01*
G01X1188283Y289922D02*
X1188195D01*
G01X1189604Y289134D02*
G03X1188283Y289922I-1365J-787D01*
G01X1191549Y287971D02*
G02X1189604Y289134I70J2325D01*
G01X1191689Y287971D02*
X1191549D01*
G01X1193634Y289134D02*
G02X1191689Y287971I-2015J1162D01*
G01X1194955Y289922D02*
G03X1193634Y289134I44J-1575D01*
G01X1195043Y289922D02*
X1194955D01*
G01X1196364Y289134D02*
G03X1195043Y289922I-1365J-787D01*
G01X1198309Y287971D02*
G02X1196364Y289134I70J2325D01*
G01X1198449Y287971D02*
X1198309D01*
G01X1200394Y289134D02*
G02X1198449Y287971I-2015J1162D01*
G01X1201715Y289922D02*
G03X1200394Y289134I44J-1575D01*
G01X1202559Y289922D02*
X1201715D01*
G01X1203931Y291095D02*
G02X1202559Y289922I-2172J1152D01*
G01X1204782Y291871D02*
G03X1203931Y291095I657J-1575D01*
G01X1209103Y291871D02*
X1204782D01*
G01X1209303Y291671D02*
X1209103Y291871D01*
G01X1212116Y291671D02*
X1209303D01*
G01X1214033Y289754D02*
X1212116Y291671D01*
G01X1157864Y284821D02*
X1157776D01*
G01X1159185Y285609D02*
G02X1157864Y284821I-1365J787D01*
G01X1161130Y286772D02*
G03X1159185Y285609I70J-2325D01*
G01X1161270Y286772D02*
X1161130D01*
G01X1163215Y285609D02*
G03X1161270Y286772I-2015J-1162D01*
G01X1164536Y284821D02*
G02X1163215Y285609I44J1575D01*
G01X1164624Y284821D02*
X1164536D01*
G01X1165945Y285609D02*
G02X1164624Y284821I-1365J787D01*
G01X1167890Y286772D02*
G03X1165945Y285609I70J-2325D01*
G01X1167960Y286772D02*
X1167890D01*
G01X1169311Y287537D02*
G02X1167960Y286772I-1351J810D01*
G01X1169324Y287560D02*
X1169311Y287537D01*
G01X1171241Y288721D02*
G03X1169324Y287560I98J-2325D01*
G01X1171383Y288721D02*
X1171241D01*
G01X1172704Y289509D02*
G02X1171383Y288721I-1365J787D01*
G01X1174649Y290672D02*
G03X1172704Y289509I70J-2325D01*
G01X1174789Y290672D02*
X1174649D01*
G01X1176734Y289509D02*
G03X1174789Y290672I-2015J-1162D01*
G01X1178055Y288721D02*
G02X1176734Y289509I44J1575D01*
G01X1178143Y288721D02*
X1178055D01*
G01X1179464Y289509D02*
G02X1178143Y288721I-1365J787D01*
G01X1181409Y290672D02*
G03X1179464Y289509I70J-2325D01*
G01X1181549Y290672D02*
X1181409D01*
G01X1183494Y289509D02*
G03X1181549Y290672I-2015J-1162D01*
G01X1184815Y288721D02*
G02X1183494Y289509I44J1575D01*
G01X1184903Y288721D02*
X1184815D01*
G01X1186224Y289509D02*
G02X1184903Y288721I-1365J787D01*
G01X1188169Y290672D02*
G03X1186224Y289509I70J-2325D01*
G01X1188309Y290672D02*
X1188169D01*
G01X1190254Y289509D02*
G03X1188309Y290672I-2015J-1162D01*
G01X1191575Y288721D02*
G02X1190254Y289509I44J1575D01*
G01X1191663Y288721D02*
X1191575D01*
G01X1192984Y289509D02*
G02X1191663Y288721I-1365J787D01*
G01X1194929Y290672D02*
G03X1192984Y289509I70J-2325D01*
G01X1195069Y290672D02*
X1194929D01*
G01X1197014Y289509D02*
G03X1195069Y290672I-2015J-1162D01*
G01X1198335Y288721D02*
G02X1197014Y289509I44J1575D01*
G01X1198423Y288721D02*
X1198335D01*
G01X1199744Y289509D02*
G02X1198423Y288721I-1365J787D01*
G01X1201689Y290672D02*
G03X1199744Y289509I70J-2325D01*
G01X1202416Y290672D02*
X1201689D01*
G01X1203267Y291448D02*
G02X1202416Y290672I-1508J799D01*
G01X1204639Y292621D02*
G03X1203267Y291448I800J-2325D01*
G01X1212510Y292621D02*
X1204639D01*
G01X1214344Y290787D02*
X1212510Y292621D01*
G01X1163215Y305109D02*
G03X1159185I-2015J-1162D01*
G01X1165945D02*
G02X1163215I-1365J787D01*
G01X1169975D02*
G03X1165945I-2015J-1162D01*
G01X1169988Y305086D02*
X1169975Y305109D01*
G01X1172704D02*
G02X1169988Y305086I-1365J787D01*
G01X1176734Y305109D02*
G03X1172704I-2015J-1162D01*
G01X1179464D02*
G02X1176734I-1365J787D01*
G01X1183494D02*
G03X1179464I-2015J-1162D01*
G01X1186224D02*
G02X1183494I-1365J787D01*
G01X1190254D02*
G03X1186224I-2015J-1162D01*
G01X1192984D02*
G02X1190254I-1365J787D01*
G01X1194929Y306272D02*
G03X1192984Y305109I70J-2325D01*
G01X1198577Y306272D02*
X1194929D01*
G01X1200041Y307736D02*
X1198577Y306272D01*
G01X1211841Y307736D02*
X1200041D01*
G01X1215172Y304405D02*
X1211841Y307736D01*
G01X1162565Y304734D02*
G03X1159835I-1365J-787D01*
G01X1166595D02*
G02X1162565I-2015J1162D01*
G01X1169298Y304779D02*
G03X1166595Y304734I-1338J-832D01*
G01X1169324D02*
X1169298Y304779D01*
G01X1173354Y304734D02*
G02X1169324I-2015J1162D01*
G01X1176084D02*
G03X1173354I-1365J-787D01*
G01X1180114D02*
G02X1176084I-2015J1162D01*
G01X1182844D02*
G03X1180114I-1365J-787D01*
G01X1186874D02*
G02X1182844I-2015J1162D01*
G01X1189604D02*
G03X1186874I-1365J-787D01*
G01X1193634D02*
G02X1189604I-2015J1162D01*
G01X1194955Y305522D02*
G03X1193634Y304734I44J-1575D01*
G01X1199264Y305522D02*
X1194955D01*
G01X1200602Y304184D02*
X1199264Y305522D01*
G01X1239261Y144006D02*
X1238448D01*
G01X1240010Y144754D02*
X1239261Y144006D01*
G01X1237397Y143213D02*
X1232765Y147845D01*
G01X1237398Y143213D02*
X1237397D01*
G01X1237755Y142856D02*
X1237398Y143213D01*
G01X1238939Y142856D02*
X1237755D01*
G01X1240022Y141773D02*
X1238939Y142856D01*
G01X1236390Y244960D02*
X1226760Y235330D01*
G01X1227520Y253860D02*
X1224080Y250420D01*
G01X1227550Y253860D02*
X1227520D01*
G01X1232550Y258860D02*
X1227550Y253860D01*
G01X1265273Y258860D02*
X1232550D01*
G01X1267204Y256929D02*
X1265273Y258860D01*
G01X1233026Y257709D02*
X1264794D01*
G01X1228027Y252710D02*
X1233026Y257709D01*
G01X1227997Y252710D02*
X1228027D01*
G01X1224258Y248971D02*
X1227997Y252710D01*
G01X1224295Y241116D02*
X1233949Y250770D01*
G01X1225061Y239761D02*
X1234640Y249340D01*
G01X1225777Y238497D02*
X1235368Y248088D01*
G01X1528094Y389531D02*
X1526896Y388333D01*
G01X1526500Y393278D02*
X1528094Y391684D01*
G01X1526500Y394708D02*
Y393278D01*
G01X1525015Y396193D02*
X1526500Y394708D01*
G01X1525015Y398077D02*
Y396193D01*
G01X1525971Y399033D02*
X1525015Y398077D01*
G01X1525973Y399033D02*
X1525971D01*
G01X1526286Y399346D02*
X1525973Y399033D01*
G01X1529758Y399346D02*
X1526286D01*
G01X1526906Y402743D02*
X1528475Y401174D01*
G01X1520025Y402743D02*
X1526906D01*
G01X1519106Y401824D02*
X1520025Y402743D01*
G01X1519106Y400394D02*
Y401824D01*
G01X1517156Y398444D02*
X1519106Y400394D01*
G01X1517156Y396734D02*
Y398444D01*
G01X1518344Y395546D02*
X1517156Y396734D01*
G01X1518344Y394135D02*
Y395546D01*
G01X1520603Y391876D02*
X1518344Y394135D01*
G01X1520603Y390070D02*
Y391876D01*
G01X1520027Y389494D02*
X1520603Y390070D01*
G01X1563205Y376875D02*
X1561719Y375389D01*
G01X1563205Y379045D02*
Y376875D01*
G01X1562006Y380244D02*
X1563205Y379045D01*
G01X1562006Y381544D02*
Y380244D01*
G01X1563495Y383033D02*
X1562006Y381544D01*
G01X1563495Y385515D02*
Y383033D01*
G01X1562006Y387004D02*
X1563495Y385515D01*
G01X1562006Y388304D02*
Y387004D01*
G01X1563495Y389793D02*
X1562006Y388304D01*
G01X1563495Y392275D02*
Y389793D01*
G01X1562006Y393764D02*
X1563495Y392275D01*
G01X1562006Y395064D02*
Y393764D01*
G01X1563495Y396553D02*
X1562006Y395064D01*
G01X1563495Y399035D02*
Y396553D01*
G01X1562006Y400524D02*
X1563495Y399035D01*
G01X1562006Y408322D02*
Y400524D01*
G01X1528094Y391684D02*
Y389531D01*
G01X1529775Y399363D02*
X1529758Y399346D01*
G01X1532785Y399363D02*
X1529775D01*
G01X1558106Y412222D02*
X1562006Y408322D01*
G01X1558106Y415344D02*
Y412222D01*
G01X1560056Y417294D02*
X1558106Y415344D01*
G01X1560056Y418727D02*
Y417294D01*
G01X1562006Y420677D02*
X1560056Y418727D01*
G01X1562006Y422104D02*
Y420677D01*
G01X1563495Y423593D02*
X1562006Y422104D01*
G01X1563495Y426075D02*
Y423593D01*
G01X1562006Y427564D02*
X1563495Y426075D01*
G01X1562006Y428994D02*
Y427564D01*
G01X1560056Y430944D02*
X1562006Y428994D01*
G01X1560056Y432244D02*
Y430944D01*
G01X1561250Y433438D02*
X1560056Y432244D01*
G01X1561250Y436871D02*
Y433438D01*
G01X1562412Y438801D02*
G03X1561250Y436871I1163J-2015D01*
G01X1562412Y441531D02*
G02Y438801I-787J-1365D01*
G01X1561250Y443461D02*
G03X1562412Y441531I2325J85D01*
G01X1561250Y443631D02*
Y443461D01*
G01X1561379Y444313D02*
G03X1561250Y443631I2196J-769D01*
G01X1560070Y446245D02*
X1561379Y444313D01*
G01X1560070Y446262D02*
Y446245D01*
G01X1560056Y446276D02*
X1560070Y446262D01*
G01X1560056Y447576D02*
Y446276D01*
G01X1560074Y447594D02*
X1560056Y447576D01*
G01X1560084Y448376D02*
X1560074Y447594D01*
G01X1561175Y450105D02*
X1560084Y448376D01*
G01X1561164Y450240D02*
X1561175Y450105D01*
G01X1561164Y451281D02*
Y450240D01*
G01X1561012Y452522D02*
X1561164Y451281D01*
G01X1559125Y454409D02*
X1561012Y452522D01*
G01X1558512Y455051D02*
G02X1559125Y454409I-787J-1365D01*
G01X1557350Y456981D02*
G03X1558512Y455051I2325J85D01*
G01X1557350Y457110D02*
Y456981D01*
G01X1556562Y458431D02*
G02X1557350Y457110I-787J-1365D01*
G01X1555400Y460361D02*
G03X1556562Y458431I2325J85D01*
G01X1555400Y460490D02*
Y460361D01*
G01X1553038Y461811D02*
G02X1555400Y460490I787J-1365D01*
G01X1550712Y461811D02*
G03X1553038I1163J2015D01*
G01X1549138D02*
G02X1550712I787J-1365D01*
G01X1546812D02*
G03X1549138I1163J2015D01*
G01X1545238D02*
G02X1546812I787J-1365D01*
G01X1542912D02*
G03X1545238I1163J2015D01*
G01X1540566Y460674D02*
G02X1542912Y461811I1559J-228D01*
G01X1540794Y460446D02*
X1540566Y460674D01*
G01X1542125Y460446D02*
X1540794D01*
G01X1539556D02*
X1538225D01*
G01X1539812Y460702D02*
X1539556Y460446D01*
G01X1543288Y462461D02*
G03X1539812Y460702I-1163J-2015D01*
G01X1544862Y462461D02*
G02X1543288I-787J1365D01*
G01X1547188D02*
G03X1544862I-1163J-2015D01*
G01X1548762D02*
G02X1547188I-787J1365D01*
G01X1551088D02*
G03X1548762I-1163J-2015D01*
G01X1552662D02*
G02X1551088I-787J1365D01*
G01X1556150Y460531D02*
G03X1552662Y462461I-2325J-85D01*
G01X1556150Y460402D02*
Y460531D01*
G01X1556938Y459081D02*
G02X1556150Y460402I787J1365D01*
G01X1558100Y457151D02*
G03X1556938Y459081I-2325J-85D01*
G01X1558100Y457022D02*
Y457151D01*
G01X1558888Y455701D02*
G02X1558100Y457022I787J1365D01*
G01X1559733Y454861D02*
G03X1558888Y455701I-2008J-1175D01*
G01X1561976Y452618D02*
X1559733Y454861D01*
G01X1561976Y451686D02*
Y452618D01*
G01X1561998Y449420D02*
X1561976Y451686D01*
G01X1563955Y447463D02*
X1561998Y449420D01*
G01X1563955Y443499D02*
Y447463D01*
G01X1594260Y40288D02*
X1594887Y39661D01*
G01X1886175Y193219D02*
X1890786Y197830D01*
G01X1886175Y182964D02*
Y193219D01*
G01X1885136Y181925D02*
X1886175Y182964D01*
G01X1882425Y181925D02*
X1885136D01*
G01X1878250Y177750D02*
X1882425Y181925D01*
G01X1878250Y177394D02*
Y177750D01*
G01X1876657Y175801D02*
X1878250Y177394D01*
G01X1887125Y192825D02*
X1891378Y197078D01*
G01X1887125Y182570D02*
Y192825D01*
G01X1885530Y180975D02*
X1887125Y182570D01*
G01X1882819Y180975D02*
X1885530D01*
G01X1879200Y177356D02*
X1882819Y180975D01*
G01X1879200Y177000D02*
Y177356D01*
G01X1876832Y174632D02*
X1879200Y177000D01*
G01X1876832Y173919D02*
Y174632D01*
G01X1936331Y191431D02*
X1939200Y194300D01*
G01X1926659Y191431D02*
X1936331D01*
G01X1925653Y190425D02*
X1926659Y191431D01*
G01X1924347Y190425D02*
X1925653D01*
G01X1922947Y191825D02*
X1924347Y190425D01*
G01X1916008Y191825D02*
X1922947D01*
G01X1913206Y194627D02*
X1916008Y191825D01*
G01X1912336Y194627D02*
X1913206D01*
G01X1938400Y188800D02*
Y178200D01*
G01X1936719Y190481D02*
X1938400Y188800D01*
G01X1926770Y190481D02*
X1936719D01*
G01X1925964Y189675D02*
X1926770Y190481D01*
G01X1924036Y189675D02*
X1925964D01*
G01X1922836Y190875D02*
X1924036Y189675D01*
G01X1915894Y190875D02*
X1922836D01*
G01X1915294Y191475D02*
X1915894Y190875D01*
G54D13*
G01X-17396Y18575D02*
X-15105Y16284D01*
G01X-17396Y61936D02*
Y18575D01*
G01X-18148Y18263D02*
X-15417Y15532D01*
G01X-18148Y61354D02*
Y18263D01*
G01X-16644Y18887D02*
Y62426D01*
G01X-14793Y17036D02*
X-16644Y18887D01*
G01X-18900Y17951D02*
Y60950D01*
G01X-15729Y14780D02*
X-18900Y17951D01*
G01X6424Y14780D02*
X-15729D01*
G01X-19892Y64432D02*
X-17396Y61936D01*
G01X-19892Y118808D02*
Y64432D01*
G01X-20644Y63850D02*
X-18148Y61354D01*
G01X-20644Y119120D02*
Y63850D01*
G01X-19140Y64922D02*
Y118496D01*
G01X-16644Y62426D02*
X-19140Y64922D01*
G01X-21396Y63446D02*
Y119432D01*
G01X-18900Y60950D02*
X-21396Y63446D01*
G01X-17418Y121282D02*
X-19892Y118808D01*
G01X8645Y121282D02*
X-17418D01*
G01X-19300Y120464D02*
X-20644Y119120D01*
G01X-19300Y127499D02*
Y120464D01*
G01X-18395Y128404D02*
X-19300Y127499D01*
G01X19667Y128404D02*
X-18395D01*
G01X-17106Y120530D02*
X13404D01*
G01X-19140Y118496D02*
X-17106Y120530D01*
G01X-18708Y129155D02*
X19980D01*
G01X-20052Y127811D02*
X-18708Y129155D01*
G01X-20052Y120776D02*
Y127811D01*
G01X-21396Y119432D02*
X-20052Y120776D01*
G01X-19776Y178541D02*
X-11036Y169801D01*
G01X-19776Y246665D02*
Y178541D01*
G01Y264124D02*
Y261965D01*
G01X-3905Y349100D02*
X-19776Y333229D01*
G01X-16189Y456429D02*
X-17014Y455604D01*
G01X-4669Y456429D02*
X-16189D01*
G01X34289Y-10779D02*
X56054D01*
G01X7226Y16284D02*
X34289Y-10779D01*
G01X-15105Y16284D02*
X7226D01*
G01X33817Y-11533D02*
X55603D01*
G01X6752Y15532D02*
X33817Y-11533D01*
G01X-15417Y15532D02*
X6752D01*
G01X7538Y17036D02*
X-14793D01*
G01X34586Y-10012D02*
X7538Y17036D01*
G01X60829Y-10012D02*
X34586D01*
G01X33504Y-12300D02*
X6424Y14780D01*
G01X55108Y-12300D02*
X33504D01*
G01X12205Y124842D02*
X8645Y121282D01*
G01X12205Y124843D02*
Y124842D01*
G01X23228Y124843D02*
X19667Y128404D01*
G01X17716Y124842D02*
Y124843D01*
G01X13404Y120530D02*
X17716Y124842D01*
G01X24583Y129000D02*
X28740Y124843D01*
G01X20135Y129000D02*
X24583D01*
G01X19980Y129155D02*
X20135Y129000D01*
G01X43745Y201813D02*
Y264566D01*
G01X43924Y201634D02*
X43745Y201813D01*
G01X43924Y201068D02*
Y201634D01*
G01X57527Y187465D02*
X43924Y201068D01*
G01X45076Y201546D02*
Y264267D01*
G01X59051Y187571D02*
X45076Y201546D01*
G01X45828Y203940D02*
X65776Y183992D01*
G01X45828Y263955D02*
Y203940D01*
G01X40569Y169801D02*
X54919Y155451D01*
G01X-11036Y169801D02*
X40569D01*
G01X45886Y278024D02*
X42818Y281092D01*
G01X45886Y266707D02*
Y278024D01*
G01X43745Y264566D02*
X45886Y266707D01*
G01X47038Y278502D02*
X44172Y281368D01*
G01X45076Y264267D02*
X47038Y266229D01*
G01X47790Y265917D02*
X45828Y263955D01*
G01X41440Y326849D02*
Y423543D01*
G01X43984Y324305D02*
X41440Y326849D01*
G01X43984Y318526D02*
Y324305D01*
G01X42818Y317360D02*
X43984Y318526D01*
G01X42818Y281092D02*
Y317360D01*
G01X43124Y328747D02*
Y423057D01*
G01X45687Y326184D02*
X43124Y328747D01*
G01X45687Y318251D02*
Y326184D01*
G01X44172Y316736D02*
X45687Y318251D01*
G01X44172Y281368D02*
Y316736D01*
G01X45828Y280820D02*
X47790Y278858D01*
G01X45828Y315132D02*
Y280820D01*
G01X50648Y319952D02*
X45828Y315132D01*
G01X45706Y364044D02*
X50510Y359240D01*
G01X45706Y405317D02*
Y364044D01*
G01X44842Y363561D02*
Y405780D01*
G01X47970Y360433D02*
X44842Y363561D01*
G01X31328Y349100D02*
X-3905D01*
G01X37634Y355406D02*
X31328Y349100D01*
G01X37634Y413357D02*
Y355406D01*
G01X52911Y412522D02*
X45706Y405317D01*
G01X41440Y423543D02*
X49394Y431497D01*
G01X2181Y463279D02*
X-4669Y456429D01*
G01X13253Y463279D02*
X2181D01*
G01X17218Y467244D02*
X13253Y463279D01*
G01X43124Y423057D02*
X51997Y431930D01*
G01X44842Y405780D02*
X49660Y410598D01*
G01X33811Y417180D02*
X37634Y413357D01*
G01X33811Y426585D02*
Y417180D01*
G01X49600Y442374D02*
X33811Y426585D01*
G01X38785Y487861D02*
X48156Y478490D01*
G01X28461Y487861D02*
X38785D01*
G01X27792Y487192D02*
X28461Y487861D01*
G01X18076Y487192D02*
X27792D01*
G01X10565Y494703D02*
X18076Y487192D01*
G01X771Y494703D02*
X10565D01*
G01X-1068Y496542D02*
X771Y494703D01*
G01X-1068Y509740D02*
Y496542D01*
G01X651Y511459D02*
X-1068Y509740D01*
G01X3030Y511459D02*
X651D01*
G01X5272Y513701D02*
X3030Y511459D01*
G01X5272Y515545D02*
Y513701D01*
G01X6748Y517021D02*
X5272Y515545D01*
G01X2350Y469800D02*
Y469650D01*
G01X4825Y472275D02*
X2350Y469800D01*
G01X33551Y472275D02*
X4825D01*
G01X34047Y472771D02*
X33551Y472275D01*
G01X52108Y472771D02*
X34047D01*
G01X20512Y467244D02*
X17218D01*
G01X40342Y473923D02*
X31477Y482788D01*
G01X58902Y473923D02*
X40342D01*
G01X4520Y515977D02*
X3354Y517143D01*
G01X4520Y514013D02*
Y515977D01*
G01X2718Y512211D02*
X4520Y514013D01*
G01X75Y512211D02*
X2718D01*
G01X-1820Y510316D02*
X75Y512211D01*
G01X-1820Y496230D02*
Y510316D01*
G01X459Y493951D02*
X-1820Y496230D01*
G01X9970Y493951D02*
X459D01*
G01X17681Y486240D02*
X9970Y493951D01*
G01X27940Y486240D02*
X17681D01*
G01X28609Y486909D02*
X27940Y486240D01*
G01X38673Y486909D02*
X28609D01*
G01X47844Y477738D02*
X38673Y486909D01*
G01X46098Y465941D02*
X49600Y462439D01*
G01X46098Y467393D02*
Y465941D01*
G01X42128Y471363D02*
X46098Y467393D01*
G01X34631Y471363D02*
X42128D01*
G01X30512Y467244D02*
X34631Y471363D01*
G01X66031Y-13689D02*
X66061D01*
G01X65172Y-14548D02*
X66031Y-13689D01*
G01X59823Y-14548D02*
X65172D01*
G01X56054Y-10779D02*
X59823Y-14548D01*
G01X88040Y22607D02*
Y84529D01*
G01X85539Y20106D02*
X88040Y22607D01*
G01X60047Y20106D02*
X85539D01*
G01X58324Y18383D02*
X60047Y20106D01*
G01X58324Y6377D02*
Y18383D01*
G01X63666Y1035D02*
X58324Y6377D01*
G01X63666Y-1249D02*
Y1035D01*
G01X62536Y-2379D02*
X63666Y-1249D01*
G01X85569Y23856D02*
Y83181D01*
G01X84192Y22479D02*
X85569Y23856D01*
G01X58995Y22479D02*
X84192D01*
G01X57400Y20884D02*
X58995Y22479D01*
G01X57400Y20450D02*
Y20884D01*
G01X56210Y19260D02*
X57400Y20450D01*
G01X56210Y5083D02*
Y19260D01*
G01X57400Y3893D02*
X56210Y5083D01*
G01X57400Y-85D02*
Y3893D01*
G01X61270Y-3955D02*
X57400Y-85D01*
G01X66902Y-3955D02*
X61270D01*
G01X77924Y-14977D02*
X66902Y-3955D01*
G01X77924Y-17253D02*
Y-14977D01*
G01X79359Y-18688D02*
X77924Y-17253D01*
G01X88582Y-18688D02*
X79359D01*
G01X91732Y-15538D02*
X88582Y-18688D01*
G01X109995Y-15538D02*
X91732D01*
G01X101921Y-4324D02*
Y59822D01*
G01X114126Y-16529D02*
X101921Y-4324D01*
G01X65006Y-19456D02*
X65164D01*
G01X63113Y-17563D02*
X65006Y-19456D01*
G01X61633Y-17563D02*
X63113D01*
G01X55603Y-11533D02*
X61633Y-17563D01*
G01X62008Y9452D02*
Y13249D01*
G01X64430Y7030D02*
X62008Y9452D01*
G01X64430Y478D02*
Y7030D01*
G01X78711Y-13803D02*
X64430Y478D01*
G01X110336Y-13803D02*
X78711D01*
G01X63683Y-12866D02*
X60829Y-10012D01*
G01X102924Y-2503D02*
Y59761D01*
G01X116198Y-15777D02*
X102924Y-2503D01*
G01X60610Y-17802D02*
X55108Y-12300D01*
G01X60610Y-19624D02*
Y-17802D01*
G01X62606Y-21620D02*
X60610Y-19624D01*
G01X66689Y-21620D02*
X62606D01*
G01X67564Y-20745D02*
X66689Y-21620D01*
G01X104316Y-1666D02*
Y58883D01*
G01X104500Y-1850D02*
X104316Y-1666D01*
G01X57362Y4994D02*
X61994Y362D01*
G01X57362Y18782D02*
Y4994D01*
G01X59648Y21068D02*
X57362Y18782D01*
G01X85140Y21068D02*
X59648D01*
G01X87078Y23006D02*
X85140Y21068D01*
G01X87078Y84130D02*
Y23006D01*
G01X78775Y-20096D02*
X405515D01*
G01X76516Y-17837D02*
X78775Y-20096D01*
G01X76516Y-16915D02*
Y-17837D01*
G01X65334Y-5733D02*
X76516Y-16915D01*
G01X61056Y-5733D02*
X65334D01*
G01X56100Y-777D02*
X61056Y-5733D01*
G01X56100Y2805D02*
Y-777D01*
G01X54330Y4575D02*
X56100Y2805D01*
G01X54330Y11749D02*
Y4575D01*
G01X47562Y18517D02*
X54330Y11749D01*
G01X47562Y81271D02*
Y18517D01*
G01X58960Y88752D02*
Y110978D01*
G01X59985Y87727D02*
X58960Y88752D01*
G01X84842Y87727D02*
X59985D01*
G01X88040Y84529D02*
X84842Y87727D01*
G01X56403Y88199D02*
Y163734D01*
G01X59491Y85111D02*
X56403Y88199D01*
G01X83639Y85111D02*
X59491D01*
G01X85569Y83181D02*
X83639Y85111D01*
G01X102779Y93053D02*
X99832Y96000D01*
G01X102779Y75711D02*
Y93053D01*
G01X103676Y74814D02*
X102779Y75711D01*
G01X103676Y61577D02*
Y74814D01*
G01X101921Y59822D02*
X103676Y61577D01*
G01X104228Y93729D02*
X100157Y97800D01*
G01X104228Y83046D02*
Y93729D01*
G01X105201Y82073D02*
X104228Y83046D01*
G01X105201Y62038D02*
Y82073D01*
G01X102924Y59761D02*
X105201Y62038D01*
G01X107775Y80279D02*
X114300Y86804D01*
G01X107775Y62342D02*
Y80279D01*
G01X104316Y58883D02*
X107775Y62342D01*
G01X84443Y86765D02*
X87078Y84130D01*
G01X59586Y86765D02*
X84443D01*
G01X57972Y88379D02*
X59586Y86765D01*
G01X57972Y162056D02*
Y88379D01*
G01X54919Y88628D02*
X47562Y81271D01*
G01X54919Y155451D02*
Y88628D01*
G01X58724Y117686D02*
Y161461D01*
G01X58924Y117486D02*
X58724Y117686D01*
G01X58924Y116014D02*
Y117486D01*
G01X58960Y115978D02*
X58924Y116014D01*
G01X58960Y112522D02*
Y115978D01*
G01X58924Y112486D02*
X58960Y112522D01*
G01X58924Y111014D02*
Y112486D01*
G01X58960Y110978D02*
X58924Y111014D01*
G01X86721Y96000D02*
X77721Y105000D01*
G01X99832Y96000D02*
X86721D01*
G01X89843Y97800D02*
X82643Y105000D01*
G01X100157Y97800D02*
X89843D01*
G01X105085Y123515D02*
Y171585D01*
G01X114300Y114300D02*
X105085Y123515D01*
G01X77770Y153990D02*
Y167530D01*
G01X78950Y152810D02*
X77770Y153990D01*
G01X76818Y153538D02*
Y167925D01*
G01X75660Y152380D02*
X76818Y153538D01*
G01X46580Y204535D02*
Y263643D01*
G01X66728Y184387D02*
X46580Y204535D01*
G01X66728Y169465D02*
Y184387D01*
G01X58724Y161461D02*
X66728Y169465D01*
G01X57527Y164858D02*
Y187465D01*
G01X56403Y163734D02*
X57527Y164858D01*
G01X112053Y206687D02*
X107700Y211040D01*
G01X91400Y193817D02*
X86731Y189148D01*
G01X91400Y203135D02*
Y193817D01*
G01X105770Y217505D02*
X91400Y203135D01*
G01X105770Y285492D02*
Y217505D01*
G01X104707Y211047D02*
X102507D01*
G01X111300Y204454D02*
X104707Y211047D01*
G01X107750Y188250D02*
X111300Y191800D01*
G01X107750Y174250D02*
Y188250D01*
G01X105085Y171585D02*
X107750Y174250D01*
G01X59051Y176696D02*
Y187571D01*
G01X59826Y175921D02*
X59051Y176696D01*
G01X63776Y175921D02*
X59826D01*
G01X64187Y176332D02*
X63776Y175921D01*
G01X65776Y169860D02*
X57972Y162056D01*
G01X65776Y183992D02*
Y169860D01*
G01X88645Y202010D02*
X104462Y217827D01*
G01X88645Y200144D02*
Y202010D01*
G01X84370Y195869D02*
X88645Y200144D01*
G01X84370Y174130D02*
Y195869D01*
G01X77770Y167530D02*
X84370Y174130D01*
G01X87693Y202405D02*
X103510Y218222D01*
G01X87693Y200539D02*
Y202405D01*
G01X83418Y196264D02*
X87693Y200539D01*
G01X83418Y174525D02*
Y196264D01*
G01X76818Y167925D02*
X83418Y174525D01*
G01X48542Y279328D02*
X46580Y281290D01*
G01X48542Y265605D02*
Y279328D01*
G01X46580Y263643D02*
X48542Y265605D01*
G01X47038Y266229D02*
Y278502D01*
G01X47790Y278858D02*
Y265917D01*
G01X104462Y217827D02*
Y284823D01*
G01X103510Y218222D02*
Y284428D01*
G01X47424Y332200D02*
Y356154D01*
G01X51400Y328224D02*
X47424Y332200D01*
G01X51400Y319640D02*
Y328224D01*
G01X46580Y314820D02*
X51400Y319640D01*
G01X46580Y281290D02*
Y314820D01*
G01X69000Y342521D02*
Y338800D01*
G01X77600Y335770D02*
Y320800D01*
G01X79217Y337387D02*
X77600Y335770D01*
G01X79217Y341344D02*
Y337387D01*
G01X72000Y343114D02*
Y338800D01*
G01X98500Y292762D02*
X105770Y285492D01*
G01X98500Y309470D02*
Y292762D01*
G01X87150Y320820D02*
X98500Y309470D01*
G01X87150Y327871D02*
Y320820D01*
G01X91639Y332360D02*
X87150Y327871D01*
G01X97770Y332360D02*
X91639D01*
G01X100550Y335140D02*
X97770Y332360D01*
G01X50648Y327912D02*
Y319952D01*
G01X46672Y331888D02*
X50648Y327912D01*
G01X46672Y356749D02*
Y331888D01*
G01X78300Y338200D02*
Y342201D01*
G01X76200Y336100D02*
X78300Y338200D01*
G01X76200Y329071D02*
Y336100D01*
G01X72129Y325000D02*
X76200Y329071D01*
G01X66799Y325000D02*
X72129D01*
G01X62500Y320701D02*
X66799Y325000D01*
G01X62500Y318000D02*
Y320701D01*
G01X64000Y316500D02*
X62500Y318000D01*
G01X64800Y315700D02*
X64000Y316500D01*
G01X69253Y315700D02*
X64800D01*
G01X72605Y319052D02*
X69253Y315700D01*
G01X85265Y319052D02*
X72605D01*
G01X97252Y307065D02*
X85265Y319052D01*
G01X97252Y292033D02*
Y307065D01*
G01X104462Y284823D02*
X97252Y292033D01*
G01X62424Y315476D02*
X64000Y313900D01*
G01X62424Y316729D02*
Y315476D01*
G01X61548Y317605D02*
X62424Y316729D01*
G01X61548Y321096D02*
Y317605D01*
G01X66404Y325952D02*
X61548Y321096D01*
G01X71734Y325952D02*
X66404D01*
G01X75248Y329466D02*
X71734Y325952D01*
G01X75248Y336495D02*
Y329466D01*
G01X77348Y338595D02*
X75248Y336495D01*
G01X77348Y342596D02*
Y338595D01*
G01X64848Y314748D02*
X64000Y313900D01*
G01X69648Y314748D02*
X64848D01*
G01X73000Y318100D02*
X69648Y314748D01*
G01X84870Y318100D02*
X73000D01*
G01X96300Y306670D02*
X84870Y318100D01*
G01X96300Y291638D02*
Y306670D01*
G01X103510Y284428D02*
X96300Y291638D01*
G01X74800Y338850D02*
Y343507D01*
G01X47424Y356154D02*
X50510Y359240D01*
G01X62403Y349997D02*
X63800Y348600D01*
G01X58553Y349997D02*
X62403D01*
G01X54205Y354345D02*
X58553Y349997D01*
G01X54205Y357787D02*
Y354345D01*
G01X46776Y365216D02*
X54205Y357787D01*
G01X46776Y403505D02*
Y365216D01*
G01X73936Y347457D02*
X69000Y342521D01*
G01X73936Y349928D02*
Y347457D01*
G01X71568Y352296D02*
X73936Y349928D01*
G01X69470Y352296D02*
X71568D01*
G01X67792Y353974D02*
X69470Y352296D01*
G01X59664Y353974D02*
X67792D01*
G01X56802Y356836D02*
X59664Y353974D01*
G01X56802Y357868D02*
Y356836D01*
G01X48628Y366042D02*
X56802Y357868D01*
G01X48628Y391971D02*
Y366042D01*
G01X52188Y395531D02*
X48628Y391971D01*
G01X57845Y395531D02*
X52188D01*
G01X64076Y389300D02*
X57845Y395531D01*
G01X67522Y389300D02*
X64076D01*
G01X69663Y391441D02*
X67522Y389300D01*
G01X69663Y394501D02*
Y391441D01*
G01X69660Y394504D02*
X69663Y394501D01*
G01X69660Y400206D02*
Y394504D01*
G01X69662Y400208D02*
X69660Y400206D01*
G01X69662Y426750D02*
Y400208D01*
G01X89400Y351527D02*
X79217Y341344D01*
G01X89400Y387094D02*
Y351527D01*
G01X86824Y389670D02*
X89400Y387094D01*
G01X86824Y391677D02*
Y389670D01*
G01X92134Y396987D02*
X86824Y391677D01*
G01X92134Y423761D02*
Y396987D01*
G01X75646Y346760D02*
X72000Y343114D01*
G01X75646Y350625D02*
Y346760D01*
G01X72273Y353998D02*
X75646Y350625D01*
G01X70175Y353998D02*
X72273D01*
G01X66773Y357400D02*
X70175Y353998D01*
G01X59891Y357400D02*
X66773D01*
G01X50330Y366961D02*
X59891Y357400D01*
G01X50330Y391266D02*
Y366961D01*
G01X52893Y393829D02*
X50330Y391266D01*
G01X57140Y393829D02*
X52893D01*
G01X63371Y387598D02*
X57140Y393829D01*
G01X68227Y387598D02*
X63371D01*
G01X71365Y390736D02*
X68227Y387598D01*
G01X71365Y395206D02*
Y390736D01*
G01X71362Y395209D02*
X71365Y395206D01*
G01X71362Y399501D02*
Y395209D01*
G01X71364Y399503D02*
X71362Y399501D01*
G01X71364Y426045D02*
Y399503D01*
G01X47970Y358047D02*
X46672Y356749D01*
G01X47970Y359550D02*
Y358047D01*
G01Y359550D02*
Y360433D01*
G01X90683Y397460D02*
Y425760D01*
G01X85424Y392201D02*
X90683Y397460D01*
G01X85424Y389471D02*
Y392201D01*
G01X88648Y386247D02*
X85424Y389471D01*
G01X88648Y357749D02*
Y386247D01*
G01X81928Y351029D02*
X88648Y357749D01*
G01X81928Y345829D02*
Y351029D01*
G01X78300Y342201D02*
X81928Y345829D01*
G01X80976Y346224D02*
X77348Y342596D01*
G01X80976Y351424D02*
Y346224D01*
G01X87696Y358144D02*
X80976Y351424D01*
G01X87696Y385659D02*
Y358144D01*
G01X86983Y386372D02*
X87696Y385659D01*
G01X86983Y386383D02*
Y386372D01*
G01X84472Y388894D02*
X86983Y386383D01*
G01X84472Y392596D02*
Y388894D01*
G01X89731Y397855D02*
X84472Y392596D01*
G01X89731Y426155D02*
Y397855D01*
G01X73066Y398798D02*
Y425339D01*
G01X73064Y398796D02*
X73066Y398798D01*
G01X73064Y395914D02*
Y398796D01*
G01X73067Y395911D02*
X73064Y395914D01*
G01X73067Y390031D02*
Y395911D01*
G01X68932Y385896D02*
X73067Y390031D01*
G01X62666Y385896D02*
X68932D01*
G01X56436Y392126D02*
X62666Y385896D01*
G01X53597Y392126D02*
X56436D01*
G01X52174Y390703D02*
X53597Y392126D01*
G01X52174Y367524D02*
Y390703D01*
G01X60596Y359102D02*
X52174Y367524D01*
G01X67478Y359102D02*
X60596D01*
G01X70880Y355700D02*
X67478Y359102D01*
G01X72978Y355700D02*
X70880D01*
G01X77348Y351330D02*
X72978Y355700D01*
G01X77348Y346055D02*
Y351330D01*
G01X74800Y343507D02*
X77348Y346055D01*
G01X54523Y412522D02*
X52911D01*
G01X57416Y415415D02*
X54523Y412522D01*
G01X57416Y428204D02*
Y415415D01*
G01X59229Y430017D02*
X57416Y428204D01*
G01X59229Y430041D02*
Y430017D01*
G01X60269Y431081D02*
X59229Y430041D01*
G01X60293Y431081D02*
X60269D01*
G01X69969Y440757D02*
X60293Y431081D01*
G01X69969Y468654D02*
Y440757D01*
G01X53991Y410720D02*
X46776Y403505D01*
G01X54820Y410720D02*
X53991D01*
G01X66248Y422148D02*
X54820Y410720D01*
G01X66248Y429398D02*
Y422148D01*
G01X71590Y434740D02*
X66248Y429398D01*
G01X71590Y440896D02*
Y434740D01*
G01X81996Y451302D02*
X71590Y440896D01*
G01X81996Y498811D02*
Y451302D01*
G01X72524Y429612D02*
X69662Y426750D01*
G01X72525Y429612D02*
X72524D01*
G01X74258Y431345D02*
X72525Y429612D01*
G01X74258Y440483D02*
Y431345D01*
G01X102192Y468417D02*
X74258Y440483D01*
G01X56836Y446397D02*
Y468043D01*
G01X49394Y438955D02*
X56836Y446397D01*
G01X49394Y431497D02*
Y438955D01*
G01X111507Y443134D02*
X92134Y423761D01*
G01X73229Y427910D02*
X71364Y426045D01*
G01X73230Y427910D02*
X73229D01*
G01X75960Y430640D02*
X73230Y427910D01*
G01X75960Y439778D02*
Y430640D01*
G01X103894Y467712D02*
X75960Y439778D01*
G01X64440Y450880D02*
Y468385D01*
G01X51997Y438437D02*
X64440Y450880D01*
G01X51997Y431930D02*
Y438437D01*
G01X68289Y440404D02*
Y469270D01*
G01X56464Y428579D02*
X68289Y440404D01*
G01X56464Y415964D02*
Y428579D01*
G01X53974Y413474D02*
X56464Y415964D01*
G01X52516Y413474D02*
X53974D01*
G01X49660Y410618D02*
X52516Y413474D01*
G01X49660Y410598D02*
Y410618D01*
G01X90683Y425760D02*
X110755Y445832D01*
G01X109803Y446227D02*
X89731Y426155D01*
G01X49600Y462439D02*
Y442374D01*
G01X77662Y439073D02*
X105596Y467007D01*
G01X77662Y429935D02*
Y439073D01*
G01X73066Y425339D02*
X77662Y429935D01*
G01X60133Y478490D02*
X69969Y468654D01*
G01X48156Y478490D02*
X60133D01*
G01X83910Y500725D02*
X81996Y498811D01*
G01X83910Y507580D02*
Y500725D01*
G01X80820Y510670D02*
X83910Y507580D01*
G01X80820Y530470D02*
Y510670D01*
G01X102192Y502697D02*
Y468417D01*
G01X100281Y504608D02*
X102192Y502697D01*
G01X89955Y504608D02*
X100281D01*
G01X83302Y511261D02*
X89955Y504608D01*
G01X83302Y530332D02*
Y511261D01*
G01X56836Y468043D02*
X52108Y472771D01*
G01X103894Y503446D02*
Y467712D01*
G01X101030Y506310D02*
X103894Y503446D01*
G01X90660Y506310D02*
X101030D01*
G01X85004Y511966D02*
X90660Y506310D01*
G01X85004Y529607D02*
Y511966D01*
G01X61905Y470920D02*
X58902Y473923D01*
G01X62035Y470920D02*
X61905D01*
G01X64188Y468767D02*
X62035Y470920D01*
G01X64188Y468637D02*
Y468767D01*
G01X64440Y468385D02*
X64188Y468637D01*
G01X59821Y477738D02*
X47844D01*
G01X68289Y469270D02*
X59821Y477738D01*
G01X107648Y494623D02*
X109803Y492468D01*
G01X107648Y501376D02*
Y494623D01*
G01X108952Y502680D02*
X107648Y501376D01*
G01X103540Y518376D02*
Y610560D01*
G01X102916Y517752D02*
X103540Y518376D01*
G01X102916Y506892D02*
Y517752D01*
G01X105596Y504212D02*
X102916Y506892D01*
G01X105596Y467007D02*
Y504212D01*
G01X83393Y533043D02*
X80820Y530470D01*
G01X83393Y617013D02*
Y533043D01*
G01X85245Y532275D02*
X83302Y530332D01*
G01X85245Y613285D02*
Y532275D01*
G01X86947Y531550D02*
X85004Y529607D01*
G01X86947Y612580D02*
Y531550D01*
G01X84040Y617660D02*
X83393Y617013D01*
G01X84040Y621370D02*
Y617660D01*
G01X87072Y624402D02*
X84040Y621370D01*
G01X307500Y624402D02*
X87072D01*
G01X90210Y618250D02*
X85245Y613285D01*
G01X91150Y618250D02*
X90210D01*
G01X90915Y616548D02*
X86947Y612580D01*
G01X92237Y616548D02*
X90915D01*
G01X93800Y618111D02*
X92237Y616548D01*
G01X103867Y612536D02*
X102236Y614167D01*
G01X103867Y610887D02*
Y612536D01*
G01X103540Y610560D02*
X103867Y610887D01*
G01X124450Y-56200D02*
X120500Y-52250D01*
G01X145030Y-56200D02*
X124450D01*
G01X147382Y-53848D02*
X145030Y-56200D01*
G01X445510Y-53848D02*
X147382D01*
G01X148901Y-50496D02*
X445510D01*
G01X112890Y-18433D02*
X109995Y-15538D01*
G01X405186Y-18433D02*
X112890D01*
G01X404396Y-16529D02*
X114126D01*
G01X108527Y-5698D02*
Y79455D01*
G01X117854Y-15025D02*
X108527Y-5698D01*
G01X403772Y-15025D02*
X117854D01*
G01X113814Y-17281D02*
X110336Y-13803D01*
G01X404708Y-17281D02*
X113814D01*
G01X404084Y-15777D02*
X116198D01*
G01X111524Y-6913D02*
Y80700D01*
G01X118884Y-14273D02*
X111524Y-6913D01*
G01X403460Y-14273D02*
X118884D01*
G01X115053Y85981D02*
Y115047D01*
G01X108527Y79455D02*
X115053Y85981D01*
G01X114300Y86804D02*
Y114300D01*
G01X117232Y86408D02*
Y125110D01*
G01X111524Y80700D02*
X117232Y86408D01*
G01X114752Y115348D02*
Y167998D01*
G01X115053Y115047D02*
X114752Y115348D01*
G01X115730Y126612D02*
Y170714D01*
G01X117232Y125110D02*
X115730Y126612D01*
G01X112053Y191489D02*
Y206687D01*
G01X108502Y187938D02*
X112053Y191489D01*
G01X108502Y174248D02*
Y187938D01*
G01X114752Y167998D02*
X108502Y174248D01*
G01X111300Y191800D02*
Y204454D01*
G01X120300Y193710D02*
X124340Y197750D01*
G01X120300Y175284D02*
Y193710D01*
G01X115730Y170714D02*
X120300Y175284D01*
G01X161774Y392042D02*
X150680Y403136D01*
G01X176378Y392042D02*
X161774D01*
G01X145194Y400666D02*
X173669Y372191D01*
G01X145194Y404648D02*
Y400666D01*
G01X161150Y390538D02*
X171759D01*
G01X149090Y402598D02*
X161150Y390538D01*
G01X149090Y406072D02*
Y402598D01*
G01X146698Y401290D02*
Y405272D01*
G01X157948Y390040D02*
X146698Y401290D01*
G01X157950Y390040D02*
X157948D01*
G01X173294Y374696D02*
X157950Y390040D01*
G01X161462Y391290D02*
X176066D01*
G01X149900Y402852D02*
X161462Y391290D01*
G01X149900Y406326D02*
Y402852D01*
G01X162086Y392794D02*
X180787D01*
G01X151616Y403264D02*
X162086Y392794D01*
G01X147450Y401602D02*
Y405584D01*
G01X158260Y390792D02*
X147450Y401602D01*
G01X158391Y390792D02*
X158260D01*
G01X173735Y375448D02*
X158391Y390792D01*
G01X169400Y382155D02*
X175255Y376300D01*
G01X169400Y388634D02*
Y382155D01*
G01X168248Y389786D02*
X169400Y388634D01*
G01X160838Y389786D02*
X168248D01*
G01X148280Y402344D02*
X160838Y389786D01*
G01X148280Y405818D02*
Y402344D01*
G01X157638Y389288D02*
X172982Y373944D01*
G01X157636Y389288D02*
X157638D01*
G01X145946Y400978D02*
X157636Y389288D01*
G01X145946Y404960D02*
Y400978D01*
G01X117493Y448750D02*
Y511807D01*
G01X133251Y432992D02*
X117493Y448750D01*
G01X135148Y432992D02*
X133251D01*
G01X144450Y423690D02*
X135148Y432992D01*
G01X144450Y412840D02*
Y423690D01*
G01X150680Y406610D02*
X144450Y412840D01*
G01X150680Y403136D02*
Y406610D01*
G01X142842Y407000D02*
X145194Y404648D01*
G01X129257Y407000D02*
X142842D01*
G01X127830Y405573D02*
X129257Y407000D01*
G01X121981Y405573D02*
X127830D01*
G01X142945Y412217D02*
X149090Y406072D01*
G01X142945Y423066D02*
Y412217D01*
G01X134524Y431488D02*
X142945Y423066D01*
G01X132627Y431488D02*
X134524D01*
G01X115438Y448677D02*
X132627Y431488D01*
G01X115438Y501224D02*
Y448677D01*
G01X124261Y411600D02*
X119100D01*
G01X127123Y408738D02*
X124261Y411600D01*
G01X143232Y408738D02*
X127123D01*
G01X146698Y405272D02*
X143232Y408738D01*
G01X143697Y412529D02*
X149900Y406326D01*
G01X143697Y423379D02*
Y412529D01*
G01X134836Y432240D02*
X143697Y423379D01*
G01X132939Y432240D02*
X134836D01*
G01X116661Y448518D02*
X132939Y432240D01*
G01X116661Y511575D02*
Y448518D01*
G01X112372Y427243D02*
Y493223D01*
G01X120330Y419285D02*
X112372Y427243D01*
G01X122156Y419285D02*
X120330D01*
G01X122242Y419199D02*
X122156Y419285D01*
G01X151616Y408302D02*
Y403264D01*
G01X152226Y408912D02*
X151616Y408302D01*
G01X152226Y410513D02*
Y408912D01*
G01X151189Y411550D02*
X152226Y410513D01*
G01X149121Y411550D02*
X151189D01*
G01X145300Y415371D02*
X149121Y411550D01*
G01X145300Y423904D02*
Y415371D01*
G01X135460Y433744D02*
X145300Y423904D01*
G01X133563Y433744D02*
X135460D01*
G01X118245Y449062D02*
X133563Y433744D01*
G01X118245Y512119D02*
Y449062D01*
G01X122724Y414201D02*
X119016D01*
G01X127435Y409490D02*
X122724Y414201D01*
G01X143544Y409490D02*
X127435D01*
G01X147450Y405584D02*
X143544Y409490D01*
G01X142193Y411905D02*
X148280Y405818D01*
G01X142193Y422754D02*
Y411905D01*
G01X134212Y430736D02*
X142193Y422754D01*
G01X132167Y430736D02*
X134212D01*
G01X114678Y448225D02*
X132167Y430736D01*
G01X114678Y500566D02*
Y448225D01*
G01X111507Y492974D02*
Y443134D01*
G01X143006Y407900D02*
X145946Y404960D01*
G01X120950Y407900D02*
X143006D01*
G01X119398Y406348D02*
X120950Y407900D01*
G01X113419Y427433D02*
Y494330D01*
G01X119264Y421588D02*
X113419Y427433D01*
G01X123234Y421588D02*
X119264D01*
G01X123441Y421795D02*
X123234Y421588D01*
G01X110755Y445832D02*
Y492590D01*
G01X109803Y492468D02*
Y446227D01*
G01X116368Y523784D02*
Y544860D01*
G01X114599Y522015D02*
X116368Y523784D01*
G01X114599Y514701D02*
Y522015D01*
G01X117493Y511807D02*
X114599Y514701D01*
G01X112566Y504096D02*
X115438Y501224D01*
G01X112566Y514078D02*
Y504096D01*
G01X111814Y514830D02*
X112566Y514078D01*
G01X111814Y520247D02*
Y514830D01*
G01X111364Y520697D02*
X111814Y520247D01*
G01X111364Y608412D02*
Y520697D01*
G01X112566Y515670D02*
X116661Y511575D01*
G01X112566Y522534D02*
Y515670D01*
G01X112116Y522984D02*
X112566Y522534D01*
G01X112116Y608100D02*
Y522984D01*
G01X110512Y498428D02*
X111961Y499877D01*
G01X110512Y495083D02*
Y498428D01*
G01X112372Y493223D02*
X110512Y495083D01*
G01X118203Y512161D02*
X118245Y512119D01*
G01X118203Y512203D02*
Y512161D01*
G01X115351Y515055D02*
X118203Y512203D01*
G01X115351Y519755D02*
Y515055D01*
G01X117459Y521863D02*
X115351Y519755D01*
G01X117459Y549281D02*
Y521863D01*
G01X111814Y503430D02*
X114678Y500566D01*
G01X111814Y513678D02*
Y503430D01*
G01X111062Y514430D02*
X111814Y513678D01*
G01X111062Y519647D02*
Y514430D01*
G01X110612Y520097D02*
X111062Y519647D01*
G01X110612Y608724D02*
Y520097D01*
G01X109152Y495329D02*
X111507Y492974D01*
G01X109152Y500752D02*
Y495329D01*
G01X110656Y502256D02*
X109152Y500752D01*
G01X110656Y513494D02*
Y502256D01*
G01X110310Y513840D02*
X110656Y513494D01*
G01X110310Y519335D02*
Y513840D01*
G01X109860Y519785D02*
X110310Y519335D01*
G01X109860Y609036D02*
Y519785D01*
G01X112427Y495322D02*
Y497225D01*
G01X113419Y494330D02*
X112427Y495322D01*
G01X108922Y519162D02*
Y611702D01*
G01X109522Y518562D02*
X108922Y519162D01*
G01X109522Y512838D02*
Y518562D01*
G01X109904Y512456D02*
X109522Y512838D01*
G01X109904Y502568D02*
Y512456D01*
G01X108400Y501064D02*
X109904Y502568D01*
G01X108400Y494945D02*
Y501064D01*
G01X110755Y492590D02*
X108400Y494945D01*
G01X108952Y512139D02*
Y502680D01*
G01X108570Y512521D02*
X108952Y512139D01*
G01X108570Y518167D02*
Y512521D01*
G01X107970Y518767D02*
X108570Y518167D01*
G01X107970Y612097D02*
Y518767D01*
G01X116085Y588023D02*
X115351Y588757D01*
G01X116085Y561565D02*
Y588023D01*
G01X114307Y559787D02*
X116085Y561565D01*
G01X114307Y546921D02*
Y559787D01*
G01X116368Y544860D02*
X114307Y546921D01*
G01X115351Y551389D02*
X117459Y549281D01*
G01X115351Y557499D02*
Y551389D01*
G01X117100Y559248D02*
X115351Y557499D01*
G01X117100Y587376D02*
Y559248D01*
G01X118568Y588844D02*
X117100Y587376D01*
G01X121013Y615933D02*
X442704D01*
G01X116368Y611288D02*
X121013Y615933D01*
G01X116368Y602027D02*
Y611288D01*
G01X115351Y601010D02*
X116368Y602027D01*
G01X115351Y588757D02*
Y601010D01*
G01X120389Y617437D02*
X111364Y608412D01*
G01X443396Y617437D02*
X120389D01*
G01X120701Y616685D02*
X112116Y608100D01*
G01X443016Y616685D02*
X120701D01*
G01X118568Y601732D02*
Y588844D01*
G01X118516Y601784D02*
X118568Y601732D01*
G01X118516Y607816D02*
Y601784D01*
G01X121800Y611100D02*
X118516Y607816D01*
G01X121800Y613008D02*
Y611100D01*
G01X123973Y615181D02*
X121800Y613008D01*
G01X442392Y615181D02*
X123973D01*
G01X120077Y618189D02*
X110612Y608724D01*
G01X443708Y618189D02*
X120077D01*
G01X119765Y618941D02*
X109860Y609036D01*
G01X444020Y618941D02*
X119765D01*
G01X119518Y622298D02*
X306355D01*
G01X108922Y611702D02*
X119518Y622298D01*
G01X119123Y623250D02*
X107970Y612097D01*
G01X306750Y623250D02*
X119123D01*
G01X207386Y362153D02*
X240939Y328600D01*
G01X241602Y330200D02*
X207002Y364800D01*
G01X207701Y362913D02*
X241254Y329360D01*
G01X197882Y370538D02*
X176378Y392042D01*
G01X197882Y370047D02*
Y370538D01*
G01X199329Y368600D02*
X197882Y370047D01*
G01X208944Y368600D02*
X199329D01*
G01X243152Y334392D02*
X208944Y368600D01*
G01X196710Y362153D02*
X207386D01*
G01X190937Y367926D02*
X196710Y362153D01*
G01X190937Y369734D02*
Y367926D01*
G01X188480Y372191D02*
X190937Y369734D01*
G01X173669Y372191D02*
X188480D01*
G01X208320Y367096D02*
X242776Y332640D01*
G01X198705Y367096D02*
X208320D01*
G01X196378Y369423D02*
X198705Y367096D01*
G01X196378Y369914D02*
Y369423D01*
G01X187630Y378662D02*
X196378Y369914D01*
G01X177025Y378662D02*
X187630D01*
G01X172834Y382853D02*
X177025Y378662D01*
G01X172834Y389463D02*
Y382853D01*
G01X171759Y390538D02*
X172834Y389463D01*
G01X173423Y374696D02*
X173294D01*
G01X173424Y374695D02*
X173423Y374696D01*
G01X174046Y374695D02*
X173424D01*
G01X174047Y374696D02*
X174046Y374695D01*
G01X174313Y374696D02*
X174047D01*
G01X174314Y374695D02*
X174313Y374696D01*
G01X174936Y374695D02*
X174314D01*
G01X174937Y374696D02*
X174936Y374695D01*
G01X188404Y374696D02*
X174937D01*
G01X194122Y368978D02*
X188404Y374696D01*
G01X194122Y368457D02*
Y368978D01*
G01X197779Y364800D02*
X194122Y368457D01*
G01X207002Y364800D02*
X197779D01*
G01X208632Y367848D02*
X242945Y333535D01*
G01X199017Y367848D02*
X208632D01*
G01X197130Y369735D02*
X199017Y367848D01*
G01X197130Y370226D02*
Y369735D01*
G01X176066Y391290D02*
X197130Y370226D01*
G01X207784Y370824D02*
X243464Y335144D01*
G01X205947Y370824D02*
X207784D01*
G01X205024Y371747D02*
X205947Y370824D01*
G01X205024Y373191D02*
Y371747D01*
G01X190575Y387640D02*
X205024Y373191D01*
G01X190555Y387620D02*
X190575Y387640D01*
G01X185961Y387620D02*
X190555D01*
G01X180787Y392794D02*
X185961Y387620D01*
G01X188092Y375448D02*
X173735D01*
G01X188093Y375449D02*
X188092Y375448D01*
G01X188715Y375449D02*
X188093D01*
G01X194874Y369290D02*
X188715Y375449D01*
G01X194874Y368769D02*
Y369290D01*
G01X198051Y365592D02*
X194874Y368769D01*
G01X207408Y365592D02*
X198051D01*
G01X241953Y331047D02*
X207408Y365592D01*
G01X208008Y366344D02*
X242492Y331860D01*
G01X198393Y366344D02*
X208008D01*
G01X195626Y369111D02*
X198393Y366344D01*
G01X195626Y369602D02*
Y369111D01*
G01X188928Y376300D02*
X195626Y369602D01*
G01X175255Y376300D02*
X188928D01*
G01X197015Y362913D02*
X207701D01*
G01X191690Y368238D02*
X197015Y362913D01*
G01X191690Y370045D02*
Y368238D01*
G01X187793Y373942D02*
X191690Y370045D01*
G01X174003Y373942D02*
X187793D01*
G01X174002Y373943D02*
X174003Y373942D01*
G01X173112Y373943D02*
X174002D01*
G01X173111Y373944D02*
X173112Y373943D01*
G01X172982Y373944D02*
X173111D01*
G01X263591Y334392D02*
X243152D01*
G01X263808Y334324D02*
X263591Y334392D01*
G01X253500Y328600D02*
X264900Y317200D01*
G01X240939Y328600D02*
X253500D01*
G01X265867Y330390D02*
X267061Y331584D01*
G01X262850Y330390D02*
X265867D01*
G01X260600Y332640D02*
X262850Y330390D01*
G01X242776Y332640D02*
X260600D01*
G01X257400Y330200D02*
X241602D01*
G01X262100Y325500D02*
X257400Y330200D01*
G01X263400Y325500D02*
X262100D01*
G01X265200Y323700D02*
X263400Y325500D01*
G01X265700Y323700D02*
X265200D01*
G01X242945Y333535D02*
X263936D01*
G01X261192Y335144D02*
X263568Y337520D01*
G01X243464Y335144D02*
X261192D01*
G01X257751Y331047D02*
X241953D01*
G01X262398Y326400D02*
X257751Y331047D01*
G01X263751Y326400D02*
X262398D01*
G01X292890Y314790D02*
X294800Y316700D01*
G01X290610Y314790D02*
X292890D01*
G01X289100Y316300D02*
X290610Y314790D01*
G01X287300Y316300D02*
X289100D01*
G01X285300Y318300D02*
X287300Y316300D01*
G01X284300Y318300D02*
X285300D01*
G01X282600Y320000D02*
X284300Y318300D01*
G01X280500Y320000D02*
X282600D01*
G01X278300Y322200D02*
X280500Y320000D01*
G01X277300Y322200D02*
X278300D01*
G01X275000Y324500D02*
X277300Y322200D01*
G01X274000Y324500D02*
X275000D01*
G01X272100Y326400D02*
X274000Y324500D01*
G01X270600Y326400D02*
X272100D01*
G01X268900Y328100D02*
X270600Y326400D01*
G01X267200Y328100D02*
X268900D01*
G01X265670Y329630D02*
X267200Y328100D01*
G01X262260Y329630D02*
X265670D01*
G01X260030Y331860D02*
X262260Y329630D01*
G01X242492Y331860D02*
X260030D01*
G01X265438Y317739D02*
Y317738D01*
G01X253815Y329360D02*
X265438Y317739D01*
G01X241254Y329360D02*
X253815D01*
G01X309892Y30231D02*
Y34299D01*
G01X307675Y28014D02*
X309892Y30231D01*
G01X309392Y26297D02*
X307675Y28014D01*
G01X309392Y18774D02*
Y26297D01*
G01X307675Y17057D02*
X309392Y18774D01*
G01X307675Y16829D02*
Y17057D01*
G01X309692Y14812D02*
X307675Y16829D01*
G01X309692Y10500D02*
Y14812D01*
G01X309404Y10212D02*
X309692Y10500D01*
G01X309404Y-2736D02*
Y10212D01*
G01X308157Y-3983D02*
X309404Y-2736D01*
G01X308157Y-7180D02*
Y-3983D01*
G01X309292Y66438D02*
X307928Y67802D01*
G01X309292Y56474D02*
Y66438D01*
G01X307675Y54857D02*
X309292Y56474D01*
G01X309892Y52640D02*
X307675Y54857D01*
G01X309892Y49500D02*
Y52640D01*
G01X309292Y48900D02*
X309892Y49500D01*
G01X309292Y34899D02*
Y48900D01*
G01X309892Y34299D02*
X309292Y34899D01*
G01X309092Y91240D02*
X307675Y92657D01*
G01X309092Y89200D02*
Y91240D01*
G01X309792Y88500D02*
X309092Y89200D01*
G01X309792Y86190D02*
Y88500D01*
G01X309292Y85690D02*
X309792Y86190D01*
G01X309292Y79300D02*
Y85690D01*
G01X310140Y78452D02*
X309292Y79300D01*
G01X310140Y68279D02*
Y78452D01*
G01X309663Y67802D02*
X310140Y68279D01*
G01X307928Y67802D02*
X309663D01*
G01X313604Y339504D02*
Y351835D01*
G01X310800Y336700D02*
X313604Y339504D01*
G01X311798Y339398D02*
Y347560D01*
G01X310000Y337600D02*
X311798Y339398D01*
G01X315178Y338478D02*
Y349509D01*
G01X313373Y336673D02*
X315178Y338478D01*
G01X313373Y327409D02*
Y336673D01*
G01X312449Y326485D02*
X313373Y327409D01*
G01X311785Y326485D02*
X312449D01*
G01X309600Y324300D02*
X311785Y326485D01*
G01X307407Y324300D02*
X309600D01*
G01X305007Y321900D02*
X307407Y324300D01*
G01X303571Y321900D02*
X305007D01*
G01X302305Y320634D02*
X303571Y321900D01*
G01X301134Y320634D02*
X302305D01*
G01X298700Y318200D02*
X301134Y320634D01*
G01X297100Y318200D02*
X298700D01*
G01X295600Y316700D02*
X297100Y318200D01*
G01X294800Y316700D02*
X295600D01*
G01X313604Y351835D02*
X315178Y353409D01*
G01X339492Y398781D02*
Y418901D01*
G01X339209Y398498D02*
X339492Y398781D01*
G01X339209Y392729D02*
Y398498D01*
G01X339092Y419301D02*
Y473944D01*
G01X339492Y418901D02*
X339092Y419301D01*
G01X308892Y516840D02*
X307675Y518057D01*
G01X308892Y514900D02*
Y516840D01*
G01X311092Y512700D02*
X308892Y514900D01*
G01X311092Y512600D02*
Y512700D01*
G01X313392Y510300D02*
X311092Y512600D01*
G01X313392Y499644D02*
Y510300D01*
G01X339092Y473944D02*
X313392Y499644D01*
G01X309392Y519774D02*
Y527669D01*
G01X307675Y518057D02*
X309392Y519774D01*
G01X309667Y587175D02*
Y591665D01*
G01X309392Y586900D02*
X309667Y587175D01*
G01X309392Y574099D02*
Y586900D01*
G01X309697Y573794D02*
X309392Y574099D01*
G01X309697Y568456D02*
Y573794D01*
G01X307984Y566743D02*
X309697Y568456D01*
G01X309392Y565335D02*
X307984Y566743D01*
G01X309392Y557574D02*
Y565335D01*
G01X307675Y555857D02*
X309392Y557574D01*
G01X309726Y553806D02*
X307675Y555857D01*
G01X309726Y549834D02*
Y553806D01*
G01X309292Y549400D02*
X309726Y549834D01*
G01X309292Y535542D02*
Y549400D01*
G01X309578Y535256D02*
X309292Y535542D01*
G01X309578Y530243D02*
Y535256D01*
G01X308198Y528863D02*
X309578Y530243D01*
G01X309392Y527669D02*
X308198Y528863D01*
G01X310102Y621800D02*
X307500Y624402D01*
G01X444636Y621800D02*
X310102D01*
G01X309667Y591665D02*
X307675Y593657D01*
G01X309392Y605985D02*
X308157Y607220D01*
G01X309392Y595374D02*
Y605985D01*
G01X307675Y593657D02*
X309392Y595374D01*
G01X308557Y620096D02*
X443929D01*
G01X306355Y622298D02*
X308557Y620096D01*
G01X308952Y621048D02*
X306750Y623250D01*
G01X444324Y621048D02*
X308952D01*
G01X407593Y-16026D02*
X405186Y-18433D01*
G01X463843Y-16026D02*
X407593D01*
G01X406803Y-14122D02*
X404396Y-16529D01*
G01X465442Y-14122D02*
X406803D01*
G01X406179Y-12618D02*
X403772Y-15025D01*
G01X466066Y-12618D02*
X406179D01*
G01X407115Y-14874D02*
X404708Y-17281D01*
G01X465130Y-14874D02*
X407115D01*
G01X406491Y-13370D02*
X404084Y-15777D01*
G01X465754Y-13370D02*
X406491D01*
G01X405867Y-11866D02*
X403460Y-14273D01*
G01X466378Y-11866D02*
X405867D01*
G01X408177Y-17434D02*
X463259D01*
G01X405515Y-20096D02*
X408177Y-17434D01*
G01X445510Y-50496D02*
G02Y-53848I0J-1676D01*
G01X466250Y-18433D02*
X463843Y-16026D01*
G01X647572Y-18433D02*
X466250D01*
G01X467125Y-15805D02*
X465442Y-14122D01*
G01X646588Y-15805D02*
X467125D01*
G01X467748Y-14300D02*
X466066Y-12618D01*
G01X616600Y-14300D02*
X467748D01*
G01X466832Y-16576D02*
X465130Y-14874D01*
G01X647085Y-16576D02*
X466832D01*
G01X467436Y-15052D02*
X465754Y-13370D01*
G01X646277Y-15052D02*
X467436D01*
G01X468060Y-13548D02*
X466378Y-11866D01*
G01X614695Y-13548D02*
X468060D01*
G01X465666Y-19841D02*
X649327D01*
G01X463259Y-17434D02*
X465666Y-19841D01*
G01X460630Y278470D02*
Y314532D01*
G01X477900Y269800D02*
X479700Y268000D01*
G01X475800Y269800D02*
X477900D01*
G01X474400Y271200D02*
X475800Y269800D01*
G01X472800Y271200D02*
X474400D01*
G01X471600Y272400D02*
X472800Y271200D01*
G01X467700Y272400D02*
X471600D01*
G01X465100Y275000D02*
X467700Y272400D01*
G01X465100Y280300D02*
Y275000D01*
G01X477300Y264900D02*
X479100Y263100D01*
G01X475560Y264900D02*
X477300D01*
G01X473943Y266517D02*
X475560Y264900D01*
G01X472417Y266517D02*
X473943D01*
G01X470800Y264900D02*
X472417Y266517D01*
G01X469200Y264900D02*
X470800D01*
G01X467200Y266900D02*
X469200Y264900D01*
G01X465500Y266900D02*
X467200D01*
G01X463800Y268600D02*
X465500Y266900D01*
G01X463800Y271900D02*
Y268600D01*
G01X462500Y273200D02*
X463800Y271900D01*
G01X459600Y273200D02*
X462500D01*
G01X458400Y274400D02*
X459600Y273200D01*
G01X458400Y276400D02*
Y274400D01*
G01X456838Y277962D02*
Y280777D01*
G01X458400Y276400D02*
X456838Y277962D01*
G01X461912Y317627D02*
X463671Y319386D01*
G01X460630Y314532D02*
X461912Y317627D01*
G01X463671Y325271D02*
Y319386D01*
G01X463973Y326000D02*
X463671Y325271D01*
G01X467135Y333635D02*
X463973Y326000D01*
G01X469000Y335500D02*
X467135Y333635D01*
G01X472800Y335500D02*
X469000D01*
G01X471600Y337300D02*
X472100Y337800D01*
G01X469402Y337300D02*
X471600D01*
G01X459361Y327259D02*
X469402Y337300D01*
G01X459361Y283300D02*
Y327259D01*
G01X456838Y280777D02*
X459361Y283300D01*
G01X477862Y290672D02*
G02X479807Y289509I-70J-2325D01*
G01X474872Y290672D02*
X477862D01*
G01X472200Y288000D02*
X474872Y290672D01*
G01X467660Y288000D02*
X472200D01*
G01X466734Y287074D02*
X467660Y288000D01*
G01X443563Y615074D02*
X616425D01*
G01X442704Y615933D02*
X443563Y615074D01*
G01X443733Y617100D02*
X443396Y617437D01*
G01X616527Y617100D02*
X443733D01*
G01X445036Y621400D02*
X444636Y621800D01*
G01X619134Y621400D02*
X445036D01*
G01X443874Y615827D02*
X443016Y616685D01*
G01X616736Y615827D02*
X443874D01*
G01X443251Y614322D02*
X442392Y615181D01*
G01X616113Y614322D02*
X443251D01*
G01X443737Y618160D02*
X443708Y618189D01*
G01X616531Y618160D02*
X443737D01*
G01X444048Y618913D02*
X444020Y618941D01*
G01X616842Y618913D02*
X444048D01*
G01X444360Y619665D02*
X618483D01*
G01X443929Y620096D02*
X444360Y619665D01*
G01X444724Y620648D02*
X444324Y621048D01*
G01X618822Y620648D02*
X444724D01*
G01X537900Y215900D02*
X535600Y218200D01*
G01X539300Y215900D02*
X537900D01*
G01X541100Y214100D02*
X539300Y215900D01*
G01X521731Y238269D02*
Y239596D01*
G01X523500Y236500D02*
X521731Y238269D01*
G01X523500Y228700D02*
Y236500D01*
G01X524400Y227800D02*
X523500Y228700D01*
G01X525700Y227800D02*
X524400D01*
G01X527300Y226200D02*
X525700Y227800D01*
G01X528700Y226200D02*
X527300D01*
G01X530600Y224300D02*
X528700Y226200D01*
G01X532400Y224300D02*
X530600D01*
G01X534600Y222100D02*
X532400Y224300D01*
G01X535800Y222100D02*
X534600D01*
G01X538000Y219900D02*
X535800Y222100D01*
G01X539500Y219900D02*
X538000D01*
G01X541300Y218100D02*
X539500Y219900D01*
G01X539200Y223800D02*
X540800Y222200D01*
G01X538000Y223800D02*
X539200D01*
G01X536200Y225600D02*
X538000Y223800D01*
G01X534600Y225600D02*
X536200D01*
G01X532350Y227850D02*
X534600Y225600D01*
G01X531050Y227850D02*
X532350D01*
G01X529400Y229500D02*
X531050Y227850D01*
G01X528400Y229500D02*
X529400D01*
G01X526809Y231091D02*
X528400Y229500D01*
G01X526809Y237803D02*
Y231091D01*
G01X539100Y243400D02*
X537600D01*
G01X541000Y241500D02*
X539100Y243400D01*
G01X539000Y232100D02*
X541200Y229900D01*
G01X538000Y232100D02*
X539000D01*
G01X536000Y234100D02*
X538000Y232100D01*
G01X533784Y234100D02*
X536000D01*
G01X531812Y236072D02*
X533784Y234100D01*
G01X530506Y236859D02*
G03X531812Y236072I1365J788D01*
G01X528576Y238021D02*
G02X530506Y236859I-85J-2325D01*
G01X518352Y236248D02*
Y237647D01*
G01X520100Y234500D02*
X518352Y236248D01*
G01X520100Y227200D02*
Y234500D01*
G01X521200Y226100D02*
X520100Y227200D01*
G01X522400Y226100D02*
X521200D01*
G01X524600Y223900D02*
X522400Y226100D01*
G01X526100Y223900D02*
X524600D01*
G01X527800Y222200D02*
X526100Y223900D01*
G01X528900Y222200D02*
X527800D01*
G01X531100Y220000D02*
X528900Y222200D01*
G01X532600Y220000D02*
X531100D01*
G01X534400Y218200D02*
X532600Y220000D01*
G01X535600Y218200D02*
X534400D01*
G01X509806Y270961D02*
X511592Y272747D01*
G01X509806Y270135D02*
Y270961D01*
G01X508873Y269202D02*
X509806Y270135D01*
G01X507442Y269202D02*
X508873D01*
G01X505493Y267253D02*
X507442Y269202D01*
G01X504064Y267253D02*
X505493D01*
G01X502113Y265302D02*
X504064Y267253D01*
G01X501302Y265302D02*
X502113D01*
G01X499353Y263353D02*
X501302Y265302D01*
G01X496590Y263353D02*
X499353D01*
G01X495353Y264590D02*
X496590Y263353D01*
G01X494010Y264590D02*
X495353D01*
G01X492059Y266541D02*
X494010Y264590D01*
G01X489832Y266541D02*
X492059D01*
G01X488593Y265302D02*
X489832Y266541D01*
G01X487271Y265302D02*
X488593D01*
G01X486273Y266300D02*
X487271Y265302D01*
G01X484700Y266300D02*
X486273D01*
G01X483000Y268000D02*
X484700Y266300D01*
G01X479700Y268000D02*
X483000D01*
G01X480800Y263100D02*
X482265Y264565D01*
G01X479100Y263100D02*
X480800D01*
G01X508979Y253000D02*
X504832Y257147D01*
G01X519204Y266896D02*
X508212D01*
G01X520800Y265300D02*
X519204Y266896D01*
G01X523000Y265300D02*
X520800D01*
G01X524202Y266502D02*
X523000Y265300D01*
G01X538716Y270422D02*
G03X540646Y271584I-85J2325D01*
G01X538587Y270422D02*
X538716D01*
G01X537266Y269634D02*
G02X538587Y270422I1365J-787D01*
G01X535321Y268471D02*
G03X537266Y269634I-70J2325D01*
G01X535192Y268471D02*
X535321D01*
G01X533886Y267684D02*
G02X535192Y268471I1365J-788D01*
G01X531956Y266522D02*
G03X533886Y267684I-85J2325D01*
G01X531827Y266522D02*
X531956D01*
G01X530506Y265734D02*
G02X531827Y266522I1365J-787D01*
G01X528491Y262996D02*
G03X530506Y265734I-11227J10372D01*
G01X533677Y241300D02*
X533470Y241093D01*
G01X536100Y241300D02*
X533677D01*
G01X537700Y239700D02*
X536100Y241300D01*
G01X538900Y239700D02*
X537700D01*
G01X541100Y237500D02*
X538900Y239700D01*
G01X534700Y237600D02*
X533006Y239294D01*
G01X536200Y237600D02*
X534700D01*
G01X537800Y236000D02*
X536200Y237600D01*
G01X538800Y236000D02*
X537800D01*
G01X541300Y233500D02*
X538800Y236000D01*
G01X516453Y249600D02*
X516987Y250134D01*
G01X514300Y249600D02*
X516453D01*
G01X511592Y252308D02*
X514300Y249600D01*
G01X511592Y253247D02*
Y252308D01*
G01X491800Y341000D02*
X494100Y343300D01*
G01X490400Y341000D02*
X491800D01*
G01X488300Y338900D02*
X490400Y341000D01*
G01X487100Y338900D02*
X488300D01*
G01X485400Y337200D02*
X487100Y338900D01*
G01X483600Y337200D02*
X485400D01*
G01X484694Y286772D02*
X487932Y286396D01*
G01X484493Y286772D02*
X484694D01*
G01X483187Y287559D02*
G03X484493Y286772I1365J788D01*
G01X481257Y288721D02*
G02X483187Y287559I-85J-2325D01*
G01X481128Y288721D02*
X481257D01*
G01X479807Y289509D02*
G03X481128Y288721I1365J787D01*
G01X525900Y341000D02*
X527700Y342800D01*
G01X524600Y341000D02*
X525900D01*
G01X522300Y338700D02*
X524600Y341000D01*
G01X520600Y338700D02*
X522300D01*
G01X518600Y336700D02*
X520600Y338700D01*
G01X517100Y336700D02*
X518600D01*
G01X515500Y335100D02*
X517100Y336700D01*
G01X514000Y335100D02*
X515500D01*
G01X512000Y333100D02*
X514000Y335100D01*
G01X510700Y333100D02*
X512000D01*
G01X508600Y331000D02*
X510700Y333100D01*
G01X507000Y331000D02*
X508600D01*
G01X505300Y329300D02*
X507000Y331000D01*
G01X504300Y329300D02*
X505300D01*
G01X502100Y327100D02*
X504300Y329300D01*
G01X500200Y327100D02*
X502100D01*
G01X498400Y325300D02*
X500200Y327100D01*
G01X497300Y325300D02*
X498400D01*
G01X496400Y324400D02*
X497300Y325300D01*
G01X496400Y320400D02*
Y324400D01*
G01X495900Y319900D02*
X496400Y320400D01*
G01X495900Y318800D02*
Y319900D01*
G01X494696Y317596D02*
X495900Y318800D01*
G01X494692Y317596D02*
X494696D01*
G01X485332Y340617D02*
X487281Y342566D01*
G01X483901Y340617D02*
X485332D01*
G01X482710Y339426D02*
X483901Y340617D01*
G01X481281Y339426D02*
X482710D01*
G01X479602Y337747D02*
X481281Y339426D01*
G01X479602Y330866D02*
Y337747D01*
G01X481172Y329296D02*
X479602Y330866D01*
G01X539200Y368100D02*
X541700Y370600D01*
G01X538100Y368100D02*
X539200D01*
G01X535934Y365934D02*
X538100Y368100D01*
G01X535902Y365966D02*
X535934Y365934D01*
G01X534600Y365966D02*
X535902D01*
G01X533681Y365047D02*
X534600Y365966D01*
G01X533681Y364881D02*
Y365047D01*
G01X532670Y363870D02*
X533681Y364881D01*
G01X532522Y364017D02*
X532670Y363870D01*
G01X531220Y364017D02*
X532522D01*
G01X531003Y363800D02*
X531220Y364017D01*
G01X530600Y363800D02*
X531003D01*
G01X529100Y362300D02*
X530600Y363800D01*
G01X527400Y362300D02*
X529100D01*
G01X525400Y360300D02*
X527400Y362300D01*
G01X523700Y360300D02*
X525400D01*
G01X523301Y359901D02*
X523700Y360300D01*
G01X523301Y359845D02*
Y359901D01*
G01X522382Y358926D02*
X523301Y359845D01*
G01X522326Y358926D02*
X522382D01*
G01X521566Y358166D02*
X522326Y358926D01*
G01X521080Y358166D02*
X521566D01*
G01X521014Y358100D02*
X521080Y358166D01*
G01X520300Y358100D02*
X521014D01*
G01X518800Y356600D02*
X520300Y358100D01*
G01X517500Y356600D02*
X518800D01*
G01X515200Y354300D02*
X517500Y356600D01*
G01X513900Y354300D02*
X515200D01*
G01X512300Y352700D02*
X513900Y354300D01*
G01X511000Y352700D02*
X512300D01*
G01X509200Y350900D02*
X511000Y352700D01*
G01X507900Y350900D02*
X509200D01*
G01X505417Y348417D02*
X507900Y350900D01*
G01X504181Y348417D02*
X505417D01*
G01X504064Y348300D02*
X504181Y348417D01*
G01X503500Y348300D02*
X504064D01*
G01X502000Y346800D02*
X503500Y348300D01*
G01X500400Y346800D02*
X502000D01*
G01X498300Y344700D02*
X500400Y346800D01*
G01X497300Y344700D02*
X498300D01*
G01X495900Y343300D02*
X497300Y344700D01*
G01X494100Y343300D02*
X495900D01*
G01X539200Y348800D02*
X541200Y350800D01*
G01X537900Y348800D02*
X539200D01*
G01X535700Y346600D02*
X537900Y348800D01*
G01X534100Y346600D02*
X535700D01*
G01X532400Y344900D02*
X534100Y346600D01*
G01X530900Y344900D02*
X532400D01*
G01X528800Y342800D02*
X530900Y344900D01*
G01X527700Y342800D02*
X528800D01*
G01X539282Y372576D02*
X540473Y373767D01*
G01X538376Y372576D02*
X539282D01*
G01X536300Y370500D02*
X538376Y372576D01*
G01X534345Y370500D02*
X536300D01*
G01X532522Y368677D02*
X534345Y370500D01*
G01X531577Y368677D02*
X532522D01*
G01X528866Y365966D02*
X531577Y368677D01*
G01X527840Y365966D02*
X528866D01*
G01X525891Y364017D02*
X527840Y365966D01*
G01X524460Y364017D02*
X525891D01*
G01X522509Y362066D02*
X524460Y364017D01*
G01X521080Y362066D02*
X522509D01*
G01X519891Y360877D02*
X521080Y362066D01*
G01X518461Y360877D02*
X519891D01*
G01X515750Y358166D02*
X518461Y360877D01*
G01X514321Y358166D02*
X515750D01*
G01X512322Y356167D02*
X514321Y358166D01*
G01X510962Y356167D02*
X512322D01*
G01X509595Y354800D02*
X510962Y356167D01*
G01X508095Y354800D02*
X509595D01*
G01X505612Y352317D02*
X508095Y354800D01*
G01X504181Y352317D02*
X505612D01*
G01X502864Y351000D02*
X504181Y352317D01*
G01X501200Y351000D02*
X502864D01*
G01X498617Y348417D02*
X501200Y351000D01*
G01X497421Y348417D02*
X498617D01*
G01X495470Y346466D02*
X497421Y348417D01*
G01X494041Y346466D02*
X495470D01*
G01X492775Y345200D02*
X494041Y346466D01*
G01X490500Y345200D02*
X492775D01*
G01X487866Y342566D02*
X490500Y345200D01*
G01X487281Y342566D02*
X487866D01*
G01X611374Y142574D02*
X547126Y206822D01*
G01X612003Y144068D02*
X547982Y208089D01*
G01X610396Y141922D02*
X546818Y205500D01*
G01X544500Y216300D02*
X542700Y218100D01*
G01X545800Y216300D02*
X544500D01*
G01X547500Y214600D02*
X545800Y216300D01*
G01X548800Y214600D02*
X547500D01*
G01X551704Y211696D02*
X548800Y214600D01*
G01X554383Y205231D02*
X551704Y211696D01*
G01X614127Y145488D02*
X554383Y205231D01*
G01X588820Y205880D02*
X630900Y163800D01*
G01X588820Y216420D02*
Y205880D01*
G01X590600Y218200D02*
X588820Y216420D01*
G01X555484Y205902D02*
X615189Y146198D01*
G01X555443Y206000D02*
X555484Y205902D01*
G01X553900Y209724D02*
X555443Y206000D01*
G01X553900Y214900D02*
Y209724D01*
G01X552600Y216200D02*
X553900Y214900D01*
G01X551300Y216200D02*
X552600D01*
G01X549200Y218300D02*
X551300Y216200D01*
G01X587500Y205400D02*
X631000Y161900D01*
G01X587500Y217000D02*
Y205400D01*
G01X589300Y218800D02*
X587500Y217000D01*
G01X573500Y211478D02*
X565068Y231832D01*
G01X573500Y204914D02*
Y211478D01*
G01X579096Y191404D02*
X573500Y204914D01*
G01X626100Y144400D02*
X579096Y191404D01*
G01X576774Y187826D02*
X625116Y139484D01*
G01X569800Y204663D02*
X576774Y187826D01*
G01X569800Y210734D02*
Y204663D01*
G01X566501Y218699D02*
X569800Y210734D01*
G01X542620Y214100D02*
X541100D01*
G01X544220Y212500D02*
X542620Y214100D01*
G01X546000Y212500D02*
X544220D01*
G01X548429Y210071D02*
X546000Y212500D01*
G01X548994Y208707D02*
X548429Y210071D01*
G01X550448Y207253D02*
X548994Y208707D01*
G01X550589Y207253D02*
X550448D01*
G01X551842Y206000D02*
X550589Y207253D01*
G01X613065Y144778D02*
X551842Y206000D01*
G01X547126Y206822D02*
X543100D01*
G01X584876Y204424D02*
X630000Y159300D01*
G01X584876Y217746D02*
Y204424D01*
G01X586752Y219622D02*
X584876Y217746D01*
G01X547982Y208089D02*
X545273D01*
G01X572200Y211061D02*
X565102Y228198D01*
G01X572200Y204921D02*
Y211061D01*
G01X578508Y189692D02*
X572200Y204921D01*
G01X626770Y141430D02*
X578508Y189692D01*
G01X542900Y205500D02*
X542341Y206059D01*
G01X546818Y205500D02*
X542900D01*
G01X571000Y210861D02*
X565486Y224174D01*
G01X571000Y204804D02*
Y210861D01*
G01X577721Y188579D02*
X571000Y204804D01*
G01X625787Y140513D02*
X577721Y188579D01*
G01X586128Y204972D02*
X630600Y160500D01*
G01X586128Y217368D02*
Y204972D01*
G01X588000Y219240D02*
X586128Y217368D01*
G01X570479Y251393D02*
X618279D01*
G01X560451Y261421D02*
X570479Y251393D01*
G01X542700Y218100D02*
X541300D01*
G01X590600Y225900D02*
Y218200D01*
G01X603800Y239100D02*
X590600Y225900D01*
G01X569625Y271800D02*
X605440D01*
G01X547700Y218300D02*
X549200D01*
G01X546000Y220000D02*
X547700Y218300D01*
G01X544600Y220000D02*
X546000D01*
G01X542400Y222200D02*
X544600Y220000D01*
G01X540800Y222200D02*
X542400D01*
G01X589300Y226900D02*
Y218800D01*
G01X603300Y240900D02*
X589300Y226900D01*
G01X569500Y270475D02*
X603791D01*
G01X542400Y241500D02*
X541000D01*
G01X544400Y239500D02*
X542400Y241500D01*
G01X545800Y239500D02*
X544400D01*
G01X548000Y237300D02*
X545800Y239500D01*
G01X549600Y237300D02*
X548000D01*
G01X551100Y235800D02*
X549600Y237300D01*
G01X552800Y235800D02*
X551100D01*
G01X554600Y234000D02*
X552800Y235800D01*
G01X562900Y234000D02*
X554600D01*
G01X565068Y231832D02*
X562900Y234000D01*
G01X563500Y221700D02*
X566501Y218699D01*
G01X561200Y221700D02*
X563500D01*
G01X559900Y220400D02*
X561200Y221700D01*
G01X558000Y220400D02*
X559900D01*
G01X556100Y222300D02*
X558000Y220400D01*
G01X554600Y222300D02*
X556100D01*
G01X553000Y223900D02*
X554600Y222300D01*
G01X551200Y223900D02*
X553000D01*
G01X549300Y225800D02*
X551200Y223900D01*
G01X548100Y225800D02*
X549300D01*
G01X545800Y228100D02*
X548100Y225800D01*
G01X544200Y228100D02*
X545800D01*
G01X542400Y229900D02*
X544200Y228100D01*
G01X541200Y229900D02*
X542400D01*
G01X586752Y230248D02*
Y219622D01*
G01X585276Y231724D02*
X586752Y230248D01*
G01X585276Y235724D02*
Y231724D01*
G01X572900Y248100D02*
X585276Y235724D01*
G01X568300Y248100D02*
X572900D01*
G01X560481Y279328D02*
X643724Y362571D01*
G01X559529Y278933D02*
X560481Y279328D01*
G01X558973Y278933D02*
X559529D01*
G01X555983Y280171D02*
X558973Y278933D01*
G01X554166Y279384D02*
G02X555472Y280171I1365J-788D01*
G01X552202Y278221D02*
G03X554166Y279384I-51J2326D01*
G01X552107Y278221D02*
X552202D01*
G01X550786Y277433D02*
G02X552107Y278221I1365J-787D01*
G01X548856Y276271D02*
G03X550786Y277433I-85J2325D01*
G01X548727Y276271D02*
X548856D01*
G01X547406Y275483D02*
G02X548727Y276271I1365J-787D01*
G01X545476Y274321D02*
G03X547406Y275483I-85J2325D01*
G01X545320Y274321D02*
X545476D01*
G01X544026Y273534D02*
G02X545320Y274321I1365J-787D01*
G01X542081Y272371D02*
G03X544026Y273534I-70J2325D01*
G01X541952Y272371D02*
X542081D01*
G01X540646Y271584D02*
G02X541952Y272371I1365J-788D01*
G01X542700Y237500D02*
X541100D01*
G01X544400Y235800D02*
X542700Y237500D01*
G01X545600Y235800D02*
X544400D01*
G01X547900Y233500D02*
X545600Y235800D01*
G01X549500Y233500D02*
X547900D01*
G01X551400Y231600D02*
X549500Y233500D01*
G01X552900Y231600D02*
X551400D01*
G01X554900Y229600D02*
X552900Y231600D01*
G01X556400Y229600D02*
X554900D01*
G01X557800Y228200D02*
X556400Y229600D01*
G01X560400Y228200D02*
X557800D01*
G01X561700Y229500D02*
X560400Y228200D01*
G01X563800Y229500D02*
X561700D01*
G01X565102Y228198D02*
X563800Y229500D01*
G01X542900Y233500D02*
X541300D01*
G01X544800Y231600D02*
X542900Y233500D01*
G01X545900Y231600D02*
X544800D01*
G01X547900Y229600D02*
X545900Y231600D01*
G01X549600Y229600D02*
X547900D01*
G01X551500Y227700D02*
X549600Y229600D01*
G01X553000Y227700D02*
X551500D01*
G01X554800Y225900D02*
X553000Y227700D01*
G01X556000Y225900D02*
X554800D01*
G01X557700Y224200D02*
X556000Y225900D01*
G01X559900Y224200D02*
X557700D01*
G01X561300Y225600D02*
X559900Y224200D01*
G01X564060Y225600D02*
X561300D01*
G01X565486Y224174D02*
X564060Y225600D01*
G01X561001Y276271D02*
X644773Y360043D01*
G01X588000Y234700D02*
Y219240D01*
G01X573300Y249400D02*
X588000Y234700D01*
G01X570700Y249400D02*
X573300D01*
G01X558965Y289935D02*
X554645Y285615D01*
G01X558965Y290851D02*
Y289935D01*
G01X661424Y393310D02*
X558965Y290851D01*
G01X556518Y284094D02*
X554963D01*
G01X557932Y282680D02*
X556518Y284094D01*
G01X559587Y282680D02*
X557932D01*
G01X562509Y283890D02*
X559587Y282680D01*
G01X663574Y384955D02*
X562509Y283890D01*
G01X555472Y280171D02*
X555983D01*
G01X553900Y392800D02*
X550500Y389400D01*
G01X553900Y401594D02*
Y392800D01*
G01X613021Y460715D02*
X553900Y401594D01*
G01X562800Y374900D02*
X560100Y372200D01*
G01X562800Y389262D02*
Y374900D01*
G01X565344Y391806D02*
X562800Y389262D01*
G01X565344Y392465D02*
Y391806D01*
G01X609425Y436546D02*
X565344Y392465D01*
G01X547093Y396417D02*
X612543Y461867D01*
G01X547093Y393493D02*
Y396417D01*
G01X569820Y398288D02*
X609030Y437498D01*
G01X561624Y398288D02*
X569820D01*
G01X557300Y393964D02*
X561624Y398288D01*
G01X557300Y379500D02*
Y393964D01*
G01X554000Y376200D02*
X557300Y379500D01*
G01X551200Y376200D02*
X554000D01*
G01X549200Y374200D02*
X551200Y376200D01*
G01X547700Y374200D02*
X549200D01*
G01X545700Y372200D02*
X547700Y374200D01*
G01X544600Y372200D02*
X545700D01*
G01X543000Y370600D02*
X544600Y372200D01*
G01X541700Y370600D02*
X543000D01*
G01X567100Y389739D02*
Y369400D01*
G01X567248Y389887D02*
X567100Y389739D01*
G01X567248Y391675D02*
Y389887D01*
G01X610215Y434642D02*
X567248Y391675D01*
G01X566296Y392070D02*
X609820Y435594D01*
G01X566296Y390324D02*
Y392070D01*
G01X565000Y389028D02*
X566296Y390324D01*
G01X565000Y369900D02*
Y389028D01*
G01X559122Y364022D02*
X565000Y369900D01*
G01X554400Y364022D02*
X559122D01*
G01X568200Y391280D02*
X610610Y433690D01*
G01X568200Y369100D02*
Y391280D01*
G01X555300Y356200D02*
X568200Y369100D01*
G01X550800Y356200D02*
X555300D01*
G01X548900Y354300D02*
X550800Y356200D01*
G01X547700Y354300D02*
X548900D01*
G01X545800Y352400D02*
X547700Y354300D01*
G01X544300Y352400D02*
X545800D01*
G01X542700Y350800D02*
X544300Y352400D01*
G01X541200Y350800D02*
X542700D01*
G01X561288Y399582D02*
Y407352D01*
G01X555200Y393494D02*
X561288Y399582D01*
G01X555200Y392400D02*
Y393494D01*
G01X553700Y390900D02*
X555200Y392400D01*
G01X553700Y382619D02*
Y390900D01*
G01X553721Y382598D02*
X553700Y382619D01*
G01X553721Y381296D02*
Y382598D01*
G01X553700Y381275D02*
X553721Y381296D01*
G01X553700Y380900D02*
Y381275D01*
G01X553000Y380200D02*
X553700Y380900D01*
G01X551300Y380200D02*
X553000D01*
G01X548766Y377666D02*
X551300Y380200D01*
G01X548120Y377666D02*
X548766D01*
G01X546931Y376477D02*
X548120Y377666D01*
G01X545501Y376477D02*
X546931D01*
G01X542791Y373767D02*
X545501Y376477D01*
G01X540473Y373767D02*
X542791D01*
G01X561288Y407352D02*
X613499Y459563D01*
G01X649500Y31891D02*
Y43198D01*
G01X648867Y31258D02*
X649500Y31891D01*
G01X651728Y-14277D02*
X647572Y-18433D01*
G01X651728Y-452D02*
Y-14277D01*
G01X660626Y8446D02*
X651728Y-452D01*
G01X660626Y11865D02*
Y8446D01*
G01X661315Y12554D02*
X660626Y11865D01*
G01X673914Y12554D02*
X661315D01*
G01X649824Y-12569D02*
X646588Y-15805D01*
G01X649824Y467D02*
Y-12569D01*
G01X658570Y9213D02*
X649824Y467D01*
G01X658570Y12503D02*
Y9213D01*
G01X660525Y14458D02*
X658570Y12503D01*
G01X672129Y14458D02*
X660525D01*
G01X631840Y940D02*
X616600Y-14300D01*
G01X648169Y940D02*
X631840D01*
G01X656180Y8951D02*
X648169Y940D01*
G01X656180Y12241D02*
Y8951D01*
G01X659901Y15962D02*
X656180Y12241D01*
G01X671052Y15962D02*
X659901D01*
G01X650576Y-13085D02*
X647085Y-16576D01*
G01X650576Y155D02*
Y-13085D01*
G01X659329Y8908D02*
X650576Y155D01*
G01X659329Y12198D02*
Y8908D01*
G01X660837Y13706D02*
X659329Y12198D01*
G01X672705Y13706D02*
X660837D01*
G01X649072Y-12257D02*
X646277Y-15052D01*
G01X649072Y779D02*
Y-12257D01*
G01X657390Y9097D02*
X649072Y779D01*
G01X657390Y12387D02*
Y9097D01*
G01X660213Y15210D02*
X657390Y12387D01*
G01X671449Y15210D02*
X660213D01*
G01X650652Y32015D02*
Y43676D01*
G01X651442Y31225D02*
X650652Y32015D01*
G01X662700Y-4552D02*
Y-17900D01*
G01X672221Y4969D02*
X662700Y-4552D01*
G01X630173Y1930D02*
X614695Y-13548D01*
G01X647600Y1930D02*
X630173D01*
G01X655280Y9610D02*
X647600Y1930D01*
G01X655280Y12405D02*
Y9610D01*
G01X659635Y16760D02*
X655280Y12405D01*
G01X669890Y16760D02*
X659635D01*
G01X662666Y8071D02*
X663395D01*
G01X653471Y-1124D02*
X662666Y8071D01*
G01X653471Y-2408D02*
Y-1124D01*
G01X653472Y-2409D02*
X653471Y-2408D01*
G01X653472Y-15696D02*
Y-2409D01*
G01X649327Y-19841D02*
X653472Y-15696D01*
G01X654545Y92054D02*
X652718Y93881D01*
G01X654545Y85645D02*
Y92054D01*
G01X646826Y77926D02*
X654545Y85645D01*
G01X646826Y45872D02*
Y77926D01*
G01X649500Y43198D02*
X646826Y45872D01*
G01X662352Y89566D02*
X655980Y95938D01*
G01X671398Y90853D02*
X634347Y106200D01*
G01X656661Y86061D02*
X664471D01*
G01X648405Y77805D02*
X656661Y86061D01*
G01X648405Y45989D02*
Y77805D01*
G01X650500Y43894D02*
X648405Y45989D01*
G01X650500Y43828D02*
Y43894D01*
G01X650652Y43676D02*
X650500Y43828D01*
G01X660500Y89788D02*
X655328Y94960D01*
G01X660500Y89185D02*
Y89788D01*
G01X661695Y87990D02*
X660500Y89185D01*
G01X667900Y87990D02*
X661695D01*
G01X624044Y121549D02*
X614127Y145488D01*
G01X629313Y116280D02*
X624044Y121549D01*
G01X635569Y113689D02*
X629313Y116280D01*
G01X661066Y103128D02*
X635569Y113689D01*
G01X670084Y94110D02*
X661066Y103128D01*
G01X661776Y104190D02*
X670794Y95172D01*
G01X661021Y104503D02*
X661776Y104190D01*
G01X630021Y117344D02*
X661021Y104503D01*
G01X625106Y122259D02*
X630021Y117344D01*
G01X615189Y146198D02*
X625106Y122259D01*
G01X636289Y144400D02*
X626100D01*
G01X663567Y133100D02*
X636289Y144400D01*
G01X649702Y129300D02*
X664413D01*
G01X625116Y139484D02*
X649702Y129300D01*
G01X622982Y120839D02*
X613065Y144778D01*
G01X628603Y115218D02*
X622982Y120839D01*
G01X660356Y102066D02*
X628603Y115218D01*
G01X669374Y93048D02*
X660356Y102066D01*
G01X622112Y116653D02*
X611374Y142574D01*
G01X633528Y105237D02*
X622112Y116653D01*
G01X633866Y105098D02*
X633528Y105237D01*
G01X633882Y105091D02*
X633866Y105098D01*
G01X633890Y105088D02*
X633882Y105091D01*
G01X655980Y95938D02*
X633890Y105088D01*
G01X622981Y117566D02*
X612003Y144068D01*
G01X634347Y106200D02*
X622981Y117566D01*
G01X650020Y131800D02*
X626770Y141430D01*
G01X664506Y131800D02*
X650020D01*
G01X621135Y116000D02*
X610396Y141922D01*
G01X632876Y104258D02*
X621135Y116000D01*
G01X633301Y104084D02*
X632876Y104258D01*
G01X633416Y104037D02*
X633301Y104084D01*
G01X633449Y104023D02*
X633416Y104037D01*
G01X633467Y104016D02*
X633449Y104023D01*
G01X655328Y94960D02*
X633467Y104016D01*
G01X649719Y130600D02*
X625787Y140513D01*
G01X664343Y130600D02*
X649719D01*
G01X634177Y212724D02*
Y243797D01*
G01X726316Y120585D02*
X634177Y212724D01*
G01X655462Y196488D02*
Y234849D01*
G01X728972Y122978D02*
X655462Y196488D01*
G01X630900Y163800D02*
X670640D01*
G01X629855Y214545D02*
X724812Y119588D01*
G01X629855Y243691D02*
Y214545D01*
G01X635085Y213514D02*
X727068Y121531D01*
G01X635085Y248034D02*
Y213514D01*
G01X660331Y198139D02*
X738700Y119770D01*
G01X660331Y238769D02*
Y198139D01*
G01X631000Y161900D02*
X670700D01*
G01X630751Y214949D02*
X725564Y120136D01*
G01X630751Y243860D02*
Y214949D01*
G01X639624Y210676D02*
Y249057D01*
G01X727690Y122610D02*
X639624Y210676D01*
G01X658106Y197104D02*
X732866Y122344D01*
G01X658106Y235465D02*
Y197104D01*
G01X630000Y159300D02*
X669550D01*
G01X656954Y196626D02*
X729724Y123856D01*
G01X656954Y234987D02*
Y196626D01*
G01X661483Y198617D02*
Y239417D01*
G01X740000Y120100D02*
X661483Y198617D01*
G01X662783Y198417D02*
X741700Y119500D01*
G01X662783Y240537D02*
Y198417D01*
G01X629027Y213673D02*
Y242889D01*
G01X723660Y119040D02*
X629027Y213673D01*
G01X659179Y197661D02*
Y237821D01*
G01X737200Y119640D02*
X659179Y197661D01*
G01X626486Y170014D02*
Y238514D01*
G01X628650Y167850D02*
X626486Y170014D01*
G01X631299Y165200D02*
X628650Y167850D01*
G01X671400Y165200D02*
X631299D01*
G01X630600Y160500D02*
X669980D01*
G01X623149Y262272D02*
Y328737D01*
G01X628624Y256797D02*
X623149Y262272D01*
G01X628624Y247051D02*
Y256797D01*
G01X631069Y244606D02*
X628624Y247051D01*
G01X633368Y244606D02*
X631069D01*
G01X634177Y243797D02*
X633368Y244606D01*
G01X627305Y277982D02*
X629259Y279936D01*
G01X627305Y263006D02*
Y277982D01*
G01X655462Y234849D02*
X627305Y263006D01*
G01X643500Y278233D02*
X645800Y280533D01*
G01X643500Y274868D02*
Y278233D01*
G01X614600Y239100D02*
X603800D01*
G01X622458Y246958D02*
X614600Y239100D01*
G01X622458Y254782D02*
Y246958D01*
G01X621165Y256075D02*
X622458Y254782D01*
G01X605440Y271800D02*
X621165Y256075D01*
G01X626691Y246855D02*
X629855Y243691D01*
G01X626691Y256601D02*
Y246855D01*
G01X620421Y262871D02*
X626691Y256601D01*
G01X620421Y328137D02*
Y262871D01*
G01X634525Y248594D02*
X635085Y248034D01*
G01X634525Y252526D02*
Y248594D01*
G01X623901Y263150D02*
X634525Y252526D01*
G01X623901Y327801D02*
Y263150D01*
G01X652951Y246149D02*
X660331Y238769D01*
G01X652951Y250698D02*
Y246149D01*
G01X652182Y251467D02*
X652951Y250698D01*
G01X652182Y253748D02*
Y251467D01*
G01X649249Y256681D02*
X652182Y253748D01*
G01X649249Y274251D02*
Y256681D01*
G01X655000Y280002D02*
X649249Y274251D01*
G01X614100Y240900D02*
X603300D01*
G01X621026Y247826D02*
X614100Y240900D01*
G01X621026Y253240D02*
Y247826D01*
G01X620850Y253416D02*
X621026Y253240D01*
G01X603791Y270475D02*
X620850Y253416D01*
G01X627698Y246913D02*
X630751Y243860D01*
G01X627698Y256659D02*
Y246913D01*
G01X621173Y263184D02*
X627698Y256659D01*
G01X621173Y327825D02*
Y263184D01*
G01X626153Y279065D02*
X627529Y280441D01*
G01X626153Y262528D02*
Y279065D01*
G01X639624Y249057D02*
X626153Y262528D01*
G01X641650Y270865D02*
X642855Y269660D01*
G01X641650Y278790D02*
Y270865D01*
G01X644098Y281238D02*
X641650Y278790D01*
G01X629609Y263962D02*
X658106Y235465D01*
G01X629609Y276208D02*
Y263962D01*
G01X638562Y285161D02*
X629609Y276208D01*
G01X628457Y263484D02*
X656954Y234987D01*
G01X628457Y277328D02*
Y263484D01*
G01X636799Y285670D02*
X628457Y277328D01*
G01X662379Y277677D02*
X662786Y278084D01*
G01X654348Y277677D02*
X662379D01*
G01X650424Y273753D02*
X654348Y277677D01*
G01X650424Y257176D02*
Y273753D01*
G01X653120Y254480D02*
X650424Y257176D01*
G01X653120Y252540D02*
Y254480D01*
G01X653881Y251779D02*
X653120Y252540D01*
G01X653881Y247019D02*
Y251779D01*
G01X661483Y239417D02*
X653881Y247019D01*
G01X663511Y278809D02*
X662786Y278084D01*
G01X655400Y247920D02*
X662783Y240537D01*
G01X655400Y252996D02*
Y247920D01*
G01X654950Y253446D02*
X655400Y252996D01*
G01X618500Y263162D02*
Y327531D01*
G01X625538Y256124D02*
X618500Y263162D01*
G01X625538Y246378D02*
Y256124D01*
G01X629027Y242889D02*
X625538Y246378D01*
G01X636842Y267658D02*
Y281783D01*
G01X640700Y263800D02*
X636842Y267658D01*
G01X640700Y259278D02*
Y263800D01*
G01X647150Y252828D02*
X640700Y259278D01*
G01X647150Y249850D02*
Y252828D01*
G01X659179Y237821D02*
X647150Y249850D01*
G01X626486Y238514D02*
X624500Y240500D01*
G01X643125Y266983D02*
X643591D01*
G01X639850Y270258D02*
X643125Y266983D01*
G01X639850Y282171D02*
Y270258D01*
G01X623149Y328737D02*
X648399Y353987D01*
G01X629259Y287098D02*
X628525Y287832D01*
G01X629259Y279936D02*
Y287098D01*
G01X656924Y283833D02*
X660901Y279856D01*
G01X656924Y286092D02*
Y283833D01*
G01X662238Y291406D02*
X656924Y286092D01*
G01X662238Y296146D02*
Y291406D01*
G01X644507Y337419D02*
X648436Y341348D01*
G01X644507Y308373D02*
Y337419D01*
G01X646280Y306600D02*
X644507Y308373D01*
G01X648180Y306600D02*
X646280D01*
G01X652600Y302180D02*
X648180Y306600D01*
G01X652600Y291384D02*
Y302180D01*
G01X645800Y284584D02*
X652600Y291384D01*
G01X645800Y280533D02*
Y284584D01*
G01X648023Y355739D02*
X620421Y328137D01*
G01X647418Y351318D02*
X623901Y327801D01*
G01X655000Y284600D02*
Y280002D01*
G01X665850Y332200D02*
X658900Y339150D01*
G01X646400Y328800D02*
X646272D01*
G01X647100Y328100D02*
X646400Y328800D01*
G01X647850Y328100D02*
X647100D01*
G01X658900Y339150D02*
X647850Y328100D01*
G01X648087Y354739D02*
X621173Y327825D01*
G01X644098Y285289D02*
Y281238D01*
G01X650898Y292089D02*
X644098Y285289D01*
G01X650898Y301475D02*
Y292089D01*
G01X647475Y304898D02*
X650898Y301475D01*
G01X645302Y304898D02*
X647475D01*
G01X642772Y307428D02*
X645302Y304898D01*
G01X642772Y337991D02*
Y307428D01*
G01X642805Y338024D02*
X642772Y337991D01*
G01X642805Y338124D02*
Y338024D01*
G01X647731Y343050D02*
X642805Y338124D01*
G01X646550Y309000D02*
X646700Y308850D01*
G01X646550Y313150D02*
Y309000D01*
G01X648500Y315100D02*
X646550Y313150D01*
G01X648500Y324400D02*
Y315100D01*
G01X646800Y326100D02*
X648500Y324400D01*
G01X653200Y304200D02*
X685929D01*
G01X648650Y308750D02*
X653200Y304200D01*
G01X648650Y308850D02*
Y308750D01*
G01X646700Y308850D02*
X648650D01*
G01X638562Y286687D02*
Y285161D01*
G01X636985Y288264D02*
X638562Y286687D01*
G01X660400Y283498D02*
X663511Y280387D01*
G01X660400Y286489D02*
Y283498D01*
G01X661232Y287321D02*
X660400Y286489D01*
G01X665740Y281260D02*
X662200Y284800D01*
G01X618500Y327531D02*
X647860Y356891D01*
G01X636477Y289985D02*
X634407Y287915D01*
G01X637560Y289985D02*
X636477D01*
G01X639728Y287817D02*
X637560Y289985D01*
G01X639728Y284669D02*
Y287817D01*
G01X636842Y281783D02*
X639728Y284669D01*
G01X642396Y284717D02*
X639850Y282171D01*
G01X642396Y285994D02*
Y284717D01*
G01X649196Y292794D02*
X642396Y285994D01*
G01X649196Y300770D02*
Y292794D01*
G01X646770Y303196D02*
X649196Y300770D01*
G01X644597Y303196D02*
X646770D01*
G01X641070Y306723D02*
X644597Y303196D01*
G01X641070Y338796D02*
Y306723D01*
G01X647026Y344752D02*
X641070Y338796D01*
G01X648399Y353987D02*
X679875D01*
G01X661424Y409674D02*
Y393310D01*
G01X648436Y341348D02*
X684221D01*
G01X679499Y355739D02*
X648023D01*
G01X647418Y351942D02*
Y351318D01*
G01X648676Y353200D02*
X647418Y351942D01*
G01X684399Y353200D02*
X648676D01*
G01X679563Y354739D02*
X648087D01*
G01X684926Y343050D02*
X647731D01*
G01X643724Y362571D02*
X678460D01*
G01X647860Y356891D02*
X679021D01*
G01X684221Y344752D02*
X647026D01*
G01X644773Y360043D02*
X678283D01*
G01X668854Y417104D02*
X661424Y409674D01*
G01X620791Y460715D02*
X613021D01*
G01X626002Y465926D02*
X620791Y460715D01*
G01X610084Y436546D02*
X609425D01*
G01X636671Y463133D02*
X610084Y436546D01*
G01X655352Y463133D02*
X636671D01*
G01X666929Y474710D02*
X655352Y463133D01*
G01X615907Y464114D02*
Y469970D01*
G01X613660Y461867D02*
X615907Y464114D01*
G01X612543Y461867D02*
X613660D01*
G01X609689Y437498D02*
X638088Y465897D01*
G01X609030Y437498D02*
X609689D01*
G01X612003Y434642D02*
X610215D01*
G01X636467Y459106D02*
X612003Y434642D01*
G01X654145Y459106D02*
X636467D01*
G01X671980Y476941D02*
X654145Y459106D01*
G01X654800Y461234D02*
X667881Y474315D01*
G01X637206Y461234D02*
X654800D01*
G01X611566Y435594D02*
X637206Y461234D01*
G01X609820Y435594D02*
X611566D01*
G01X612937Y455200D02*
X609191Y451454D01*
G01X625376Y455200D02*
X612937D01*
G01X637254Y467078D02*
X625376Y455200D01*
G01X653260Y433690D02*
X682560Y462990D01*
G01X610610Y433690D02*
X653260D01*
G01X628580Y459563D02*
X636847Y467830D01*
G01X613499Y459563D02*
X628580D01*
G01X603913Y514622D02*
Y535460D01*
G01X605510Y513025D02*
X603913Y514622D01*
G01X605510Y510157D02*
Y513025D01*
G01X623000Y492667D02*
X605510Y510157D01*
G01X623000Y480400D02*
Y492667D01*
G01X625100Y478300D02*
X623000Y480400D01*
G01X627000Y478300D02*
X625100D01*
G01X647916Y489500D02*
X656050D01*
G01X625800Y511616D02*
X647916Y489500D01*
G01X625800Y560827D02*
Y511616D01*
G01X626002Y469917D02*
Y465926D01*
G01X638235Y482150D02*
X626002Y469917D01*
G01X648700Y482150D02*
X638235D01*
G01X656050Y489500D02*
X648700Y482150D01*
G01X605510Y517999D02*
Y528899D01*
G01X607139Y516370D02*
X605510Y517999D01*
G01X620480Y516370D02*
X607139D01*
G01X622700Y514150D02*
X620480Y516370D01*
G01X622700Y509280D02*
Y514150D01*
G01X636500Y495480D02*
X622700Y509280D01*
G01X636500Y493924D02*
Y495480D01*
G01X663020Y484323D02*
X666929Y480414D01*
G01X663020Y489043D02*
Y484323D01*
G01X672600Y498623D02*
X663020Y489043D01*
G01X645206Y496600D02*
X653800D01*
G01X629200Y512606D02*
X645206Y496600D01*
G01X629200Y557200D02*
Y512606D01*
G01X638755Y484300D02*
X641150D01*
G01X626750Y472295D02*
X638755Y484300D01*
G01X618232Y472295D02*
X626750D01*
G01X615907Y469970D02*
X618232Y472295D01*
G01X661911Y489281D02*
X670400Y497770D01*
G01X661911Y484085D02*
Y489281D01*
G01X665976Y480020D02*
X661911Y484085D01*
G01X656418Y465897D02*
X665976Y475455D01*
G01X638088Y465897D02*
X656418D01*
G01X642248Y467078D02*
X637254D01*
G01X655884Y480714D02*
X642248Y467078D01*
G01X657553Y480714D02*
X655884D01*
G01X660646Y483807D02*
X657553Y480714D01*
G01X660646Y489363D02*
Y483807D01*
G01X662551Y491268D02*
X660646Y489363D01*
G01X662551Y494851D02*
Y491268D01*
G01X675525Y507825D02*
X662551Y494851D01*
G01X628048Y512130D02*
Y557678D01*
G01X628049Y512127D02*
X628048Y512130D01*
G01X646165Y494011D02*
X628049Y512127D01*
G01X653768Y494011D02*
X646165D01*
G01X659070Y488709D02*
X653768Y494011D01*
G01X659070Y487320D02*
Y488709D01*
G01X651644Y479894D02*
X659070Y487320D01*
G01X651644Y477538D02*
Y479894D01*
G01X641936Y467830D02*
X651644Y477538D01*
G01X636847Y467830D02*
X641936D01*
G01X605510Y585757D02*
Y590399D01*
G01Y574857D02*
Y585757D01*
G01X603868Y573215D02*
X605510Y574857D01*
G01X603868Y551472D02*
Y573215D01*
G01X605510Y549830D02*
X603868Y551472D01*
G01X605510Y547957D02*
Y549830D01*
G01Y537057D02*
Y547957D01*
G01X603913Y535460D02*
X605510Y537057D01*
G01X649422Y583185D02*
Y588922D01*
G01X650785Y581822D02*
X649422Y583185D01*
G01X676802Y581822D02*
X650785D01*
G01X630180Y571401D02*
X625800Y560827D01*
G01X631579Y574779D02*
X630180Y571401D01*
G01X634003Y577203D02*
X631579Y574779D01*
G01X639429Y579450D02*
X634003Y577203D01*
G01X673920Y579450D02*
X639429D01*
G01X607226Y572294D02*
Y591883D01*
G01X605510Y570578D02*
X607226Y572294D01*
G01X605510Y566699D02*
Y570578D01*
G01Y555799D02*
Y566699D01*
G01X607181Y554128D02*
X605510Y555799D01*
G01X607181Y533472D02*
Y554128D01*
G01X605510Y531801D02*
X607181Y533472D01*
G01X605510Y528899D02*
Y531801D01*
G01X632100Y560100D02*
X629200Y557200D01*
G01X654500Y560100D02*
X632100D01*
G01X656500Y562100D02*
X654500Y560100D01*
G01X722500Y562100D02*
X656500D01*
G01X650174Y583497D02*
Y588610D01*
G01X651097Y582574D02*
X650174Y583497D01*
G01X676490Y582574D02*
X651097D01*
G01X661304Y586224D02*
X647408Y600120D01*
G01X723325Y586224D02*
X661304D01*
G01X642576Y564876D02*
X723205D01*
G01X639000Y561300D02*
X642576Y564876D01*
G01X631670Y561300D02*
X639000D01*
G01X628048Y557678D02*
X631670Y561300D01*
G01X603823Y610970D02*
X605510Y612657D01*
G01X603823Y592086D02*
Y610970D01*
G01X605510Y590399D02*
X603823Y592086D01*
G01X646760Y594568D02*
Y592992D01*
G01X644216Y597112D02*
X646760Y594568D01*
G01X628506Y597112D02*
X644216D01*
G01X617705Y607913D02*
X628506Y597112D01*
G01X617705Y610592D02*
Y607913D01*
G01X617877Y610764D02*
X617705Y610592D01*
G01X617877Y613622D02*
Y610764D01*
G01X616425Y615074D02*
X617877Y613622D01*
G01X620306Y613321D02*
X616527Y617100D01*
G01X620306Y611952D02*
Y613321D01*
G01X633642Y598616D02*
X620306Y611952D01*
G01X644840Y598616D02*
X633642D01*
G01X649756Y593700D02*
X644840Y598616D01*
G01X649756Y589256D02*
Y593700D01*
G01X649422Y588922D02*
X649756Y589256D01*
G01X619165Y621369D02*
X619134Y621400D01*
G01X619190Y621369D02*
X619165D01*
G01X619390Y621169D02*
X619190Y621369D01*
G01X623332Y621169D02*
X619390D01*
G01X629901Y614600D02*
X623332Y621169D01*
G01X630671Y614600D02*
X629901D01*
G01X631088Y614183D02*
X630671Y614600D01*
G01X632394Y614183D02*
X631088D01*
G01X632811Y614600D02*
X632394Y614183D01*
G01X632813Y614600D02*
X632811D01*
G01X634569Y616356D02*
X632813Y614600D01*
G01X641111Y616356D02*
X634569D01*
G01X652119Y605348D02*
X641111Y616356D01*
G01X663352Y605348D02*
X652119D01*
G01X618629Y613934D02*
X616736Y615827D01*
G01X618629Y610452D02*
Y613934D01*
G01X618457Y610280D02*
X618629Y610452D01*
G01X618457Y608225D02*
Y610280D01*
G01X628818Y597864D02*
X618457Y608225D01*
G01X644528Y597864D02*
X628818D01*
G01X648336Y594056D02*
X644528Y597864D01*
G01X648336Y590858D02*
Y594056D01*
G01X648180Y590702D02*
X648336Y590858D01*
G01X605510Y593599D02*
Y604499D01*
G01X607226Y591883D02*
X605510Y593599D01*
G01X617125Y613310D02*
X616113Y614322D01*
G01X617125Y611076D02*
Y613310D01*
G01X616953Y610904D02*
X617125Y611076D01*
G01X616953Y607601D02*
Y610904D01*
G01X628194Y596360D02*
X616953Y607601D01*
G01X642540Y596360D02*
X628194D01*
G01X644500Y594400D02*
X642540Y596360D01*
G01X621174Y613517D02*
X616531Y618160D01*
G01X621174Y612148D02*
Y613517D01*
G01X633954Y599368D02*
X621174Y612148D01*
G01X645152Y599368D02*
X633954D01*
G01X650508Y594012D02*
X645152Y599368D01*
G01X650508Y588944D02*
Y594012D01*
G01X650174Y588610D02*
X650508Y588944D01*
G01X622662Y613093D02*
X616842Y618913D01*
G01X622662Y611724D02*
Y613093D01*
G01X634266Y600120D02*
X622662Y611724D01*
G01X647408Y600120D02*
X634266D01*
G01X633482Y617500D02*
X631741Y615759D01*
G01X643900Y617500D02*
X633482D01*
G01X655300Y606100D02*
X643900Y617500D01*
G01X663700Y606100D02*
X655300D01*
G01X655776Y593700D02*
X679500D01*
G01X648536Y600940D02*
X655776Y593700D01*
G01X634510Y600940D02*
X648536D01*
G01X623814Y611636D02*
X634510Y600940D01*
G01X623814Y614334D02*
Y611636D01*
G01X618483Y619665D02*
X623814Y614334D01*
G01X618853Y620617D02*
X618822Y620648D01*
G01X618878Y620617D02*
X618853D01*
G01X624766Y614729D02*
X618878Y620617D01*
G01X624766Y612031D02*
Y614729D01*
G01X634905Y601892D02*
X624766Y612031D01*
G01X648931Y601892D02*
X634905D01*
G01X656171Y594652D02*
X648931Y601892D01*
G01X679895Y594652D02*
X656171D01*
G01X710747Y-19199D02*
X710107Y-19839D01*
G01X711245Y-19199D02*
X710747D01*
G01X712940Y-20894D02*
X711245Y-19199D01*
G01X1293979Y-20894D02*
X712940D01*
G01X676064Y14704D02*
X673914Y12554D01*
G01X680254Y14704D02*
X676064D01*
G01X688194Y22644D02*
X680254Y14704D01*
G01X693183Y22644D02*
X688194D01*
G01X694683Y21144D02*
X693183Y22644D01*
G01X694683Y18097D02*
Y21144D01*
G01X697420Y15360D02*
X694683Y18097D01*
G01X704942Y15360D02*
X697420D01*
G01X706673Y13629D02*
X704942Y15360D01*
G01X713749Y13629D02*
X706673D01*
G01X722127Y5251D02*
X713749Y13629D01*
G01X722127Y-1504D02*
Y5251D01*
G01X719180Y-4451D02*
X722127Y-1504D01*
G01X718975Y-4451D02*
X719180D01*
G01X678940Y21269D02*
X672129Y14458D01*
G01X684083Y21269D02*
X678940D01*
G01X688092Y25278D02*
X684083Y21269D01*
G01X693523Y25278D02*
X688092D01*
G01X698470Y20331D02*
X693523Y25278D01*
G01X698470Y19669D02*
Y20331D01*
G01X677040Y21950D02*
X671052Y15962D01*
G01X677040Y28170D02*
Y21950D01*
G01X681670Y32800D02*
X677040Y28170D01*
G01X699950Y24051D02*
X691201Y32800D01*
G01X705582Y24051D02*
X699950D01*
G01X711642Y17991D02*
X705582Y24051D01*
G01X729600Y17991D02*
X711642D01*
G01X723762Y-17886D02*
X1278326D01*
G01X715345Y-9469D02*
X723762Y-17886D01*
G01X715345Y-5378D02*
Y-9469D01*
G01X715913Y-4810D02*
X715345Y-5378D01*
G01X715913Y8505D02*
Y-4810D01*
G01X711942Y12476D02*
X715913Y8505D01*
G01X706196Y12476D02*
X711942D01*
G01X704464Y14208D02*
X706196Y12476D01*
G01X696942Y14208D02*
X704464D01*
G01X692400Y18750D02*
X696942Y14208D01*
G01X692400Y20800D02*
Y18750D01*
G01X674869Y15870D02*
X672705Y13706D01*
G01X679790Y15870D02*
X674869D01*
G01X687838Y23918D02*
X679790Y15870D01*
G01X693539Y23918D02*
X687838D01*
G01X695835Y21622D02*
X693539Y23918D01*
G01X695835Y18575D02*
Y21622D01*
G01X697898Y16512D02*
X695835Y18575D01*
G01X705420Y16512D02*
X697898D01*
G01X707151Y14781D02*
X705420Y16512D01*
G01X714227Y14781D02*
X707151D01*
G01X723461Y5547D02*
X714227Y14781D01*
G01X723461Y-12795D02*
Y5547D01*
G01X722251Y-14005D02*
X723461Y-12795D01*
G01X722251Y-15311D02*
Y-14005D01*
G01X723174Y-16234D02*
X722251Y-15311D01*
G01X723222Y-16234D02*
X723174D01*
G01X724122Y-17134D02*
X723222Y-16234D01*
G01X1268145Y-17134D02*
X724122D01*
G01X709685Y-21646D02*
X1295438D01*
G01X706269Y-18230D02*
X709685Y-21646D01*
G01X706269Y-16026D02*
Y-18230D01*
G01X710327Y-11968D02*
X706269Y-16026D01*
G01X707300Y16500D02*
X725000D01*
G01X704150Y19650D02*
X707300Y16500D01*
G01X678400Y22161D02*
X671449Y15210D01*
G01X683755Y22161D02*
X678400D01*
G01X687827Y26233D02*
X683755Y22161D01*
G01X694506Y26233D02*
X687827D01*
G01X701120Y19619D02*
X694506Y26233D01*
G01X680165Y4969D02*
X672221D01*
G01X683799Y8603D02*
X680165Y4969D01*
G01X698159Y8603D02*
X683799D01*
G01X700238Y6524D02*
X698159Y8603D01*
G01X703424Y6524D02*
X700238D01*
G01X703426Y6526D02*
X703424Y6524D01*
G01X705103Y6526D02*
X703426D01*
G01X707724Y3905D02*
X705103Y6526D01*
G01X707724Y-5259D02*
Y3905D01*
G01X713909Y-11444D02*
X707724Y-5259D01*
G01X713909Y-13730D02*
Y-11444D01*
G01X718817Y-18638D02*
X713909Y-13730D01*
G01X1282974Y-18638D02*
X718817D01*
G01X708778Y-18254D02*
X708330Y-17806D01*
G01X711516Y-18254D02*
X708778D01*
G01X713404Y-20142D02*
X711516Y-18254D01*
G01X1293667Y-20142D02*
X713404D01*
G01X675860Y22730D02*
X669890Y16760D01*
G01X675860Y28160D02*
Y22730D01*
G01X681300Y33600D02*
X675860Y28160D01*
G01X696638Y30163D02*
X693201Y33600D01*
G01X728338Y30163D02*
X696638D01*
G01X709580Y7100D02*
X710800D01*
G01X703880Y12800D02*
X709580Y7100D01*
G01X683032Y12800D02*
X703880D01*
G01X678303Y8071D02*
X683032Y12800D01*
G01X663952Y8071D02*
X678303D01*
G01X663951Y8072D02*
X663952Y8071D01*
G01X663396Y8072D02*
X663951D01*
G01X663395Y8071D02*
X663396Y8072D01*
G01X672818Y92977D02*
X670084Y94110D01*
G01X677865Y87930D02*
X672818Y92977D01*
G01X695670Y87930D02*
X677865D01*
G01X698300Y85300D02*
X695670Y87930D01*
G01X716268Y91532D02*
Y88683D01*
G01X714400Y93400D02*
X716268Y91532D01*
G01X714400Y120040D02*
Y93400D01*
G01X724812Y84561D02*
X731029Y78344D01*
G01X724812Y119588D02*
Y84561D01*
G01X700000Y87000D02*
X701500Y85500D01*
G01X698471Y87000D02*
X700000D01*
G01X696164Y89307D02*
X698471Y87000D01*
G01X678260Y89307D02*
X696164D01*
G01X673528Y94039D02*
X678260Y89307D01*
G01X670794Y95172D02*
X673528Y94039D01*
G01X716894Y85729D02*
Y84047D01*
G01X714692Y87931D02*
X716894Y85729D01*
G01X714692Y90808D02*
Y87931D01*
G01X713000Y92500D02*
X714692Y90808D01*
G01X713000Y119600D02*
Y92500D01*
G01X707329Y92351D02*
X702880Y96800D01*
G01X707329Y88955D02*
Y92351D01*
G01X709559Y84649D02*
X709560Y84648D01*
G01X705451Y84649D02*
X709559D01*
G01X702200Y87900D02*
X705451Y84649D01*
G01X702200Y89700D02*
Y87900D01*
G01X698609Y93291D02*
X702200Y89700D01*
G01X688708Y97392D02*
X698609Y93291D01*
G01X691201Y32800D02*
X681670D01*
G01X672108Y91915D02*
X669374Y93048D01*
G01X677345Y86678D02*
X672108Y91915D01*
G01X692922Y86678D02*
X677345D01*
G01X694600Y85000D02*
X692922Y86678D01*
G01X713300Y86116D02*
Y86000D01*
G01X709986Y89430D02*
X713300Y86116D01*
G01X709986Y118864D02*
Y89430D01*
G01X676851Y85400D02*
X671398Y90853D01*
G01X678369Y85400D02*
X676851D01*
G01X687969Y75800D02*
X678369Y85400D01*
G01X722183Y75800D02*
X687969D01*
G01X726928Y71055D02*
X722183Y75800D01*
G01X705620Y89880D02*
X700180Y95320D01*
G01X705620Y87012D02*
Y89880D01*
G01X705972Y86660D02*
X705620Y87012D01*
G01X693201Y33600D02*
X681300D01*
G01X723660Y83023D02*
Y119040D01*
G01X729491Y77192D02*
X723660Y83023D01*
G01X719262Y90010D02*
Y117338D01*
G01X720572Y88700D02*
X719262Y90010D01*
G01X699592Y94208D02*
X689349Y98451D01*
G01X703845Y89955D02*
X699592Y94208D01*
G01X703845Y88830D02*
Y89955D01*
G01X713115Y90485D02*
Y88629D01*
G01X711286Y92314D02*
X713115Y90485D01*
G01X711286Y119194D02*
Y92314D01*
G01X670640Y163800D02*
X714400Y120040D01*
G01X670700Y161900D02*
X713000Y119600D01*
G01X664682Y133100D02*
X663567D01*
G01X676322Y128278D02*
X664682Y133100D01*
G01X682430Y122170D02*
X676322Y128278D01*
G01X684000Y118380D02*
X682430Y122170D01*
G01X684000Y115319D02*
Y118380D01*
G01X689740Y101460D02*
X684000Y115319D01*
G01X690620Y100580D02*
X689740Y101460D01*
G01X699746Y96800D02*
X690620Y100580D01*
G01X702880Y96800D02*
X699746D01*
G01X686526Y99574D02*
X688708Y97392D01*
G01X680400Y114363D02*
X686526Y99574D01*
G01X680400Y117335D02*
Y114363D01*
G01X679303Y119983D02*
X680400Y117335D01*
G01X673927Y125359D02*
X679303Y119983D01*
G01X664413Y129300D02*
X673927Y125359D01*
G01X669550Y159300D02*
X709986Y118864D01*
G01X675158Y127388D02*
X664506Y131800D01*
G01X681681Y120865D02*
X675158Y127388D01*
G01X682800Y118164D02*
X681681Y120865D01*
G01X682800Y114836D02*
Y118164D01*
G01X688552Y100948D02*
X682800Y114836D01*
G01X689937Y99563D02*
X688552Y100948D01*
G01X700180Y95320D02*
X689937Y99563D01*
G01X719262Y117338D02*
X671400Y165200D01*
G01X674539Y126377D02*
X664343Y130600D01*
G01X680608Y120308D02*
X674539Y126377D01*
G01X681600Y117913D02*
X680608Y120308D01*
G01X681600Y114694D02*
Y117913D01*
G01X687606Y100194D02*
X681600Y114694D01*
G01X689349Y98451D02*
X687606Y100194D01*
G01X669980Y160500D02*
X711286Y119194D01*
G01X663860Y200982D02*
Y234280D01*
G01X678078Y186764D02*
X663860Y200982D01*
G01X725581Y186764D02*
X678078D01*
G01X723874Y187916D02*
X724888Y188930D01*
G01X678556Y187916D02*
X723874D01*
G01X664895Y201577D02*
X678556Y187916D01*
G01X664895Y233685D02*
Y201577D01*
G01X701044Y257844D02*
X700400Y257200D01*
G01X707276Y257844D02*
X701044D01*
G01X709960Y255160D02*
X707276Y257844D01*
G01X725240Y255160D02*
X709960D01*
G01X694400Y278010D02*
Y287850D01*
G01X691060Y274670D02*
X694400Y278010D01*
G01X682871Y274670D02*
X691060D01*
G01X681861Y273660D02*
X682871Y274670D01*
G01X681861Y252914D02*
Y273660D01*
G01X683774Y251001D02*
X681861Y252914D01*
G01X683774Y245910D02*
Y251001D01*
G01X674430Y236566D02*
X683774Y245910D01*
G01X666146Y236566D02*
X674430D01*
G01X663860Y234280D02*
X666146Y236566D01*
G01X716350Y257750D02*
X715200Y258900D01*
G01X730611Y257750D02*
X716350D01*
G01X666624Y235414D02*
X664895Y233685D01*
G01X674908Y235414D02*
X666624D01*
G01X685019Y245525D02*
X674908Y235414D01*
G01X685019Y252232D02*
Y245525D01*
G01X683349Y253902D02*
X685019Y252232D01*
G01X683349Y270710D02*
Y253902D01*
G01X685539Y272900D02*
X683349Y270710D01*
G01X692480Y272900D02*
X685539D01*
G01X695330Y275750D02*
X692480Y272900D01*
G01X695330Y281840D02*
Y275750D01*
G01X712800Y258020D02*
Y286600D01*
G01X714300Y256520D02*
X712800Y258020D01*
G01X725680Y256520D02*
X714300D01*
G01X707250Y256080D02*
X704090D01*
G01X709620Y253710D02*
X707250Y256080D01*
G01X724890Y253710D02*
X709620D01*
G01X726900Y251700D02*
X724890Y253710D01*
G01X663511Y280387D02*
Y278809D01*
G01X724351Y248059D02*
X727394Y245016D01*
G01X719541Y248059D02*
X724351D01*
G01X717680Y249920D02*
X719541Y248059D01*
G01X717420Y249920D02*
X717680D01*
G01X665000Y283064D02*
Y284800D01*
G01X666052Y282012D02*
X665000Y283064D01*
G01X674990Y282012D02*
X666052D01*
G01X678384Y285406D02*
X674990Y282012D01*
G01X687794Y285406D02*
X678384D01*
G01X689348Y283852D02*
X687794Y285406D01*
G01X689847Y283852D02*
X689348D01*
G01X690048Y284053D02*
X689847Y283852D01*
G01X705908Y332338D02*
X719948Y346378D01*
G01X705908Y322018D02*
Y332338D01*
G01X691113Y307223D02*
X705908Y322018D01*
G01X691113Y291137D02*
Y307223D01*
G01X694400Y287850D02*
X691113Y291137D01*
G01X680300Y332200D02*
X665850D01*
G01X687300Y325200D02*
X680300Y332200D01*
G01X687300Y325100D02*
Y325200D01*
G01X684650Y322450D02*
X687300Y325100D01*
G01X684650Y312100D02*
Y322450D01*
G01X688100Y308650D02*
X684650Y312100D01*
G01X688100Y308600D02*
Y308650D01*
G01X696990Y283500D02*
X695330Y281840D01*
G01X696990Y293370D02*
Y283500D01*
G01X692265Y298095D02*
X696990Y293370D01*
G01X692265Y306745D02*
Y298095D01*
G01X707060Y321540D02*
X692265Y306745D01*
G01X707060Y331860D02*
Y321540D01*
G01X721100Y345900D02*
X707060Y331860D01*
G01X706780Y301600D02*
X705800D01*
G01X708100Y300280D02*
X706780Y301600D01*
G01X708100Y291300D02*
Y300280D01*
G01X712800Y286600D02*
X708100Y291300D01*
G01X698600Y338600D02*
Y338900D01*
G01X700100Y337100D02*
X698600Y338600D01*
G01X703900Y337100D02*
X700100D01*
G01X705400Y338600D02*
X703900Y337100D01*
G01X705400Y371100D02*
Y338600D01*
G01X697100Y340400D02*
X698600Y338900D01*
G01X694600Y340400D02*
X697100D01*
G01X689676Y335476D02*
X694600Y340400D01*
G01X689676Y307947D02*
Y335476D01*
G01X685929Y304200D02*
X689676Y307947D01*
G01X702700Y339000D02*
X701100D01*
G01X704500Y340800D02*
X702700Y339000D01*
G01X704500Y371473D02*
Y340800D01*
G01X701100Y339600D02*
Y339000D01*
G01X698800Y341900D02*
X701100Y339600D01*
G01X688314Y337914D02*
X692300Y341900D01*
G01X688314Y329114D02*
Y337914D01*
G01X687400Y328200D02*
X688314Y329114D01*
G01X681800Y333800D02*
X687400Y328200D01*
G01X680100Y333800D02*
X681800D01*
G01X674700Y339200D02*
X680100Y333800D01*
G01X675302Y281260D02*
X665740D01*
G01X678626Y284584D02*
X675302Y281260D01*
G01X687025Y284584D02*
X678626D01*
G01X690048Y281561D02*
X687025Y284584D01*
G01X690048Y281053D02*
Y281561D01*
G01X690328Y399630D02*
X702300Y411602D01*
G01X690328Y391357D02*
Y399630D01*
G01X689664Y390693D02*
X690328Y391357D01*
G01X689664Y369336D02*
Y390693D01*
G01X690176Y368824D02*
X689664Y369336D01*
G01X690176Y364288D02*
Y368824D01*
G01X679875Y353987D02*
X690176Y364288D01*
G01X696860Y396646D02*
X703414Y403200D01*
G01X696860Y362389D02*
Y396646D01*
G01X693056Y358585D02*
X696860Y362389D01*
G01X693056Y348773D02*
Y358585D01*
G01X685630Y341347D02*
X693056Y348773D01*
G01X684222Y341347D02*
X685630D01*
G01X684221Y341348D02*
X684222Y341347D01*
G01X686145Y362385D02*
X679499Y355739D01*
G01X686145Y368865D02*
Y362385D01*
G01X685099Y369911D02*
X686145Y368865D01*
G01X685099Y388256D02*
Y369911D01*
G01X688824Y391981D02*
X685099Y388256D01*
G01X688824Y400826D02*
Y391981D01*
G01X700796Y412798D02*
X688824Y400826D01*
G01X686699Y355500D02*
X684399Y353200D01*
G01X686699Y359747D02*
Y355500D01*
G01X690928Y363976D02*
X686699Y359747D01*
G01X690928Y389727D02*
Y363976D01*
G01X691240Y390039D02*
X690928Y389727D01*
G01X719948Y346378D02*
Y410548D01*
G01X686897Y362073D02*
X679563Y354739D01*
G01X686897Y369177D02*
Y362073D01*
G01X685851Y370223D02*
X686897Y369177D01*
G01X685851Y387944D02*
Y370223D01*
G01X689576Y391669D02*
X685851Y387944D01*
G01X689576Y400178D02*
Y391669D01*
G01X701548Y412150D02*
X689576Y400178D01*
G01X683100Y396732D02*
X699644Y413276D01*
G01X683100Y392200D02*
Y396732D01*
G01X721100Y410500D02*
Y345900D01*
G01X691354Y349478D02*
X684926Y343050D01*
G01X691354Y359290D02*
Y349478D01*
G01X695060Y362996D02*
X691354Y359290D01*
G01X695060Y397253D02*
Y362996D01*
G01X702727Y404920D02*
X695060Y397253D01*
G01X714800Y380500D02*
X705400Y371100D01*
G01X714800Y407800D02*
Y380500D01*
G01X663574Y409548D02*
Y384955D01*
G01X713900Y380873D02*
X704500Y371473D01*
G01X713900Y408173D02*
Y380873D01*
G01X692300Y341900D02*
X698800D01*
G01X678460Y362571D02*
X678730Y362841D01*
G01X683947Y389928D02*
X686619Y392600D01*
G01X683947Y369433D02*
Y389928D01*
G01X684993Y368387D02*
X683947Y369433D01*
G01X684993Y362863D02*
Y368387D01*
G01X679021Y356891D02*
X684993Y362863D01*
G01X689652Y350183D02*
X684221Y344752D01*
G01X689652Y359995D02*
Y350183D01*
G01X693310Y363653D02*
X689652Y359995D01*
G01X693310Y397910D02*
Y363653D01*
G01X702022Y406622D02*
X693310Y397910D01*
G01X681402Y396496D02*
X697465Y412559D01*
G01X681402Y363162D02*
Y396496D01*
G01X678283Y360043D02*
X681402Y363162D01*
G01X716497Y432323D02*
Y501688D01*
G01X702300Y418126D02*
X716497Y432323D01*
G01X702300Y411602D02*
Y418126D01*
G01X679015Y417104D02*
X668854D01*
G01X688821Y426910D02*
X679015Y417104D01*
G01X688821Y488357D02*
Y426910D01*
G01X706100Y403200D02*
X727103Y424203D01*
G01X703414Y403200D02*
X706100D01*
G01X700796Y418750D02*
Y412798D01*
G01X713550Y431504D02*
X700796Y418750D01*
G01X713550Y502250D02*
Y431504D01*
G01X719948Y410548D02*
X738200Y428800D01*
G01X701548Y418438D02*
Y412150D01*
G01X715745Y432635D02*
X701548Y418438D01*
G01X715745Y502079D02*
Y432635D01*
G01X701052Y420636D02*
Y496353D01*
G01X699644Y419228D02*
X701052Y420636D01*
G01X699644Y413276D02*
Y419228D01*
G01X739850Y429250D02*
X721100Y410500D01*
G01X705233Y404920D02*
X702727D01*
G01X725146Y424833D02*
X705233Y404920D01*
G01X732300Y425300D02*
X714800Y407800D01*
G01X669830Y415804D02*
X663574Y409548D01*
G01X679554Y415804D02*
X669830D01*
G01X694996Y431246D02*
X679554Y415804D01*
G01X694996Y488271D02*
Y431246D01*
G01X731400Y425673D02*
X713900Y408173D01*
G01X682560Y462990D02*
Y496258D01*
G01X704528Y406622D02*
X702022D01*
G01X722700Y424794D02*
X704528Y406622D01*
G01X722700Y482892D02*
Y424794D01*
G01X697175Y464559D02*
X696823Y464911D01*
G01X699500Y464559D02*
X697175D01*
G01X699852Y464207D02*
X699500Y464559D01*
G01X699852Y463059D02*
Y464207D01*
G01X699500Y462707D02*
X699852Y463059D01*
G01X697175Y462707D02*
X699500D01*
G01X696823Y462355D02*
X697175Y462707D01*
G01X696823Y461207D02*
Y462355D01*
G01X697175Y460855D02*
X696823Y461207D01*
G01X699500Y460855D02*
X697175D01*
G01X699852Y460503D02*
X699500Y460855D01*
G01X699852Y459355D02*
Y460503D01*
G01X699500Y459003D02*
X699852Y459355D01*
G01X697175Y459003D02*
X699500D01*
G01X696823Y458651D02*
X697175Y459003D01*
G01X696823Y457503D02*
Y458651D01*
G01X697175Y457151D02*
X696823Y457503D01*
G01X699500Y457151D02*
X697175D01*
G01X699852Y456799D02*
X699500Y457151D01*
G01X699852Y455651D02*
Y456799D01*
G01X699500Y455299D02*
X699852Y455651D01*
G01X697175Y455299D02*
X699500D01*
G01X696823Y454947D02*
X697175Y455299D01*
G01X696823Y453799D02*
Y454947D01*
G01X697175Y453447D02*
X696823Y453799D01*
G01X699500Y453447D02*
X697175D01*
G01X699852Y453095D02*
X699500Y453447D01*
G01X699852Y451947D02*
Y453095D01*
G01X699500Y451595D02*
X699852Y451947D01*
G01X697175Y451595D02*
X699500D01*
G01X696823Y451243D02*
X697175Y451595D01*
G01X696823Y450095D02*
Y451243D01*
G01X697175Y449743D02*
X696823Y450095D01*
G01X699500Y449743D02*
X697175D01*
G01X699852Y449391D02*
X699500Y449743D01*
G01X699852Y448243D02*
Y449391D01*
G01X699500Y447891D02*
X699852Y448243D01*
G01X697175Y447891D02*
X699500D01*
G01X696823Y447539D02*
X697175Y447891D01*
G01X696823Y446391D02*
Y447539D01*
G01X697175Y446039D02*
X696823Y446391D01*
G01X699500Y446039D02*
X697175D01*
G01X699852Y445687D02*
X699500Y446039D01*
G01X699852Y444539D02*
Y445687D01*
G01X699500Y444187D02*
X699852Y444539D01*
G01X697175Y444187D02*
X699500D01*
G01X696823Y443835D02*
X697175Y444187D01*
G01X696823Y442687D02*
Y443835D01*
G01X697175Y442335D02*
X696823Y442687D01*
G01X699500Y442335D02*
X697175D01*
G01X699852Y441983D02*
X699500Y442335D01*
G01X699852Y440835D02*
Y441983D01*
G01X699500Y440483D02*
X699852Y440835D01*
G01X697175Y440483D02*
X699500D01*
G01X696823Y440131D02*
X697175Y440483D01*
G01X696823Y438983D02*
Y440131D01*
G01X697175Y438631D02*
X696823Y438983D01*
G01X699500Y438631D02*
X697175D01*
G01X699852Y438279D02*
X699500Y438631D01*
G01X699852Y437131D02*
Y438279D01*
G01X699500Y436779D02*
X699852Y437131D01*
G01X697175Y436779D02*
X699500D01*
G01X696823Y436427D02*
X697175Y436779D01*
G01X696823Y435279D02*
Y436427D01*
G01X697175Y434927D02*
X696823Y435279D01*
G01X699500Y434927D02*
X697175D01*
G01X699852Y434575D02*
X699500Y434927D01*
G01X699852Y433427D02*
Y434575D01*
G01X699500Y433075D02*
X699852Y433427D01*
G01X697175Y433075D02*
X699500D01*
G01X696823Y432723D02*
X697175Y433075D01*
G01X696823Y431575D02*
Y432723D01*
G01X697175Y431223D02*
X696823Y431575D01*
G01X699500Y431223D02*
X697175D01*
G01X699852Y430871D02*
X699500Y431223D01*
G01X699852Y429723D02*
Y430871D01*
G01X699500Y429371D02*
X699852Y429723D01*
G01X697175Y429371D02*
X699500D01*
G01X696823Y429019D02*
X697175Y429371D01*
G01X696823Y427871D02*
Y429019D01*
G01X697175Y427519D02*
X696823Y427871D01*
G01X699500Y427519D02*
X697175D01*
G01X699852Y427167D02*
X699500Y427519D01*
G01X699852Y426019D02*
Y427167D01*
G01X699500Y425667D02*
X699852Y426019D01*
G01X697175Y425667D02*
X699500D01*
G01X696823Y425315D02*
X697175Y425667D01*
G01X696823Y424167D02*
Y425315D01*
G01X697175Y423815D02*
X696823Y424167D01*
G01X699500Y423815D02*
X697175D01*
G01X699852Y423463D02*
X699500Y423815D01*
G01X699852Y421594D02*
Y423463D01*
G01X697465Y419207D02*
X699852Y421594D01*
G01X697465Y412559D02*
Y419207D01*
G01X706400Y509700D02*
X703800Y507100D01*
G01X716993Y509700D02*
X706400D01*
G01X718428Y508265D02*
X716993Y509700D01*
G01X718428Y503619D02*
Y508265D01*
G01X716497Y501688D02*
X718428Y503619D01*
G01X686239Y490939D02*
X688821Y488357D01*
G01X686239Y499722D02*
Y490939D01*
G01X694944Y508427D02*
X686239Y499722D01*
G01X694944Y513745D02*
Y508427D01*
G01X697736Y516537D02*
X694944Y513745D01*
G01X719950Y516537D02*
X697736D01*
G01X730377Y506110D02*
X719950Y516537D01*
G01X723792Y486614D02*
Y489148D01*
G01X727103Y483303D02*
X723792Y486614D01*
G01X710643Y505157D02*
X713550Y502250D01*
G01X710643Y505496D02*
Y505157D01*
G01X666929Y480414D02*
Y474710D01*
G01X672600Y499800D02*
Y498623D01*
G01X674000Y501200D02*
X672600Y499800D01*
G01X717676Y504010D02*
X715745Y502079D01*
G01X717676Y507953D02*
Y504010D01*
G01X716729Y508900D02*
X717676Y507953D01*
G01X707900Y508900D02*
X716729D01*
G01X704500Y505500D02*
X707900Y508900D01*
G01X701500Y505500D02*
X704500D01*
G01X704099Y499400D02*
X708700D01*
G01X701052Y496353D02*
X704099Y499400D01*
G01X670400Y500200D02*
X671500Y501300D01*
G01X670400Y497770D02*
Y500200D01*
G01X665976Y475455D02*
Y480020D01*
G01X722090Y485909D02*
X725146Y482853D01*
G01X722090Y487411D02*
Y485909D01*
G01X721301Y488200D02*
X722090Y487411D01*
G01X696000Y489275D02*
X694996Y488271D01*
G01X696000Y496800D02*
Y489275D01*
G01X671980Y483894D02*
Y476941D01*
G01X671704Y484170D02*
X671980Y483894D01*
G01X671704Y486970D02*
Y484170D01*
G01X671980Y487246D02*
X671704Y486970D01*
G01X671980Y495309D02*
Y487246D01*
G01X673971Y497300D02*
X671980Y495309D01*
G01X674829Y497300D02*
X673971D01*
G01X678176Y500647D02*
X674829Y497300D01*
G01X678176Y502142D02*
Y500647D01*
G01X677473Y502845D02*
X678176Y502142D01*
G01X677473Y504399D02*
Y502845D01*
G01X678688Y505614D02*
X677473Y504399D01*
G01X685015Y505614D02*
X678688D01*
G01X685016Y505615D02*
X685015Y505614D01*
G01X688900Y505615D02*
X685016D01*
G01X693792Y510507D02*
X688900Y505615D01*
G01X693792Y514391D02*
Y510507D01*
G01X697120Y517719D02*
X693792Y514391D01*
G01X720398Y517719D02*
X697120D01*
G01X730797Y507320D02*
X720398Y517719D01*
G01X676600Y501276D02*
Y501300D01*
G01X664850Y489526D02*
X676600Y501276D01*
G01X664850Y483840D02*
Y489526D01*
G01X667881Y480809D02*
X664850Y483840D01*
G01X667881Y474315D02*
Y480809D01*
G01X686775Y507825D02*
X675525D01*
G01X690950Y512000D02*
X686775Y507825D01*
G01X690950Y513310D02*
Y512000D01*
G01X696476Y518836D02*
X690950Y513310D01*
G01X733890Y518836D02*
X696476D01*
G01X679128Y503667D02*
X679049Y503746D01*
G01X679128Y499690D02*
Y503667D01*
G01X682560Y496258D02*
X679128Y499690D01*
G01X720300Y485292D02*
X722700Y482892D01*
G01X720300Y485800D02*
Y485292D01*
G01X722827Y508170D02*
X726431D01*
G01X722067Y507410D02*
X722827Y508170D01*
G01X720761Y507410D02*
X722067D01*
G01X717371Y510800D02*
X720761Y507410D01*
G01X704200Y510800D02*
X717371D01*
G01X699852Y506452D02*
X704200Y510800D01*
G01X699852Y466763D02*
Y506452D01*
G01X699500Y466411D02*
X699852Y466763D01*
G01X697175Y466411D02*
X699500D01*
G01X696823Y466059D02*
X697175Y466411D01*
G01X696823Y464911D02*
Y466059D01*
G01X678997Y584017D02*
X676802Y581822D01*
G01X727866Y584017D02*
X678997D01*
G01X677740Y575630D02*
X673920Y579450D01*
G01X684110Y575630D02*
X677740D01*
G01X687930Y579450D02*
X684110Y575630D01*
G01X709550Y579450D02*
X687930D01*
G01X712000Y577000D02*
X709550Y579450D01*
G01X726500Y577000D02*
X712000D01*
G01X730476Y570076D02*
X722500Y562100D01*
G01X678685Y584769D02*
X676490Y582574D01*
G01X727554Y584769D02*
X678685D01*
G01X725601Y588500D02*
X723325Y586224D01*
G01X723205Y564876D02*
X729251Y570922D01*
G01X672900Y595800D02*
X663352Y605348D01*
G01X680800Y595800D02*
X672900D01*
G01X685252Y591348D02*
X680800Y595800D01*
G01X696912Y591348D02*
X685252D01*
G01X710100Y604536D02*
X696912Y591348D01*
G01X710100Y608503D02*
Y604536D01*
G01X714597Y613000D02*
X710100Y608503D01*
G01X731601Y613000D02*
X714597D01*
G01X673200Y596600D02*
X663700Y606100D01*
G01X681100Y596600D02*
X673200D01*
G01X685600Y592100D02*
X681100Y596600D01*
G01X696600Y592100D02*
X685600D01*
G01X709348Y604848D02*
X696600Y592100D01*
G01X709348Y608815D02*
Y604848D01*
G01X714285Y613752D02*
X709348Y608815D01*
G01X730252Y613752D02*
X714285D01*
G01X722500Y601000D02*
X725500Y604000D01*
G01X717500Y601000D02*
X722500D01*
G01X715000Y598500D02*
X717500Y601000D01*
G01X715000Y596000D02*
Y598500D01*
G01X713100Y594100D02*
X715000Y596000D01*
G01X703600Y594100D02*
X713100D01*
G01X697901Y588401D02*
X703600Y594100D01*
G01X684799Y588401D02*
X697901D01*
G01X679500Y593700D02*
X684799Y588401D01*
G01X685194Y589353D02*
X679895Y594652D01*
G01X697506Y589353D02*
X685194D01*
G01X703205Y595052D02*
X697506Y589353D01*
G01X712705Y595052D02*
X703205D01*
G01X714048Y596395D02*
X712705Y595052D01*
G01X714048Y598895D02*
Y596395D01*
G01X717105Y601952D02*
X714048Y598895D01*
G01X722105Y601952D02*
X717105D01*
G01X725105Y604952D02*
X722105Y601952D01*
G01X767498Y31901D02*
X764324Y35075D01*
G01X767498Y1627D02*
Y31901D01*
G01X764724Y-1147D02*
X767498Y1627D01*
G01X764724Y-2453D02*
Y-1147D01*
G01X767498Y-5227D02*
X764724Y-2453D01*
G01X767498Y-10811D02*
Y-5227D01*
G01X770061Y-13374D02*
X767498Y-10811D01*
G01X1263913Y-13374D02*
X770061D01*
G01X759348Y24488D02*
Y48330D01*
G01X759500Y24336D02*
X759348Y24488D01*
G01X759500Y22623D02*
Y24336D01*
G01X758504Y21627D02*
X759500Y22623D01*
G01X758504Y-9024D02*
Y21627D01*
G01X765862Y-16382D02*
X758504Y-9024D01*
G01X1267833Y-16382D02*
X765862D01*
G01X766486Y-14878D02*
X1266167D01*
G01X760952Y-9344D02*
X766486Y-14878D01*
G01X760952Y-1448D02*
Y-9344D01*
G01X765700Y3300D02*
X760952Y-1448D01*
G01X765700Y27752D02*
Y3300D01*
G01X760952Y32500D02*
X765700Y27752D01*
G01X760952Y66785D02*
Y32500D01*
G01X770373Y-12622D02*
X1261319D01*
G01X768250Y-10499D02*
X770373Y-12622D01*
G01X768250Y62679D02*
Y-10499D01*
G01X766798Y-14126D02*
X1265855D01*
G01X761772Y-9100D02*
X766798Y-14126D01*
G01X761772Y-2028D02*
Y-9100D01*
G01X766700Y2900D02*
X761772Y-2028D01*
G01X766700Y29172D02*
Y2900D01*
G01X761772Y34100D02*
X766700Y29172D01*
G01X751600Y29800D02*
Y41000D01*
G01X734217Y12417D02*
X751600Y29800D01*
G01X729083Y12417D02*
X734217D01*
G01X725000Y16500D02*
X729083Y12417D01*
G01X753900Y25693D02*
Y33170D01*
G01X752099Y23892D02*
X753900Y25693D01*
G01X752099Y8801D02*
Y23892D01*
G01X753924Y6976D02*
X752099Y8801D01*
G01X756176Y-2567D02*
Y4724D01*
G01X758290Y30410D02*
X754328Y34372D01*
G01X758290Y22477D02*
Y30410D01*
G01X757752Y21939D02*
X758290Y22477D01*
G01X757752Y-6049D02*
Y21939D01*
G01X748667Y-15134D02*
X757752Y-6049D01*
G01X731210Y-15134D02*
X748667D01*
G01X734256Y24245D02*
X728338Y30163D01*
G01X734256Y17991D02*
Y24245D01*
G01X760100Y24800D02*
Y63100D01*
G01X762100Y22800D02*
X760100Y24800D01*
G01X762100Y15900D02*
Y22800D01*
G01X760100Y13900D02*
X762100Y15900D01*
G01X760100Y-9556D02*
Y13900D01*
G01X766174Y-15630D02*
X760100Y-9556D01*
G01X1267099Y-15630D02*
X766174D01*
G01X726316Y85751D02*
Y120585D01*
G01X732219Y79848D02*
X726316Y85751D01*
G01X750017Y79848D02*
X732219D01*
G01X765676Y64189D02*
X750017Y79848D01*
G01X765676Y37926D02*
Y64189D01*
G01X764324Y36574D02*
X765676Y37926D01*
G01X764324Y35075D02*
Y36574D01*
G01X728972Y89474D02*
Y122978D01*
G01X730038Y88408D02*
X728972Y89474D01*
G01X737300Y71783D02*
X733671Y75412D01*
G01X737300Y67400D02*
Y71783D01*
G01X741700Y63000D02*
X737300Y67400D01*
G01X744678Y63000D02*
X741700D01*
G01X759348Y48330D02*
X744678Y63000D01*
G01X749393Y78344D02*
X760952Y66785D01*
G01X731029Y78344D02*
X749393D01*
G01X749929Y81000D02*
X768250Y62679D01*
G01X732131Y81000D02*
X749929D01*
G01X727068Y86063D02*
X732131Y81000D01*
G01X727068Y121531D02*
Y86063D01*
G01X763930Y87070D02*
Y85100D01*
G01X753200Y97800D02*
X763930Y87070D01*
G01X761772Y67029D02*
Y34100D01*
G01X749705Y79096D02*
X761772Y67029D01*
G01X731341Y79096D02*
X749705D01*
G01X725564Y84873D02*
X731341Y79096D01*
G01X725564Y120136D02*
Y84873D01*
G01X728220Y87140D02*
Y122009D01*
G01X732734Y82626D02*
X728220Y87140D01*
G01X735241Y93131D02*
Y88329D01*
G01X736639Y94529D02*
X735241Y93131D01*
G01X729724Y91283D02*
X732599Y88408D01*
G01X729724Y123856D02*
Y91283D01*
G01X726928Y61909D02*
Y71055D01*
G01X730007Y58830D02*
X726928Y61909D01*
G01X745956Y58830D02*
X730007D01*
G01X752772Y52014D02*
X745956Y58830D01*
G01X752772Y42057D02*
Y52014D01*
G01X753176Y41653D02*
X752772Y42057D01*
G01X753176Y33894D02*
Y41653D01*
G01X753900Y33170D02*
X753176Y33894D01*
G01X766824Y85943D02*
X753567Y99200D01*
G01X728080Y72472D02*
X730923Y75315D01*
G01X728080Y62387D02*
Y72472D01*
G01X730357Y60110D02*
X728080Y62387D01*
G01X746504Y60110D02*
X730357D01*
G01X753924Y52690D02*
X746504Y60110D01*
G01X753924Y42535D02*
Y52690D01*
G01X754328Y42131D02*
X753924Y42535D01*
G01X754328Y34372D02*
Y42131D01*
G01X746250Y77192D02*
X729491D01*
G01X750145Y73297D02*
X746250Y77192D01*
G01X750316Y72884D02*
X750145Y73297D01*
G01X760100Y63100D02*
X750316Y72884D01*
G01X761953Y86747D02*
X752800Y95900D01*
G01X761953Y82617D02*
Y86747D01*
G01X763350Y81220D02*
X761953Y82617D01*
G01X762504Y119004D02*
Y172704D01*
G01X752900Y109400D02*
X762504Y119004D01*
G01X752900Y101000D02*
Y109400D01*
G01X764800Y114200D02*
Y171600D01*
G01X759450Y108850D02*
X764800Y114200D01*
G01X759450Y100850D02*
Y108850D01*
G01X758000Y99400D02*
X759450Y100850D01*
G01X756800Y99400D02*
X758000D01*
G01X741100Y97800D02*
X753200D01*
G01X738700Y100200D02*
X741100Y97800D01*
G01X738700Y119770D02*
Y100200D01*
G01X727690Y122539D02*
Y122610D01*
G01X728220Y122009D02*
X727690Y122539D01*
G01X763656Y116156D02*
Y172056D01*
G01X756800Y109300D02*
X763656Y116156D01*
G01X756800Y102000D02*
Y109300D01*
G01X736639Y97680D02*
Y94529D01*
G01X732866Y101453D02*
X736639Y97680D01*
G01X732866Y122344D02*
Y101453D01*
G01X761352Y123452D02*
Y173252D01*
G01X746600Y108700D02*
X761352Y123452D01*
G01X746600Y103900D02*
Y108700D01*
G01X740000Y101300D02*
Y120100D01*
G01X742100Y99200D02*
X740000Y101300D01*
G01X753567Y99200D02*
X742100D01*
G01X741700Y119500D02*
Y102000D01*
G01X737200Y99500D02*
Y119640D01*
G01X740800Y95900D02*
X737200Y99500D01*
G01X752800Y95900D02*
X740800D01*
G01X744200Y108900D02*
Y102800D01*
G01X760200Y124900D02*
X744200Y108900D01*
G01X760200Y173800D02*
Y124900D01*
G01X728952Y211376D02*
Y232742D01*
G01X744780Y195548D02*
X728952Y211376D01*
G01X771080Y195548D02*
X744780D01*
G01X773200Y193428D02*
X771080Y195548D01*
G01X773200Y183400D02*
Y193428D01*
G01X762504Y172704D02*
X773200Y183400D01*
G01X727628Y188811D02*
X725581Y186764D01*
G01X727776Y188811D02*
X727628D01*
G01X731003Y211897D02*
Y231718D01*
G01X745448Y197452D02*
X731003Y211897D01*
G01X771948Y197452D02*
X745448D01*
G01X775200Y194200D02*
X771948Y197452D01*
G01X775200Y182000D02*
Y194200D01*
G01X764800Y171600D02*
X775200Y182000D01*
G01X730251Y211585D02*
Y232030D01*
G01X745136Y196700D02*
X730251Y211585D01*
G01X771300Y196700D02*
X745136D01*
G01X774448Y193552D02*
X771300Y196700D01*
G01X774448Y187748D02*
Y193552D01*
G01X774400Y187700D02*
X774448Y187748D01*
G01X774400Y182800D02*
Y187700D01*
G01X763656Y172056D02*
X774400Y182800D01*
G01X728200Y211064D02*
Y233054D01*
G01X744868Y194396D02*
X728200Y211064D01*
G01X770100Y194396D02*
X744868D01*
G01X772000Y192496D02*
X770100Y194396D01*
G01X772000Y183900D02*
Y192496D01*
G01X761352Y173252D02*
X772000Y183900D01*
G01X770800Y184400D02*
X760200Y173800D01*
G01X770800Y192044D02*
Y184400D01*
G01X769600Y193244D02*
X770800Y192044D01*
G01X744956Y193244D02*
X769600D01*
G01X725200Y213000D02*
X744956Y193244D01*
G01X725200Y238799D02*
Y213000D01*
G01X728000Y252400D02*
X725240Y255160D01*
G01X728000Y252230D02*
Y252400D01*
G01X728052Y252178D02*
X728000Y252230D01*
G01X728052Y252114D02*
Y252178D01*
G01X729056Y251110D02*
X728052Y252114D01*
G01X729056Y246706D02*
Y251110D01*
G01X730924Y244838D02*
X729056Y246706D01*
G01X730924Y234714D02*
Y244838D01*
G01X728952Y232742D02*
X730924Y234714D01*
G01X731919Y256442D02*
X730611Y257750D01*
G01X731919Y249688D02*
Y256442D01*
G01X733238Y248369D02*
X731919Y249688D01*
G01X733238Y233953D02*
Y248369D01*
G01X731003Y231718D02*
X733238Y233953D01*
G01X730086Y252114D02*
X725680Y256520D01*
G01X730086Y246897D02*
Y252114D01*
G01X732486Y244497D02*
X730086Y246897D01*
G01X732486Y234265D02*
Y244497D01*
G01X730251Y232030D02*
X732486Y234265D01*
G01X726900Y251636D02*
Y251700D01*
G01X727904Y250632D02*
X726900Y251636D01*
G01X727904Y245934D02*
Y250632D01*
G01X730172Y243666D02*
X727904Y245934D01*
G01X730172Y235026D02*
Y243666D01*
G01X728200Y233054D02*
X730172Y235026D01*
G01X727394Y240993D02*
X725200Y238799D01*
G01X727394Y245016D02*
Y240993D01*
G01X732000Y385400D02*
Y380000D01*
G01X743200Y396600D02*
X732000Y385400D01*
G01X752000Y396600D02*
X743200D01*
G01X758990Y403590D02*
X752000Y396600D01*
G01X766970Y401500D02*
X764880Y403590D01*
G01X773500Y401500D02*
X766970D01*
G01X774510Y402510D02*
X773500Y401500D01*
G01X780430Y402510D02*
X774510D01*
G01X785720Y407800D02*
X780430Y402510D01*
G01X727103Y424203D02*
Y483303D01*
G01X738200Y431850D02*
X747950Y441600D01*
G01X738200Y428800D02*
Y431850D01*
G01X764880Y403590D02*
X758990D01*
G01X800000Y407800D02*
X785720D01*
G01X739850Y430250D02*
Y429250D01*
G01X748500Y438900D02*
X739850Y430250D01*
G01X767558Y452117D02*
X731339Y488336D01*
G01X767558Y423201D02*
Y452117D01*
G01X765881Y421524D02*
X767558Y423201D01*
G01X765881Y417324D02*
Y421524D01*
G01X766200Y417005D02*
X765881Y417324D01*
G01X725146Y482853D02*
Y424833D01*
G01X732300Y481999D02*
Y425300D01*
G01X731400Y481626D02*
Y425673D01*
G01X766130Y451525D02*
X729299Y488356D01*
G01X766130Y423793D02*
Y451525D01*
G01X764624Y422287D02*
X766130Y423793D01*
G01X764624Y416167D02*
Y422287D01*
G01X766394Y414397D02*
X764624Y416167D01*
G01X751081Y506110D02*
X730377D01*
G01X757178Y512207D02*
X751081Y506110D01*
G01X757178Y519228D02*
Y512207D01*
G01X760695Y522745D02*
X757178Y519228D01*
G01X763035Y522745D02*
X760695D01*
G01X763544Y522236D02*
X763035Y522745D01*
G01X731339Y488336D02*
Y489319D01*
G01X726734Y487565D02*
X732300Y481999D01*
G01X726734Y489840D02*
Y487565D01*
G01X728823Y491929D02*
X726734Y489840D01*
G01X732371Y491929D02*
X728823D01*
G01X735042Y489258D02*
X732371Y491929D01*
G01X758516Y489258D02*
X735042D01*
G01X766294Y497036D02*
X758516Y489258D01*
G01X766294Y515718D02*
Y497036D01*
G01X764901Y517111D02*
X766294Y515718D01*
G01X764901Y518771D02*
Y517111D01*
G01X768242Y522112D02*
X764901Y518771D01*
G01X768242Y531658D02*
Y522112D01*
G01X725834Y487192D02*
X731400Y481626D01*
G01X725834Y490213D02*
Y487192D01*
G01X728450Y492829D02*
X725834Y490213D01*
G01X732744Y492829D02*
X728450D01*
G01X735415Y490158D02*
X732744Y492829D01*
G01X758352Y490158D02*
X735415D01*
G01X765542Y497348D02*
X758352Y490158D01*
G01X765542Y515090D02*
Y497348D01*
G01X763868Y516764D02*
X765542Y515090D01*
G01X763868Y518802D02*
Y516764D01*
G01X767206Y522140D02*
X763868Y518802D01*
G01X767206Y531422D02*
Y522140D01*
G01X750587Y507320D02*
X730797D01*
G01X755767Y512500D02*
X750587Y507320D01*
G01X755767Y519744D02*
Y512500D01*
G01X757725Y521702D02*
X755767Y519744D01*
G01X757725Y586580D02*
Y521702D01*
G01X738311Y523257D02*
X733890Y518836D01*
G01X747531Y523257D02*
X738311D01*
G01X754137Y529863D02*
X747531Y523257D01*
G01X729299Y488356D02*
X728373D01*
G01X761090Y511634D02*
X763706Y514250D01*
G01X761090Y500336D02*
Y511634D01*
G01X756544Y495790D02*
X761090Y500336D01*
G01X738811Y495790D02*
X756544D01*
G01X726431Y508170D02*
X738811Y495790D01*
G01X735405Y591556D02*
X727866Y584017D01*
G01X732500Y583000D02*
X726500Y577000D01*
G01X732500Y586599D02*
Y583000D01*
G01X736557Y590656D02*
X732500Y586599D01*
G01X730476Y575747D02*
Y570076D01*
G01X736566Y581837D02*
X730476Y575747D01*
G01X753286Y581837D02*
X736566D01*
G01X755621Y584172D02*
X753286Y581837D01*
G01X755621Y587453D02*
Y584172D01*
G01X755900Y587732D02*
X755621Y587453D01*
G01X755900Y593650D02*
Y587732D01*
G01X734653Y591868D02*
X727554Y584769D01*
G01X763200Y536700D02*
X768242Y531658D01*
G01X763200Y543400D02*
Y536700D01*
G01X766400Y546600D02*
X763200Y543400D01*
G01X766400Y552380D02*
Y546600D01*
G01X761591Y557189D02*
X766400Y552380D01*
G01X761591Y579391D02*
Y557189D01*
G01X765900Y583700D02*
X761591Y579391D01*
G01X765900Y587300D02*
Y583700D01*
G01X762300Y536328D02*
X767206Y531422D01*
G01X762300Y543773D02*
Y536328D01*
G01X765500Y546973D02*
X762300Y543773D01*
G01X765500Y552007D02*
Y546973D01*
G01X760839Y556668D02*
X765500Y552007D01*
G01X760839Y580279D02*
Y556668D01*
G01X763200Y582640D02*
X760839Y580279D01*
G01X763200Y584950D02*
Y582640D01*
G01X763450Y585200D02*
X763200Y584950D01*
G01X761471Y590326D02*
X757725Y586580D01*
G01X754137Y538601D02*
Y529863D01*
G01X756773Y541237D02*
X754137Y538601D01*
G01X756773Y586975D02*
Y541237D01*
G01X760519Y590721D02*
X756773Y586975D01*
G01X748134Y583034D02*
X753300Y588200D01*
G01X736133Y583034D02*
X748134D01*
G01X729251Y576152D02*
X736133Y583034D01*
G01X729251Y570922D02*
Y576152D01*
G01X735405Y610859D02*
Y591556D01*
G01X745084Y620538D02*
X735405Y610859D01*
G01X1044828Y620538D02*
X745084D01*
G01X740643Y622042D02*
X731601Y613000D01*
G01X1045452Y622042D02*
X740643D01*
G01X736557Y610947D02*
Y590656D01*
G01X745396Y619786D02*
X736557Y610947D01*
G01X1044516Y619786D02*
X745396D01*
G01X734653Y610547D02*
Y591868D01*
G01X734652Y610548D02*
X734653Y610547D01*
G01X734652Y611170D02*
Y610548D01*
G01X744772Y621290D02*
X734652Y611170D01*
G01X1045140Y621290D02*
X744772D01*
G01X729217Y588500D02*
X725601D01*
G01X732259Y591542D02*
X729217Y588500D01*
G01X732259Y601741D02*
Y591542D01*
G01X731456Y602544D02*
X732259Y601741D01*
G01X731456Y605456D02*
Y602544D01*
G01X732500Y606500D02*
X731456Y605456D01*
G01X732500Y611000D02*
Y606500D01*
G01X761471Y609480D02*
Y590326D01*
G01X770073Y618082D02*
X761471Y609480D01*
G01X1043809Y618082D02*
X770073D01*
G01X739294Y622794D02*
X730252Y613752D01*
G01X1045764Y622794D02*
X739294D01*
G01X729679Y610800D02*
X729616Y610863D01*
G01X729679Y605679D02*
Y610800D01*
G01X728000Y604000D02*
X729679Y605679D01*
G01X725500Y604000D02*
X728000D01*
G01X760519Y609085D02*
Y590721D01*
G01X760518Y609086D02*
X760519Y609085D01*
G01X760518Y609874D02*
Y609086D01*
G01X769678Y619034D02*
X760518Y609874D01*
G01X1044204Y619034D02*
X769678D01*
G01X727605Y604952D02*
X725105D01*
G01X728727Y606074D02*
X727605Y604952D01*
G01X728727Y609001D02*
Y606074D01*
G01X726857Y610871D02*
X728727Y609001D01*
G01X753300Y588200D02*
Y593600D01*
G01X802900Y400600D02*
Y404900D01*
G01X815119Y388381D02*
X802900Y400600D01*
G01X830619Y388381D02*
X815119D01*
G01X831000Y388000D02*
X830619Y388381D01*
G01X831000Y379184D02*
Y388000D01*
G01X833274Y376910D02*
X831000Y379184D01*
G01X833274Y373639D02*
Y376910D01*
G01X841628Y365285D02*
X833274Y373639D01*
G01X852539Y365285D02*
X841628D01*
G01X802900Y404900D02*
X800000Y407800D01*
G01X891320Y326504D02*
X852539Y365285D01*
G01X909704Y326504D02*
X891320D01*
G01X912830Y329630D02*
X909704Y326504D01*
G01X959000Y26297D02*
X957283Y28014D01*
G01X959000Y18774D02*
Y26297D01*
G01X957283Y17057D02*
X959000Y18774D01*
G01X957283Y16417D02*
Y17057D01*
G01X959300Y14400D02*
X957283Y16417D01*
G01X959300Y10500D02*
Y14400D01*
G01X958900Y10100D02*
X959300Y10500D01*
G01X958900Y-2600D02*
Y10100D01*
G01X957765Y-3735D02*
X958900Y-2600D01*
G01X957765Y-7180D02*
Y-3735D01*
G01X959500Y30231D02*
Y34299D01*
G01X957283Y28014D02*
X959500Y30231D01*
G01X958900Y66438D02*
X957536Y67802D01*
G01X958900Y56474D02*
Y66438D01*
G01X957283Y54857D02*
X958900Y56474D01*
G01X959500Y52640D02*
X957283Y54857D01*
G01X959500Y49500D02*
Y52640D01*
G01X958900Y48900D02*
X959500Y49500D01*
G01X958900Y34899D02*
Y48900D01*
G01X959500Y34299D02*
X958900Y34899D01*
G01X958700Y91240D02*
X957283Y92657D01*
G01X958700Y89200D02*
Y91240D01*
G01X959400Y88500D02*
X958700Y89200D01*
G01X959400Y86400D02*
Y88500D01*
G01X958900Y85900D02*
X959400Y86400D01*
G01X958900Y79300D02*
Y85900D01*
G01X959748Y78452D02*
X958900Y79300D01*
G01X959748Y68279D02*
Y78452D01*
G01X959271Y67802D02*
X959748Y68279D01*
G01X957536Y67802D02*
X959271D01*
G01X914870Y329630D02*
X912830D01*
G01X916500Y328000D02*
X914870Y329630D01*
G01X918200Y328000D02*
X916500D01*
G01X920100Y326100D02*
X918200Y328000D01*
G01X921400Y326100D02*
X920100D01*
G01X923300Y324200D02*
X921400Y326100D01*
G01X924500Y324200D02*
X923300D01*
G01X925800Y322900D02*
X924500Y324200D01*
G01X925800Y319700D02*
Y322900D01*
G01X927300Y318200D02*
X925800Y319700D01*
G01X928500Y318200D02*
X927300D01*
G01X930100Y316600D02*
X928500Y318200D01*
G01X932000Y316600D02*
X930100D01*
G01X933600Y318200D02*
X932000Y316600D01*
G01X935100Y318200D02*
X933600D01*
G01X937000Y316300D02*
X935100Y318200D01*
G01X938400Y316300D02*
X937000D01*
G01X940200Y314500D02*
X938400Y316300D01*
G01X942100Y314500D02*
X940200D01*
G01X943700Y316100D02*
X942100Y314500D01*
G01X945300Y316100D02*
X943700D01*
G01X946800Y314600D02*
X945300Y316100D01*
G01X949000Y314600D02*
X946800D01*
G01X950900Y316500D02*
X949000Y314600D01*
G01X951900Y316500D02*
X950900D01*
G01X953800Y318400D02*
X951900Y316500D01*
G01X955500Y318400D02*
X953800D01*
G01X957200Y320100D02*
X955500Y318400D01*
G01X958600Y320100D02*
X957200D01*
G01X960700Y322200D02*
X958600Y320100D01*
G01X962556Y322200D02*
X960700D01*
G01X964556Y324200D02*
X962556Y322200D01*
G01X965979Y324200D02*
X964556D01*
G01X968265Y326486D02*
X965979Y324200D01*
G01X969286Y326486D02*
X968265D01*
G01X970484Y327684D02*
X969286Y326486D01*
G01X971984Y327684D02*
X970484D01*
G01X959000Y519774D02*
Y527669D01*
G01X957283Y518057D02*
X959000Y519774D01*
G01X958500Y516840D02*
X957283Y518057D01*
G01X958500Y514900D02*
Y516840D01*
G01X960700Y512700D02*
X958500Y514900D01*
G01X960700Y512600D02*
Y512700D01*
G01X963000Y510300D02*
X960700Y512600D01*
G01X963000Y499644D02*
Y510300D01*
G01X988700Y473944D02*
X963000Y499644D01*
G01X959275Y587175D02*
Y591665D01*
G01X959000Y586900D02*
X959275Y587175D01*
G01X959000Y574099D02*
Y586900D01*
G01X959305Y573794D02*
X959000Y574099D01*
G01X959305Y568456D02*
Y573794D01*
G01X957592Y566743D02*
X959305Y568456D01*
G01X959000Y565335D02*
X957592Y566743D01*
G01X959000Y557574D02*
Y565335D01*
G01X957283Y555857D02*
X959000Y557574D01*
G01Y527669D02*
X957806Y528863D01*
G01X959334Y553806D02*
X957283Y555857D01*
G01X959334Y549834D02*
Y553806D01*
G01X958900Y549400D02*
X959334Y549834D01*
G01X958900Y535542D02*
Y549400D01*
G01X959186Y535256D02*
X958900Y535542D01*
G01X959186Y530243D02*
Y535256D01*
G01X957806Y528863D02*
X959186Y530243D01*
G01X959275Y591665D02*
X957283Y593657D01*
G01X959000Y605985D02*
X957765Y607220D01*
G01X959000Y595374D02*
Y605985D01*
G01X957283Y593657D02*
X959000Y595374D01*
G01X974100Y329800D02*
X971984Y327684D01*
G01X976100Y329800D02*
X974100D01*
G01X977800Y328100D02*
X976100Y329800D01*
G01X979499Y328100D02*
X977800D01*
G01X981499Y330100D02*
X979499Y328100D01*
G01X982930Y330100D02*
X981499D01*
G01X984413Y331583D02*
X982930Y330100D01*
G01X986596Y331583D02*
X984413D01*
G01X987793Y330386D02*
X986596Y331583D01*
G01X989503Y330386D02*
X987793D01*
G01X991456Y332339D02*
X989503Y330386D01*
G01X992477Y332339D02*
X991456D01*
G01X994428Y334290D02*
X992477Y332339D01*
G01X995857Y334290D02*
X994428D01*
G01X996900Y335333D02*
X995857Y334290D01*
G01X996900Y338600D02*
Y335333D01*
G01X998000Y339700D02*
X996900Y338600D01*
G01X998800Y339700D02*
X998000D01*
G01X1000300Y341200D02*
X998800Y339700D01*
G01X1000300Y348270D02*
Y341200D01*
G01X1029200Y340400D02*
Y344730D01*
G01X1033450Y336150D02*
X1029200Y340400D01*
G01X1001800Y349770D02*
X1000300Y348270D01*
G01X1002900Y349770D02*
X1001800D01*
G01X1004300Y351170D02*
X1002900Y349770D01*
G01X1005920Y351170D02*
X1004300D01*
G01X1007274Y349816D02*
X1005920Y351170D01*
G01X1033300Y351400D02*
X1031800D01*
G01X1034810Y349890D02*
X1033300Y351400D01*
G01X989100Y398781D02*
Y418901D01*
G01X988817Y398498D02*
X989100Y398781D01*
G01X988817Y392729D02*
Y398498D01*
G01X1029200Y344730D02*
X1027980Y345950D01*
G01X988700Y419301D02*
Y473944D01*
G01X989100Y418901D02*
X988700Y419301D01*
G01X1086986Y343595D02*
X1107051Y323530D01*
G01X1039150Y336150D02*
X1033450D01*
G01X1044979Y341979D02*
X1039150Y336150D01*
G01X1106255Y322655D02*
X1086931Y341979D01*
G01X1055890Y349890D02*
X1034810D01*
G01X1059500Y353500D02*
X1055890Y349890D01*
G01X1061300Y353500D02*
X1059500D01*
G01X1063300Y351500D02*
X1061300Y353500D01*
G01X1074500Y351500D02*
X1063300D01*
G01X1075300Y350700D02*
X1074500Y351500D01*
G01X1098100Y350700D02*
X1075300D01*
G01X1076435Y343595D02*
X1086986D01*
G01X1086931Y341979D02*
X1044979D01*
G01X1045220Y620146D02*
X1044828Y620538D01*
G01X1045229Y620146D02*
X1045220D01*
G01X1045335Y620040D02*
X1045229Y620146D01*
G01X1045359Y620040D02*
X1045335D01*
G01X1045702Y619697D02*
X1045359Y620040D01*
G01X1266513Y619697D02*
X1045702D01*
G01X1045844Y621650D02*
X1045452Y622042D01*
G01X1045853Y621650D02*
X1045844D01*
G01X1045913Y621590D02*
X1045853Y621650D01*
G01X1045937Y621590D02*
X1045913D01*
G01X1046070Y621457D02*
X1045937Y621590D01*
G01X1267542Y621457D02*
X1046070D01*
G01X1044908Y619394D02*
X1044516Y619786D01*
G01X1044917Y619394D02*
X1044908D01*
G01X1045766Y618545D02*
X1044917Y619394D01*
G01X1266601Y618545D02*
X1045766D01*
G01X1045532Y620898D02*
X1045140Y621290D01*
G01X1045541Y620898D02*
X1045532D01*
G01X1045647Y620792D02*
X1045541Y620898D01*
G01X1045671Y620792D02*
X1045647D01*
G01X1046014Y620449D02*
X1045671Y620792D01*
G01X1266825Y620449D02*
X1046014D01*
G01X1044201Y617690D02*
X1043809Y618082D01*
G01X1044210Y617690D02*
X1044201D01*
G01X1045459Y616441D02*
X1044210Y617690D01*
G01X1265728Y616441D02*
X1045459D01*
G01X1045779Y622779D02*
X1045764Y622794D01*
G01X1046500Y623500D02*
X1045779Y622779D01*
G01X1044596Y618642D02*
X1044204Y619034D01*
G01X1044605Y618642D02*
X1044596D01*
G01X1045854Y617393D02*
X1044605Y618642D01*
G01X1266123Y617393D02*
X1045854D01*
G01X1149370Y279572D02*
G02X1145990I-1690J975D01*
G01X1154440Y278596D02*
G02X1152751Y279572I1J1951D01*
G01X1156309Y279528D02*
G02X1154440Y278596I-2214J2100D01*
G01X1158089Y280148D02*
G03X1156309Y279528I-290J-2034D01*
G01X1155804Y264160D02*
G03X1155823Y265699I-1364J786D01*
G01X1156456Y263783D02*
G03X1156481Y266068I-2016J1165D01*
G01X1155804Y275861D02*
G02X1157359Y276979I2016J-1163D01*
G01X1154468Y275073D02*
G03X1155804Y275861I-28J1574D01*
G01X1153979Y275028D02*
G02X1154468Y275073I453J-2240D01*
G01X1152424Y273910D02*
G02X1153979Y275028I2016J-1163D01*
G01X1151088Y273122D02*
G03X1152424Y273910I-28J1574D01*
G01X1150965Y273122D02*
X1151088D01*
G01X1149019Y269675D02*
G02X1150965Y273122I2041J1121D01*
G01X1149044Y269633D02*
X1149019Y269675D01*
G01X1149063Y269599D02*
X1149044Y269633D01*
G01X1147728Y267273D02*
G03X1149063Y269599I-48J1574D01*
G01X1147599Y267273D02*
X1147728D01*
G01X1145805Y266327D02*
G02X1147599Y267273I1874J-1380D01*
G01X1145453Y266232D02*
X1145805Y266327D01*
G01X1144300Y266896D02*
X1145453Y266232D01*
G01X1142169Y266800D02*
X1143349Y265620D01*
G01X1140500Y266800D02*
X1142169D01*
G01X1138400Y268900D02*
X1140500Y266800D01*
G01X1137000Y268900D02*
X1138400D01*
G01X1135300Y270600D02*
X1137000Y268900D01*
G01X1130900Y270600D02*
X1135300D01*
G01X1125355Y276145D02*
X1130900Y270600D01*
G01X1125355Y280082D02*
Y276145D01*
G01X1155610Y270980D02*
X1157377Y272747D01*
G01X1153360Y270980D02*
X1155610D01*
G01X1152659Y270279D02*
X1153360Y270980D01*
G01X1152659Y266233D02*
Y270279D01*
G01X1151723Y265297D02*
X1152659Y266233D01*
G01X1150521Y265297D02*
X1151723D01*
G01X1148324Y263100D02*
X1150521Y265297D01*
G01X1146458Y263100D02*
X1148324D01*
G01X1144986Y264572D02*
X1146458Y263100D01*
G01X1143614Y264572D02*
X1144986D01*
G01X1142142Y263100D02*
X1143614Y264572D01*
G01X1138800Y263100D02*
X1142142D01*
G01X1135680Y266220D02*
X1138800Y263100D01*
G01X1132780Y266220D02*
X1135680D01*
G01X1122884Y276116D02*
X1132780Y266220D01*
G01X1122884Y278066D02*
Y276116D01*
G01X1120759Y280191D02*
X1122884Y278066D01*
G01X1139621Y326449D02*
X1140920Y323446D01*
G01X1139556Y326560D02*
X1139621Y326449D01*
G01X1139537Y328099D02*
G03X1139556Y326560I1383J-753D01*
G01Y328133D02*
X1139537Y328099D01*
G01X1139581Y328175D02*
X1139556Y328133D01*
G01Y330460D02*
G02X1139581Y328175I-2016J-1165D01*
G01X1139537Y331999D02*
G03X1139556Y330460I1383J-753D01*
G01Y332033D02*
X1139537Y331999D01*
G01X1139581Y332075D02*
X1139556Y332033D01*
G01Y334360D02*
G02X1139581Y332075I-2016J-1165D01*
G01X1139537Y335899D02*
G03X1139556Y334360I1383J-753D01*
G01Y335933D02*
X1139537Y335899D01*
G01X1139581Y335975D02*
X1139556Y335933D01*
G01Y338260D02*
G02X1139581Y335975I-2016J-1165D01*
G01X1139537Y339799D02*
G03X1139556Y338260I1383J-753D01*
G01Y339833D02*
X1139537Y339799D01*
G01X1139581Y339875D02*
X1139556Y339833D01*
G01Y342160D02*
G02X1139581Y339875I-2016J-1165D01*
G01X1155804Y293033D02*
G03X1159836I2016J1163D01*
G01X1154468Y293821D02*
G02X1155804Y293033I-28J-1574D01*
G01X1154345Y293821D02*
X1154468D01*
G01X1152424Y294983D02*
G03X1154345Y293821I2016J1164D01*
G01X1151108Y295770D02*
G02X1152424Y294983I-48J-1574D01*
G01X1150979Y295770D02*
X1151108D01*
G01X1149044Y296933D02*
G03X1150979Y295770I2016J1163D01*
G01X1147708Y297721D02*
G02X1149044Y296933I-28J-1574D01*
G01X1147585Y297721D02*
X1147708D01*
G01X1145664Y298883D02*
G03X1147585Y297721I2016J1164D01*
G01X1144528Y299654D02*
G02X1145664Y298883I-228J-1558D01*
G01X1143930Y299687D02*
G02X1144528Y299654I117J-3323D01*
G01X1142651Y300689D02*
G03X1143930Y299687I1235J259D01*
G01X1140985Y301997D02*
G02X1142651Y300689I-66J-1799D01*
G01X1140920Y301997D02*
X1140985D01*
G01X1137540Y301996D02*
G02X1140920Y301997I3380J-5712199D01*
G01X1135850Y301021D02*
X1134160Y303947D01*
G01X1135850Y301022D02*
Y301021D01*
G01Y299072D02*
G03Y301022I-1690J975D01*
G01X1135818Y297177D02*
G02X1135850Y299072I1722J919D01*
G01Y297122D02*
X1135818Y297177D01*
G01X1135850Y295172D02*
G03Y297122I-1690J975D01*
G01X1135818Y293277D02*
G02X1135850Y295172I1722J919D01*
G01Y293222D02*
X1135818Y293277D01*
G01X1137539Y292246D02*
G02X1135850Y293222I0J1949D01*
G01X1137619Y292246D02*
X1137539D01*
G01X1139230Y291272D02*
G03X1137619Y292246I-1690J-976D01*
G01X1140855Y290297D02*
G02X1139230Y291272I65J1950D01*
G01X1140985Y290297D02*
X1140855D01*
G01X1142610Y289322D02*
G03X1140985Y290297I-1690J-975D01*
G01X1144252Y288346D02*
G02X1142610Y289322I48J1950D01*
G01X1144379Y288346D02*
X1144252D01*
G01X1145990Y287372D02*
G03X1144379Y288346I-1690J-976D01*
G01X1147615Y286397D02*
G02X1145990Y287372I65J1950D01*
G01X1147745Y286397D02*
X1147615D01*
G01X1149370Y285422D02*
G03X1147745Y286397I-1690J-975D01*
G01X1151012Y284446D02*
G02X1149370Y285422I48J1950D01*
G01X1151139Y284446D02*
X1151012D01*
G01X1152750Y283472D02*
G03X1151139Y284446I-1690J-976D01*
G01X1154375Y282497D02*
G02X1152750Y283472I65J1950D01*
G01X1154505Y282497D02*
X1154375D01*
G01X1156262Y281800D02*
G03X1154505Y282497I-1757J-1866D01*
G01X1156741Y281349D02*
X1156262Y281800D01*
G01X1157551Y280944D02*
G02X1156741Y281349I270J1552D01*
G01X1117548Y289252D02*
X1115230D01*
G01X1118300Y288500D02*
X1117548Y289252D01*
G01X1121615Y288500D02*
X1118300D01*
G01X1123415Y286700D02*
X1121615Y288500D01*
G01X1137540Y284446D02*
X1134160Y284447D01*
G01X1137619Y284446D02*
X1137540D01*
G01X1139230Y283472D02*
G03X1137619Y284446I-1690J-976D01*
G01X1140919Y282497D02*
G02X1139230Y283472I0J1950D01*
G01X1140985Y282497D02*
X1140919D01*
G01X1142610Y281522D02*
G03X1140985Y282497I-1690J-975D01*
G01X1144252Y280546D02*
G02X1142610Y281522I48J1950D01*
G01X1144379Y280546D02*
X1144252D01*
G01X1145990Y279572D02*
G03X1144379Y280546I-1690J-976D01*
G01X1150981D02*
G03X1149370Y279572I79J-1950D01*
G01X1151139Y280546D02*
X1150981D01*
G01X1152750Y279572D02*
G03X1151139Y280546I-1690J-976D01*
G01X1152751Y279572D02*
X1152750D01*
G01X1110300Y339900D02*
X1108300Y341900D01*
G01X1110300Y326200D02*
Y339900D01*
G01X1109200Y325100D02*
X1110300Y326200D01*
G01X1132861Y330349D02*
X1134160Y327347D01*
G01X1132796Y330460D02*
X1132861Y330349D01*
G01X1132777Y331999D02*
G03X1132796Y330460I1383J-753D01*
G01Y332033D02*
X1132777Y331999D01*
G01X1132821Y332075D02*
X1132796Y332033D01*
G01Y334360D02*
G02X1132821Y332075I-2016J-1165D01*
G01X1132777Y335899D02*
G03X1132796Y334360I1383J-753D01*
G01Y335933D02*
X1132777Y335899D01*
G01X1132821Y335975D02*
X1132796Y335933D01*
G01Y338260D02*
G02X1132821Y335975I-2016J-1165D01*
G01X1132777Y339799D02*
G03X1132796Y338260I1383J-753D01*
G01Y339833D02*
X1132777Y339799D01*
G01X1132821Y339875D02*
X1132796Y339833D01*
G01Y342160D02*
G02X1132821Y339875I-2016J-1165D01*
G01X1155804Y314860D02*
G02X1159836I2016J-1164D01*
G01X1154488Y314073D02*
G03X1155804Y314860I-48J1574D01*
G01X1154359Y314073D02*
X1154488D01*
G01X1152424Y312910D02*
G02X1154359Y314073I2016J-1163D01*
G01X1151058Y312126D02*
G03X1152424Y312910I9J1567D01*
G01X1150979Y312123D02*
X1151058Y312126D01*
G01X1148927Y308864D02*
G02X1150979Y312123I2133J933D01*
G01X1148833Y308512D02*
X1148927Y308864D01*
G01X1147680Y307847D02*
X1148833Y308512D01*
G01X1122277Y340519D02*
Y345211D01*
G01X1123370Y339426D02*
X1122277Y340519D01*
G01X1123912Y339426D02*
X1123370D01*
G01X1126621Y336717D02*
X1123912Y339426D01*
G01X1128051Y336717D02*
X1126621D01*
G01X1128970Y335798D02*
X1128051Y336717D01*
G01X1128970Y316741D02*
Y335798D01*
G01X1130094Y315617D02*
X1128970Y316741D01*
G01X1131494Y315617D02*
X1130094D01*
G01X1133046Y314065D02*
X1131494Y315617D01*
G01X1135237Y314065D02*
X1133046D01*
G01X1136515Y315343D02*
X1135237Y314065D01*
G01X1138770Y315343D02*
X1136515D01*
G01X1140275Y313838D02*
X1138770Y315343D01*
G01X1142102Y313838D02*
X1140275D01*
G01X1143534Y315270D02*
X1142102Y313838D01*
G01X1144381Y315270D02*
X1143534D01*
G01X1146316Y316433D02*
G02X1144381Y315270I-2016J1163D01*
G01X1149044Y316433D02*
G03X1146316I-1364J-786D01*
G01X1153076D02*
G02X1149044I-2016J1163D01*
G01X1154412Y317221D02*
G03X1153076Y316433I28J-1574D01*
G01X1154535Y317221D02*
X1154412D01*
G01X1156456Y318383D02*
G02X1154535Y317221I-2016J1164D01*
G01X1157772Y319170D02*
G03X1156456Y318383I48J-1574D01*
G01X1111200Y337600D02*
X1120447Y346847D01*
G01X1111200Y324879D02*
Y337600D01*
G01X1109851Y323530D02*
X1111200Y324879D01*
G01X1107051Y323530D02*
X1109851D01*
G01X1135590Y324118D02*
X1137540Y321496D01*
G01X1135524Y324233D02*
X1135590Y324118D01*
G01X1134208Y325020D02*
G02X1135524Y324233I-48J-1574D01*
G01X1134095Y325020D02*
X1134208D01*
G01X1132119Y328468D02*
G03X1134095Y325020I2041J-1121D01*
G01X1132144Y328510D02*
X1132119Y328468D01*
G01X1132163Y328544D02*
X1132144Y328510D01*
G01Y330083D02*
G02X1132163Y328544I-1364J-786D01*
G01X1132119Y332368D02*
G03X1132144Y330083I2041J-1120D01*
G01Y332410D02*
X1132119Y332368D01*
G01X1132163Y332444D02*
X1132144Y332410D01*
G01Y333983D02*
G02X1132163Y332444I-1364J-786D01*
G01X1132119Y336268D02*
G03X1132144Y333983I2041J-1120D01*
G01Y336310D02*
X1132119Y336268D01*
G01X1132163Y336344D02*
X1132144Y336310D01*
G01Y337883D02*
G02X1132163Y336344I-1364J-786D01*
G01X1132119Y340168D02*
G03X1132144Y337883I2041J-1120D01*
G01Y340210D02*
X1132119Y340168D01*
G01X1132163Y340244D02*
X1132144Y340210D01*
G01Y341783D02*
G02X1132163Y340244I-1364J-786D01*
G01X1149907Y309132D02*
X1151060Y309797D01*
G01X1149597Y309216D02*
X1149907Y309132D01*
G01X1151141Y311370D02*
G03X1149597Y309216I-81J-1573D01*
G01X1153076Y312533D02*
G02X1151141Y311370I-2015J1161D01*
G01X1154412Y313321D02*
G03X1153076Y312533I28J-1574D01*
G01X1154535Y313321D02*
X1154412D01*
G01X1156456Y314483D02*
G02X1154535Y313321I-2016J1164D01*
G01X1159184Y314483D02*
G03X1156456I-1364J-787D01*
G01X1140920Y298097D02*
X1137540Y298096D01*
G01X1142087Y297339D02*
G03X1140920Y298097I-1098J-413D01*
G01X1142425Y296716D02*
G02X1142087Y297339I2080J1532D01*
G01X1144219Y295770D02*
G02X1142425Y296716I80J2326D01*
G01X1144348Y295770D02*
X1144219D01*
G01X1145664Y294983D02*
G03X1144348Y295770I-1364J-787D01*
G01X1147585Y293821D02*
G02X1145664Y294983I95J2326D01*
G01X1147708Y293821D02*
X1147585D01*
G01X1149044Y293033D02*
G03X1147708Y293821I-1364J-786D01*
G01X1150979Y291870D02*
G02X1149044Y293033I81J2326D01*
G01X1151108Y291870D02*
X1150979D01*
G01X1152424Y291083D02*
G03X1151108Y291870I-1364J-787D01*
G01X1154345Y289921D02*
G02X1152424Y291083I95J2326D01*
G01X1154468Y289921D02*
X1154345D01*
G01X1155804Y289133D02*
G03X1154468Y289921I-1364J-786D01*
G01X1159836Y289133D02*
G02X1155804I-2016J1163D01*
G01X1147761Y294573D02*
X1147632D01*
G01X1149696Y293410D02*
G03X1147761Y294573I-2016J-1163D01*
G01X1151032Y292622D02*
G02X1149696Y293410I28J1574D01*
G01X1151155Y292622D02*
X1151032D01*
G01X1153076Y291460D02*
G03X1151155Y292622I-2016J-1164D01*
G01X1154392Y290673D02*
G02X1153076Y291460I48J1574D01*
G01X1154521Y290673D02*
X1154392D01*
G01X1156456Y289510D02*
G03X1154521Y290673I-2016J-1163D01*
G01X1159184Y289510D02*
G02X1156456I-1364J786D01*
G01X1142348Y320220D02*
X1144300Y317596D01*
G01X1142284Y320333D02*
X1142348Y320220D01*
G01X1142284Y322659D02*
G03Y320333I2016J-1163D01*
G01Y324233D02*
G02Y322659I-1364J-787D01*
G01X1142259Y324275D02*
X1142284Y324233D01*
G01Y326560D02*
G03X1142259Y324275I2016J-1165D01*
G01X1142303Y328099D02*
G02X1142284Y326560I-1383J-753D01*
G01Y328133D02*
X1142303Y328099D01*
G01X1142259Y328175D02*
X1142284Y328133D01*
G01Y330460D02*
G03X1142259Y328175I2016J-1165D01*
G01X1142303Y331999D02*
G02X1142284Y330460I-1383J-753D01*
G01Y332033D02*
X1142303Y331999D01*
G01X1142259Y332075D02*
X1142284Y332033D01*
G01Y334360D02*
G03X1142259Y332075I2016J-1165D01*
G01X1142303Y335899D02*
G02X1142284Y334360I-1383J-753D01*
G01Y335933D02*
X1142303Y335899D01*
G01X1142259Y335975D02*
X1142284Y335933D01*
G01Y338260D02*
G03X1142259Y335975I2016J-1165D01*
G01X1142303Y339799D02*
G02X1142284Y338260I-1383J-753D01*
G01Y339833D02*
X1142303Y339799D01*
G01X1142259Y339875D02*
X1142284Y339833D01*
G01Y342160D02*
G03X1142259Y339875I2016J-1165D01*
G01X1110105Y322655D02*
X1106255D01*
G01X1112880Y325430D02*
X1110105Y322655D01*
G01X1118250Y325430D02*
X1112880D01*
G01X1123730Y319950D02*
X1118250Y325430D01*
G01X1123730Y312150D02*
Y319950D01*
G01X1125720Y310160D02*
X1123730Y312150D01*
G01X1127656Y310160D02*
X1125720D01*
G01X1144300Y300666D02*
Y301996D01*
G01X1144556Y300410D02*
X1144300Y300666D01*
G01X1146316Y299260D02*
G03X1144556Y300410I-2016J-1164D01*
G01X1147632Y298473D02*
G02X1146316Y299260I48J1574D01*
G01X1147761Y298473D02*
X1147632D01*
G01X1149696Y297310D02*
G03X1147761Y298473I-2016J-1163D01*
G01X1151032Y296522D02*
G02X1149696Y297310I28J1574D01*
G01X1151155Y296522D02*
X1151032D01*
G01X1153076Y295360D02*
G03X1151155Y296522I-2016J-1164D01*
G01X1154392Y294573D02*
G02X1153076Y295360I48J1574D01*
G01X1154521Y294573D02*
X1154392D01*
G01X1156456Y293410D02*
G03X1154521Y294573I-2016J-1163D01*
G01X1159184Y293410D02*
G02X1156456I-1364J786D01*
G01X1138923Y340244D02*
G03X1138904Y341783I-1383J753D01*
G01Y340210D02*
X1138923Y340244D01*
G01X1138879Y340168D02*
X1138904Y340210D01*
G01Y337883D02*
G02X1138879Y340168I2016J1165D01*
G01X1138923Y336344D02*
G03X1138904Y337883I-1383J753D01*
G01Y336310D02*
X1138923Y336344D01*
G01X1138879Y336268D02*
X1138904Y336310D01*
G01Y333983D02*
G02X1138879Y336268I2016J1165D01*
G01X1138923Y332444D02*
G03X1138904Y333983I-1383J753D01*
G01Y332410D02*
X1138923Y332444D01*
G01X1138879Y332368D02*
X1138904Y332410D01*
G01Y330083D02*
G02X1138879Y332368I2016J1165D01*
G01X1138923Y328544D02*
G03X1138904Y330083I-1383J753D01*
G01Y328510D02*
X1138923Y328544D01*
G01X1138837Y328395D02*
X1138904Y328510D01*
G01X1137540Y325396D02*
X1138837Y328395D01*
G01X1155804Y318760D02*
G02X1157725Y319922I2016J-1164D01*
G01X1154488Y317973D02*
G03X1155804Y318760I-48J1574D01*
G01X1154359Y317973D02*
X1154488D01*
G01X1152424Y316810D02*
G02X1154359Y317973I2016J-1163D01*
G01X1149696Y316810D02*
G03X1152424I1364J786D01*
G01X1145664D02*
G02X1149696I2016J-1163D01*
G01X1144328Y316022D02*
G03X1145664Y316810I-28J1574D01*
G01X1143488Y316022D02*
X1144328D01*
G01X1141891Y317619D02*
X1143488Y316022D01*
G01X1140033Y317619D02*
X1141891D01*
G01X1139163Y318489D02*
X1140033Y317619D01*
G01X1139163Y322155D02*
Y318489D01*
G01X1137540Y323778D02*
X1139163Y322155D01*
G01X1137540Y325396D02*
Y323778D01*
G01X1120700Y284737D02*
X1125355Y280082D01*
G01X1118670Y284737D02*
X1120700D01*
G01X1116999Y286408D02*
X1118670Y284737D01*
G01X1116999Y286826D02*
Y286408D01*
G01X1116155Y280191D02*
X1120759D01*
G01X1115786Y280560D02*
X1116155Y280191D01*
G01X1114340Y280560D02*
X1115786D01*
G01X1110300Y294534D02*
X1113132Y291702D01*
G01X1110300Y320200D02*
Y294534D01*
G01X1113500Y323400D02*
X1110300Y320200D01*
G01X1130113Y288721D02*
X1130865D01*
G01X1128374Y290460D02*
X1130113Y288721D01*
G01X1127470Y290672D02*
G02X1128374Y290460I-68J-2325D01*
G01X1123602Y290672D02*
X1127470D01*
G01X1122141Y292133D02*
X1123602Y290672D01*
G01X1117901Y292133D02*
X1122141D01*
G01X1117470Y291702D02*
X1117901Y292133D01*
G01X1113132Y291702D02*
X1117470D01*
G01X1139537Y343699D02*
G03X1139556Y342160I1383J-753D01*
G01Y343733D02*
X1139537Y343699D01*
G01X1139581Y343775D02*
X1139556Y343733D01*
G01Y346060D02*
G02X1139581Y343775I-2016J-1165D01*
G01X1139537Y347599D02*
G03X1139556Y346060I1383J-753D01*
G01Y347633D02*
X1139537Y347599D01*
G01X1139581Y347675D02*
X1139556Y347633D01*
G01Y349960D02*
G02X1139581Y347675I-2016J-1165D01*
G01X1139537Y351499D02*
G03X1139556Y349960I1383J-753D01*
G01Y351533D02*
X1139537Y351499D01*
G01X1139581Y351575D02*
X1139556Y351533D01*
G01Y353860D02*
G02X1139581Y351575I-2016J-1165D01*
G01X1140892Y356221D02*
G03X1139556Y353860I28J-1574D01*
G01X1141015Y356221D02*
X1140892D01*
G01X1142936Y357383D02*
G02X1141015Y356221I-2016J1164D01*
G01X1144252Y358170D02*
G03X1142936Y357383I48J-1574D01*
G01X1144381Y358170D02*
X1144252D01*
G01X1146316Y359333D02*
G02X1144381Y358170I-2016J1163D01*
G01X1147652Y360121D02*
G03X1146316Y359333I28J-1574D01*
G01X1147775Y360121D02*
X1147652D01*
G01X1149696Y361283D02*
G02X1147775Y360121I-2016J1164D01*
G01X1151012Y362070D02*
G03X1149696Y361283I48J-1574D01*
G01X1151141Y362070D02*
X1151012D01*
G01X1153076Y365560D02*
G02X1151141Y362070I-2016J-1164D01*
G01X1153057Y367099D02*
G03X1153076Y365560I1383J-753D01*
G01Y367133D02*
X1153057Y367099D01*
G01X1153101Y367175D02*
X1153076Y367133D01*
G01Y369460D02*
G02X1153101Y367175I-2016J-1165D01*
G01X1153076Y371034D02*
G03Y369460I1364J-787D01*
G01Y373360D02*
G02Y371034I-2016J-1163D01*
G01X1153057Y373394D02*
X1153076Y373360D01*
G01Y374933D02*
G03X1153057Y373394I1364J-786D01*
G01X1153101Y374975D02*
X1153076Y374933D01*
G01Y377260D02*
G02X1153101Y374975I-2016J-1165D01*
G01X1153057Y378799D02*
G03X1153076Y377260I1383J-753D01*
G01Y378833D02*
X1153057Y378799D01*
G01X1153101Y378875D02*
X1153076Y378833D01*
G01Y381160D02*
G02X1153101Y378875I-2016J-1165D01*
G01X1153057Y382699D02*
G03X1153076Y381160I1383J-753D01*
G01Y382733D02*
X1153057Y382699D01*
G01X1153101Y382775D02*
X1153076Y382733D01*
G01Y385060D02*
G02X1153101Y382775I-2016J-1165D01*
G01X1153057Y386599D02*
G03X1153076Y385060I1383J-753D01*
G01Y386633D02*
X1153057Y386599D01*
G01X1153101Y386675D02*
X1153076Y386633D01*
G01Y388960D02*
G02X1153101Y386675I-2016J-1165D01*
G01X1154412Y391321D02*
G03X1153076Y388960I28J-1574D01*
G01X1154535Y391321D02*
X1154412D01*
G01X1156481Y394768D02*
G02X1154535Y391321I-2041J-1121D01*
G01X1156456Y394810D02*
X1156481Y394768D01*
G01X1156437Y396349D02*
G03X1156456Y394810I1383J-753D01*
G01Y396383D02*
X1156437Y396349D01*
G01X1158066Y397230D02*
G03X1156456Y396383I-154J-1661D01*
G01X1106900Y341900D02*
X1098100Y350700D01*
G01X1108300Y341900D02*
X1106900D01*
G01X1132777Y343699D02*
G03X1132796Y342160I1383J-753D01*
G01Y343733D02*
X1132777Y343699D01*
G01X1132821Y343775D02*
X1132796Y343733D01*
G01Y346060D02*
G02X1132821Y343775I-2016J-1165D01*
G01X1132777Y347599D02*
G03X1132796Y346060I1383J-753D01*
G01Y347633D02*
X1132777Y347599D01*
G01X1132821Y347675D02*
X1132796Y347633D01*
G01Y349960D02*
G02X1132821Y347675I-2016J-1165D01*
G01X1132777Y351499D02*
G03X1132796Y349960I1383J-753D01*
G01Y351533D02*
X1132777Y351499D01*
G01X1132821Y351575D02*
X1132796Y351533D01*
G01Y353860D02*
G02X1132821Y351575I-2016J-1165D01*
G01X1134132Y356221D02*
G03X1132796Y353860I28J-1574D01*
G01X1134255Y356221D02*
X1134132D01*
G01X1136176Y357383D02*
G02X1134255Y356221I-2016J1164D01*
G01X1137492Y358170D02*
G03X1136176Y357383I48J-1574D01*
G01X1137621Y358170D02*
X1137492D01*
G01X1139556Y359333D02*
G02X1137621Y358170I-2016J1163D01*
G01X1140892Y360121D02*
G03X1139556Y359333I28J-1574D01*
G01X1141015Y360121D02*
X1140892D01*
G01X1142936Y361283D02*
G02X1141015Y360121I-2016J1164D01*
G01X1144252Y362070D02*
G03X1142936Y361283I48J-1574D01*
G01X1144381Y362070D02*
X1144252D01*
G01X1146316Y363233D02*
G02X1144381Y362070I-2016J1163D01*
G01X1147652Y364021D02*
G03X1146316Y363233I28J-1574D01*
G01X1147775Y364021D02*
X1147652D01*
G01X1149721Y367468D02*
G02X1147775Y364021I-2041J-1121D01*
G01X1149696Y367510D02*
X1149721Y367468D01*
G01X1149677Y367544D02*
X1149696Y367510D01*
G01Y369083D02*
G03X1149677Y367544I1364J-786D01*
G01X1149721Y371368D02*
G02X1149696Y369083I-2041J-1120D01*
G01Y371410D02*
X1149721Y371368D01*
G01X1149677Y372949D02*
G03X1149696Y371410I1383J-753D01*
G01Y372983D02*
X1149677Y372949D01*
G01X1149696Y375309D02*
G02Y372983I-2016J-1163D01*
G01Y376883D02*
G03Y375309I1364J-787D01*
G01X1149721Y379168D02*
G02X1149696Y376883I-2041J-1120D01*
G01Y379210D02*
X1149721Y379168D01*
G01X1149677Y379244D02*
X1149696Y379210D01*
G01Y380783D02*
G03X1149677Y379244I1364J-786D01*
G01X1149721Y383068D02*
G02X1149696Y380783I-2041J-1120D01*
G01Y383110D02*
X1149721Y383068D01*
G01X1149677Y383144D02*
X1149696Y383110D01*
G01Y384683D02*
G03X1149677Y383144I1364J-786D01*
G01X1149721Y386968D02*
G02X1149696Y384683I-2041J-1120D01*
G01Y387010D02*
X1149721Y386968D01*
G01X1149677Y387044D02*
X1149696Y387010D01*
G01Y388583D02*
G03X1149677Y387044I1364J-786D01*
G01X1149721Y390868D02*
G02X1149696Y388583I-2041J-1120D01*
G01Y390910D02*
X1149721Y390868D01*
G01X1149677Y390944D02*
X1149696Y390910D01*
G01X1151012Y393270D02*
G03X1149677Y390944I48J-1574D01*
G01X1151104Y393270D02*
X1151012D01*
G01X1153076Y396760D02*
G02X1151104Y393270I-2016J-1163D01*
G01X1153076Y398332D02*
G03Y396760I1364J-786D01*
G01X1155473Y399717D02*
G03X1153076Y398332I0J-2767D01*
G01X1157580Y399717D02*
X1155473D01*
G01X1122277Y345211D02*
X1120641Y346847D01*
G01X1120447D02*
X1120641D01*
G01X1132119Y344068D02*
G03X1132144Y341783I2041J-1120D01*
G01Y344110D02*
X1132119Y344068D01*
G01X1132163Y344144D02*
X1132144Y344110D01*
G01Y345683D02*
G02X1132163Y344144I-1364J-786D01*
G01X1132119Y347968D02*
G03X1132144Y345683I2041J-1120D01*
G01Y348010D02*
X1132119Y347968D01*
G01X1132163Y348044D02*
X1132144Y348010D01*
G01Y349583D02*
G02X1132163Y348044I-1364J-786D01*
G01X1132119Y351868D02*
G03X1132144Y349583I2041J-1120D01*
G01Y351910D02*
X1132119Y351868D01*
G01X1132163Y351944D02*
X1132144Y351910D01*
G01Y353483D02*
G02X1132163Y351944I-1364J-786D01*
G01X1134079Y356973D02*
G03X1132144Y353483I81J-2326D01*
G01X1134208Y356973D02*
X1134079D01*
G01X1135524Y357760D02*
G02X1134208Y356973I-1364J787D01*
G01X1137445Y358922D02*
G03X1135524Y357760I95J-2326D01*
G01X1137568Y358922D02*
X1137445D01*
G01X1138904Y359710D02*
G02X1137568Y358922I-1364J786D01*
G01X1140839Y360873D02*
G03X1138904Y359710I81J-2326D01*
G01X1140968Y360873D02*
X1140839D01*
G01X1142284Y361660D02*
G02X1140968Y360873I-1364J787D01*
G01X1144205Y362822D02*
G03X1142284Y361660I95J-2326D01*
G01X1144328Y362822D02*
X1144205D01*
G01X1145664Y363610D02*
G02X1144328Y362822I-1364J786D01*
G01X1147599Y364773D02*
G03X1145664Y363610I81J-2326D01*
G01X1147728Y364773D02*
X1147599D01*
G01X1149063Y367099D02*
G02X1147728Y364773I-1383J-752D01*
G01X1149044Y367133D02*
X1149063Y367099D01*
G01X1149019Y367175D02*
X1149044Y367133D01*
G01Y369460D02*
G03X1149019Y367175I2016J-1165D01*
G01X1149044Y371034D02*
G02Y369460I-1364J-787D01*
G01Y373360D02*
G03Y371034I2016J-1163D01*
G01X1149063Y373394D02*
X1149044Y373360D01*
G01Y374933D02*
G02X1149063Y373394I-1364J-786D01*
G01X1149019Y374975D02*
X1149044Y374933D01*
G01Y377260D02*
G03X1149019Y374975I2016J-1165D01*
G01X1149063Y378799D02*
G02X1149044Y377260I-1383J-753D01*
G01Y378833D02*
X1149063Y378799D01*
G01X1149019Y378875D02*
X1149044Y378833D01*
G01Y381160D02*
G03X1149019Y378875I2016J-1165D01*
G01X1149063Y382699D02*
G02X1149044Y381160I-1383J-753D01*
G01Y382733D02*
X1149063Y382699D01*
G01X1149019Y382775D02*
X1149044Y382733D01*
G01Y385060D02*
G03X1149019Y382775I2016J-1165D01*
G01X1149063Y386599D02*
G02X1149044Y385060I-1383J-753D01*
G01Y386633D02*
X1149063Y386599D01*
G01X1149019Y386675D02*
X1149044Y386633D01*
G01Y388960D02*
G03X1149019Y386675I2016J-1165D01*
G01X1149063Y390499D02*
G02X1149044Y388960I-1383J-753D01*
G01Y390533D02*
X1149063Y390499D01*
G01X1149019Y390575D02*
X1149044Y390533D01*
G01X1150995Y394023D02*
G03X1149019Y390575I65J-2327D01*
G01X1151108Y394023D02*
X1150995D01*
G01X1152443Y396349D02*
G02X1151108Y394023I-1383J-752D01*
G01X1152424Y396383D02*
X1152443Y396349D01*
G01X1152424Y398709D02*
G03Y396383I2016J-1163D01*
G01X1153594Y399924D02*
G03X1152424Y398709I1863J-2964D01*
G01X1154749Y401376D02*
G02X1153594Y399924I-2645J919D01*
G01X1154749Y402485D02*
Y401376D01*
G01X1155358Y403094D02*
X1154749Y402485D01*
G01X1142303Y343699D02*
G02X1142284Y342160I-1383J-753D01*
G01Y343733D02*
X1142303Y343699D01*
G01X1142259Y343775D02*
X1142284Y343733D01*
G01Y346060D02*
G03X1142259Y343775I2016J-1165D01*
G01X1142303Y347599D02*
G02X1142284Y346060I-1383J-753D01*
G01Y347633D02*
X1142303Y347599D01*
G01X1142259Y347675D02*
X1142284Y347633D01*
G01Y349960D02*
G03X1142259Y347675I2016J-1165D01*
G01X1142303Y351499D02*
G02X1142284Y349960I-1383J-753D01*
G01Y351533D02*
X1142303Y351499D01*
G01X1142259Y351575D02*
X1142284Y351533D01*
G01X1144205Y355022D02*
G03X1142259Y351575I95J-2326D01*
G01X1144328Y355022D02*
X1144205D01*
G01X1145664Y355810D02*
G02X1144328Y355022I-1364J786D01*
G01X1147599Y356973D02*
G03X1145664Y355810I81J-2326D01*
G01X1147728Y356973D02*
X1147599D01*
G01X1149044Y357760D02*
G02X1147728Y356973I-1364J787D01*
G01X1150965Y358922D02*
G03X1149044Y357760I95J-2326D01*
G01X1151088Y358922D02*
X1150965D01*
G01X1152424Y359710D02*
G02X1151088Y358922I-1364J786D01*
G01X1154359Y360873D02*
G03X1152424Y359710I81J-2326D01*
G01X1154488Y360873D02*
X1154359D01*
G01X1155823Y363199D02*
G02X1154488Y360873I-1383J-752D01*
G01X1155804Y363233D02*
X1155823Y363199D01*
G01X1155779Y363275D02*
X1155804Y363233D01*
G01Y365560D02*
G03X1155779Y363275I2016J-1165D01*
G01X1155823Y367099D02*
G02X1155804Y365560I-1383J-753D01*
G01Y367133D02*
X1155823Y367099D01*
G01X1155779Y367175D02*
X1155804Y367133D01*
G01Y369460D02*
G03X1155779Y367175I2016J-1165D01*
G01X1155804Y371034D02*
G02Y369460I-1364J-787D01*
G01Y373360D02*
G03Y371034I2016J-1163D01*
G01X1155823Y373394D02*
X1155804Y373360D01*
G01Y374933D02*
G02X1155823Y373394I-1364J-786D01*
G01X1155779Y374975D02*
X1155804Y374933D01*
G01Y377260D02*
G03X1155779Y374975I2016J-1165D01*
G01X1155823Y378799D02*
G02X1155804Y377260I-1383J-753D01*
G01Y378833D02*
X1155823Y378799D01*
G01X1155779Y378875D02*
X1155804Y378833D01*
G01Y381160D02*
G03X1155779Y378875I2016J-1165D01*
G01X1155823Y382699D02*
G02X1155804Y381160I-1383J-753D01*
G01Y382733D02*
X1155823Y382699D01*
G01X1155779Y382775D02*
X1155804Y382733D01*
G01Y385060D02*
G03X1155779Y382775I2016J-1165D01*
G01X1155823Y386599D02*
G02X1155804Y385060I-1383J-753D01*
G01Y386633D02*
X1155823Y386599D01*
G01X1155779Y386675D02*
X1155804Y386633D01*
G01X1157725Y390122D02*
G03X1155779Y386675I95J-2326D01*
G01X1156125Y397199D02*
G02X1157908Y398959I17630J-16077D01*
G01X1155804Y396760D02*
G02X1156125Y397199I2183J-1259D01*
G01X1155804Y394434D02*
G02Y396760I2016J1163D01*
G01X1154488Y392073D02*
G03X1155804Y394434I-48J1574D01*
G01X1154359Y392073D02*
X1154488D01*
G01X1152424Y388583D02*
G02X1154359Y392073I2016J1164D01*
G01X1152443Y387044D02*
G03X1152424Y388583I-1383J753D01*
G01Y387010D02*
X1152443Y387044D01*
G01X1152399Y386968D02*
X1152424Y387010D01*
G01Y384683D02*
G02X1152399Y386968I2016J1165D01*
G01X1152443Y383144D02*
G03X1152424Y384683I-1383J753D01*
G01Y383110D02*
X1152443Y383144D01*
G01X1152399Y383068D02*
X1152424Y383110D01*
G01Y380783D02*
G02X1152399Y383068I2016J1165D01*
G01X1152443Y379244D02*
G03X1152424Y380783I-1383J753D01*
G01Y379210D02*
X1152443Y379244D01*
G01X1152399Y379168D02*
X1152424Y379210D01*
G01Y376883D02*
G02X1152399Y379168I2016J1165D01*
G01X1152424Y375309D02*
G03Y376883I-1364J787D01*
G01Y372983D02*
G02Y375309I2016J1163D01*
G01X1152443Y372949D02*
X1152424Y372983D01*
G01Y371410D02*
G03X1152443Y372949I-1364J786D01*
G01X1152399Y371368D02*
X1152424Y371410D01*
G01Y369083D02*
G02X1152399Y371368I2016J1165D01*
G01X1152443Y367544D02*
G03X1152424Y369083I-1383J753D01*
G01Y367510D02*
X1152443Y367544D01*
G01X1152399Y367468D02*
X1152424Y367510D01*
G01Y365183D02*
G02X1152399Y367468I2016J1165D01*
G01X1151088Y362822D02*
G03X1152424Y365183I-28J1574D01*
G01X1150965Y362822D02*
X1151088D01*
G01X1149044Y361660D02*
G02X1150965Y362822I2016J-1164D01*
G01X1147728Y360873D02*
G03X1149044Y361660I-48J1574D01*
G01X1147599Y360873D02*
X1147728D01*
G01X1145664Y359710D02*
G02X1147599Y360873I2016J-1163D01*
G01X1144328Y358922D02*
G03X1145664Y359710I-28J1574D01*
G01X1144205Y358922D02*
X1144328D01*
G01X1142284Y357760D02*
G02X1144205Y358922I2016J-1164D01*
G01X1140968Y356973D02*
G03X1142284Y357760I-48J1574D01*
G01X1140839Y356973D02*
X1140968D01*
G01X1138904Y353483D02*
G02X1140839Y356973I2016J1164D01*
G01X1138923Y351944D02*
G03X1138904Y353483I-1383J753D01*
G01Y351910D02*
X1138923Y351944D01*
G01X1138879Y351868D02*
X1138904Y351910D01*
G01Y349583D02*
G02X1138879Y351868I2016J1165D01*
G01X1138923Y348044D02*
G03X1138904Y349583I-1383J753D01*
G01Y348010D02*
X1138923Y348044D01*
G01X1138879Y347968D02*
X1138904Y348010D01*
G01Y345683D02*
G02X1138879Y347968I2016J1165D01*
G01X1138923Y344144D02*
G03X1138904Y345683I-1383J753D01*
G01Y344110D02*
X1138923Y344144D01*
G01X1138879Y344068D02*
X1138904Y344110D01*
G01Y341783D02*
G02X1138879Y344068I2016J1165D01*
G01X1158178Y403094D02*
X1155358D01*
G01X1217660Y183528D02*
X1226146Y192014D01*
G01X1217660Y166423D02*
Y183528D01*
G01X1233910Y150173D02*
X1217660Y166423D01*
G01X1202412Y211674D02*
X1219855D01*
G01X1201013Y213073D02*
X1202412Y211674D01*
G01X1202179Y212987D02*
X1221153D01*
G01X1200101Y208816D02*
X1199815D01*
G01X1205465Y203452D02*
X1200101Y208816D01*
G01X1223546Y203452D02*
X1205465D01*
G01X1202500Y179954D02*
Y194343D01*
G01X1201000Y200672D02*
X1196149Y205523D01*
G01X1201000Y179610D02*
Y200672D01*
G01X1232765Y147845D02*
X1201000Y179610D01*
G01X1204987Y202300D02*
X1197943Y209344D01*
G01X1224024Y202300D02*
X1204987D01*
G01X1214576Y214869D02*
X1207774Y221671D01*
G01X1218868Y214869D02*
X1214576D01*
G01X1215130Y262165D02*
X1223265Y270300D01*
G01X1206963Y262165D02*
X1215130D01*
G01X1206220Y261422D02*
X1206963Y262165D01*
G01X1205111Y261422D02*
X1206220D01*
G01X1203775Y262210D02*
G03X1205111Y261422I1364J786D01*
G01X1201840Y263373D02*
G02X1203775Y262210I-81J-2326D01*
G01X1201711Y263373D02*
X1201840D01*
G01X1200395Y264160D02*
G03X1201711Y263373I1364J787D01*
G01X1198444Y265323D02*
G02X1200395Y264160I-65J-2327D01*
G01X1197414Y265323D02*
X1198444D01*
G01X1196733Y264642D02*
X1197414Y265323D01*
G01X1196363Y264160D02*
G02X1196733Y264642I2016J-1164D01*
G01X1195047Y263373D02*
G03X1196363Y264160I-48J1574D01*
G01X1194951Y263373D02*
X1195047D01*
G01X1193635Y264160D02*
G03X1194951Y263373I1364J787D01*
G01X1191714Y265322D02*
G02X1193635Y264160I-95J-2326D01*
G01X1191591Y265322D02*
X1191714D01*
G01X1190255Y266110D02*
G03X1191591Y265322I1364J786D01*
G01X1186223Y266111D02*
G02X1190255Y266110I2016J-1164D01*
G01X1186210Y266088D02*
X1186223Y266111D01*
G01X1183508Y266088D02*
G03X1186210I1351J810D01*
G01X1183495Y266111D02*
X1183508Y266088D01*
G01X1179463Y266110D02*
G02X1183495Y266111I2016J-1163D01*
G01X1176735Y266110D02*
G03X1179463I1364J786D01*
G01X1174975Y267261D02*
G02X1176735Y266110I-256J-2313D01*
G01X1174719Y267517D02*
X1174975Y267261D01*
G01X1174719Y268847D02*
Y267517D01*
G01X1210525Y256163D02*
X1209936Y255574D01*
G01X1226595Y256163D02*
X1210525D01*
G01X1216362Y273571D02*
X1306172D01*
G01X1210064Y267273D02*
X1214094Y271303D01*
G01X1208438Y267273D02*
X1210064D01*
G01X1206503Y266110D02*
G02X1208438Y267273I2016J-1163D01*
G01X1205167Y265322D02*
G03X1206503Y266110I-28J1574D01*
G01X1205111Y265322D02*
X1205167D01*
G01X1203775Y266110D02*
G03X1205111Y265322I1364J786D01*
G01X1202683Y267273D02*
G02X1203775Y266110I-1925J-2901D01*
G01X1194951Y267273D02*
X1202683D01*
G01X1193635Y268060D02*
G03X1194951Y267273I1364J787D01*
G01X1191714Y269222D02*
G02X1193635Y268060I-95J-2326D01*
G01X1191591Y269222D02*
X1191714D01*
G01X1190255Y270010D02*
G03X1191591Y269222I1364J786D01*
G01X1186223Y270010D02*
G02X1190255I2016J-1163D01*
G01X1184921Y269223D02*
G03X1186223Y270010I-62J1573D01*
G01X1184797Y269223D02*
X1184921D01*
G01X1183495Y270010D02*
G03X1184797Y269223I1364J786D01*
G01X1179463Y270010D02*
G02X1183495I2016J-1163D01*
G01X1176735D02*
G03X1179463I1364J786D01*
G01X1174975Y271161D02*
G02X1176735Y270010I-256J-2313D01*
G01X1174719Y271417D02*
X1174975Y271161D01*
G01X1174719Y272747D02*
Y271417D01*
G01X1159184Y279383D02*
G03X1158089Y280148I-1364J-787D01*
G01X1161182Y278596D02*
G02X1159184Y279383I0J2930D01*
G01X1162812Y279484D02*
G02X1161182Y278596I-1339J519D01*
G01X1164133Y280212D02*
G03X1162812Y279484I-226J-1152D01*
G01X1167912Y278973D02*
G02X1166596Y279760I48J1574D01*
G01X1168187Y278990D02*
G02X1167912Y278973I-240J1645D01*
G01X1169314Y279745D02*
G02X1168187Y278990I-1354J803D01*
G01X1194951Y278973D02*
G02X1193635Y279760I48J1574D01*
G01X1195043Y278973D02*
X1194951D01*
G01X1197015Y277809D02*
G03X1195043Y278973I-2016J-1163D01*
G01X1199743Y277809D02*
G02X1197015I-1364J787D01*
G01X1203775D02*
G03X1199743I-2016J-1163D01*
G01X1206503D02*
G02X1203775I-1364J787D01*
G01X1206583Y277948D02*
X1206503Y277809D01*
G01X1208466Y278951D02*
G03X1206583Y277948I0J-2270D01*
G01X1210910Y278951D02*
X1208466D01*
G01X1216103Y284144D02*
X1210910Y278951D01*
G01X1216336Y272100D02*
X1305651D01*
G01X1210757Y266521D02*
X1216336Y272100D01*
G01X1208491Y266521D02*
X1210757D01*
G01X1207155Y265733D02*
G02X1208491Y266521I1364J-786D01*
G01X1205220Y264570D02*
G03X1207155Y265733I-81J2326D01*
G01X1205058Y264570D02*
X1205220D01*
G01X1203123Y265733D02*
G03X1205058Y264570I2016J1163D01*
G01X1202046Y266521D02*
G02X1203123Y265733I-354J-1613D01*
G01X1194904Y266521D02*
X1202046D01*
G01X1192983Y267683D02*
G03X1194904Y266521I2016J1164D01*
G01X1191667Y268470D02*
G02X1192983Y267683I-48J-1574D01*
G01X1191538Y268470D02*
X1191667D01*
G01X1189603Y269633D02*
G03X1191538Y268470I2016J1163D01*
G01X1186875Y269633D02*
G02X1189603I1364J-786D01*
G01X1184965Y268471D02*
G03X1186875Y269633I-106J2325D01*
G01X1184753Y268471D02*
X1184965D01*
G01X1182843Y269633D02*
G03X1184753Y268471I2016J1163D01*
G01X1180115Y269633D02*
G02X1182843I1364J-786D01*
G01X1176083D02*
G03X1180115I2016J1163D01*
G01X1174946Y270404D02*
G02X1176083Y269633I-226J-1558D01*
G01X1173029Y269822D02*
G02X1174946Y270404I1579J-1751D01*
G01X1171387Y268846D02*
G03X1173029Y269822I-48J1950D01*
G01X1171337Y268846D02*
X1171387D01*
G01X1169650Y267872D02*
G02X1171337Y268846I1687J-974D01*
G01X1168025Y266897D02*
G03X1169650Y267872I-65J1950D01*
G01X1167960Y266897D02*
X1168025D01*
G01X1166637Y266469D02*
X1167960Y266897D01*
G01X1163368Y263200D02*
X1166637Y266469D01*
G01X1160130Y263200D02*
X1163368D01*
G01X1159390Y262460D02*
X1160130Y263200D01*
G01X1169717Y275120D02*
X1167960Y272747D01*
G01X1169976Y275483D02*
G02X1169717Y275120I-2015J1164D01*
G01X1169985Y275498D02*
X1169976Y275483D01*
G01X1171339Y276270D02*
G03X1169985Y275498I0J-1573D01*
G01X1171420Y276270D02*
X1171339D01*
G01X1173355Y277433D02*
G02X1171420Y276270I-2016J1163D01*
G01X1176083Y277433D02*
G03X1173355I-1364J-787D01*
G01X1180115D02*
G02X1176083I-2016J1163D01*
G01X1182843D02*
G03X1180115I-1364J-787D01*
G01X1186875D02*
G02X1182843I-2016J1163D01*
G01X1189603D02*
G03X1186875I-1364J-787D01*
G01X1191538Y276270D02*
G02X1189603Y277433I81J2326D01*
G01X1191667Y276270D02*
X1191538D01*
G01X1192983Y275483D02*
G03X1191667Y276270I-1364J-787D01*
G01X1194918Y274320D02*
G02X1192983Y275483I81J2326D01*
G01X1195061Y274320D02*
X1194918D01*
G01X1196363Y273533D02*
G03X1195061Y274320I-1364J-786D01*
G01X1200395Y273533D02*
G02X1196363I-2016J1163D01*
G01X1201697Y274320D02*
G03X1200395Y273533I62J-1573D01*
G01X1201821Y274320D02*
X1201697D01*
G01X1203123Y273533D02*
G03X1201821Y274320I-1364J-786D01*
G01X1207155Y273533D02*
G02X1203123I-2016J1163D01*
G01X1207405Y273861D02*
G03X1207155Y273533I1117J-1110D01*
G01X1208651Y274377D02*
G03X1207405Y273861I0J-1762D01*
G01X1209433Y274377D02*
X1208651D01*
G01X1211327Y276271D02*
X1209433Y274377D01*
G01X1213297Y276271D02*
X1211327D01*
G01X1217194Y280168D02*
X1213297Y276271D01*
G01X1167960Y251297D02*
X1164580Y251296D01*
G01X1168025Y251297D02*
X1167960D01*
G01X1169650Y250322D02*
G03X1168025Y251297I-1690J-975D01*
G01X1170430Y248970D02*
X1169650Y250322D01*
G01X1171387Y248970D02*
X1170430D01*
G01X1172703Y248183D02*
G03X1171387Y248970I-1364J-787D01*
G01X1174624Y247021D02*
G02X1172703Y248183I95J2326D01*
G01X1174747Y247021D02*
X1174624D01*
G01X1176083Y246233D02*
G03X1174747Y247021I-1364J-786D01*
G01X1178018Y245070D02*
G02X1176083Y246233I81J2326D01*
G01X1178180Y245070D02*
X1178018D01*
G01X1180115Y246233D02*
G02X1178180Y245070I-2016J1163D01*
G01X1181451Y247021D02*
G03X1180115Y246233I28J-1574D01*
G01X1181507Y247021D02*
X1181451D01*
G01X1182843Y246233D02*
G03X1181507Y247021I-1364J-786D01*
G01X1184778Y245070D02*
G02X1182843Y246233I81J2326D01*
G01X1184940Y245070D02*
X1184778D01*
G01X1186875Y246233D02*
G02X1184940Y245070I-2016J1163D01*
G01X1188211Y247021D02*
G03X1186875Y246233I28J-1574D01*
G01X1195481Y247021D02*
X1188211D01*
G01X1196122Y246651D02*
G03X1195481Y247021I-641J-370D01*
G01X1196363Y246233D02*
X1196122Y246651D01*
G01X1198298Y245070D02*
G02X1196363Y246233I81J2326D01*
G01X1198460Y245070D02*
X1198298D01*
G01X1200395Y246233D02*
G02X1198460Y245070I-2016J1163D01*
G01X1201731Y247021D02*
G03X1200395Y246233I28J-1574D01*
G01X1225659Y247021D02*
X1201731D01*
G01X1175661Y260104D02*
X1174719Y261047D01*
G01X1176409Y260072D02*
G02X1175661Y260104I-357J424D01*
G01X1178051Y260670D02*
G03X1176409Y260072I0J-2553D01*
G01X1178247Y260670D02*
X1178051D01*
G01X1178355Y260682D02*
X1178247Y260670D01*
G01X1180115Y261833D02*
G02X1178355Y260682I-2016J1162D01*
G01X1182843Y261833D02*
G03X1180115I-1364J-786D01*
G01X1184778Y260670D02*
G02X1182843Y261833I81J2326D01*
G01X1184907Y260670D02*
X1184778D01*
G01X1186223Y259883D02*
G03X1184907Y260670I-1364J-787D01*
G01X1190255Y259883D02*
G02X1186223I-2016J1164D01*
G01X1192983D02*
G03X1190255I-1364J-787D01*
G01X1197015D02*
G02X1192983I-2016J1164D01*
G01X1199743D02*
G03X1197015I-1364J-787D01*
G01X1201664Y258721D02*
G02X1199743Y259883I95J2326D01*
G01X1201787Y258721D02*
X1201664D01*
G01X1203123Y257933D02*
G03X1201787Y258721I-1364J-786D01*
G01X1207155Y257933D02*
G02X1203123I-2016J1163D01*
G01X1208491Y258721D02*
G03X1207155Y257933I28J-1574D01*
G01X1216633Y258721D02*
X1208491D01*
G01X1222450Y264538D02*
X1216633Y258721D01*
G01X1216265Y276302D02*
X1306955D01*
G01X1211240Y271277D02*
X1216265Y276302D01*
G01X1210242Y271277D02*
X1211240D01*
G01X1210240Y271275D02*
X1210242Y271277D01*
G01X1218000Y218100D02*
X1219939D01*
G01X1214970Y232270D02*
X1213640Y233600D01*
G01X1229151Y232270D02*
X1214970D01*
G01X1216660Y275350D02*
X1306560D01*
G01X1211635Y270325D02*
X1216660Y275350D01*
G01X1210250Y270325D02*
X1211635D01*
G01X1173355Y248560D02*
G03X1171339Y251296I-13203J-7618D01*
G01X1174671Y247773D02*
G02X1173355Y248560I48J1574D01*
G01X1174800Y247773D02*
X1174671D01*
G01X1176735Y246610D02*
G03X1174800Y247773I-2016J-1163D01*
G01X1178071Y245822D02*
G02X1176735Y246610I28J1574D01*
G01X1178127Y245822D02*
X1178071D01*
G01X1179463Y246610D02*
G02X1178127Y245822I-1364J786D01*
G01X1181398Y247773D02*
G03X1179463Y246610I81J-2326D01*
G01X1181560Y247773D02*
X1181398D01*
G01X1183495Y246610D02*
G03X1181560Y247773I-2016J-1163D01*
G01X1184831Y245822D02*
G02X1183495Y246610I28J1574D01*
G01X1184887Y245822D02*
X1184831D01*
G01X1186223Y246610D02*
G02X1184887Y245822I-1364J786D01*
G01X1188158Y247773D02*
G03X1186223Y246610I81J-2326D01*
G01X1195828Y247773D02*
X1188158D01*
G01X1196604Y247324D02*
G03X1195828Y247773I-776J-446D01*
G01X1197015Y246610D02*
X1196604Y247324D01*
G01X1198351Y245822D02*
G02X1197015Y246610I28J1574D01*
G01X1198407Y245822D02*
X1198351D01*
G01X1199743Y246610D02*
G02X1198407Y245822I-1364J786D01*
G01X1201678Y247773D02*
G03X1199743Y246610I81J-2326D01*
G01X1225237Y247773D02*
X1201678D01*
G01X1211732Y278182D02*
X1216650Y283100D01*
G01X1208436Y278182D02*
X1211732D01*
G01X1207217Y277540D02*
G02X1208436Y278182I1219J-837D01*
G01X1207155Y277433D02*
X1207217Y277540D01*
G01X1203123Y277433D02*
G03X1207155I2016J1163D01*
G01X1200395D02*
G02X1203123I1364J-787D01*
G01X1196363D02*
G03X1200395I2016J1163D01*
G01X1195047Y278220D02*
G02X1196363Y277433I-48J-1574D01*
G01X1194934Y278220D02*
X1195047D01*
G01X1192983Y279383D02*
G03X1194934Y278220I2016J1164D01*
G01X1191667Y280170D02*
G02X1192983Y279383I-48J-1574D01*
G01X1169985Y279398D02*
G02X1171339Y280170I1354J-801D01*
G01X1169976Y279383D02*
X1169985Y279398D01*
G01X1168217Y278233D02*
G03X1169976Y279383I-257J2314D01*
G01X1168100Y278220D02*
X1168217Y278233D01*
G01X1167895Y278220D02*
X1168100D01*
G01X1165728Y277518D02*
G02X1167895Y278220I2167J-2994D01*
G01X1164628Y277022D02*
G03X1165728Y277518I-48J1574D01*
G01X1164499Y277022D02*
X1164628D01*
G01X1162564Y275859D02*
G02X1164499Y277022I2016J-1163D01*
G01X1161274Y275073D02*
G03X1162564Y275859I-74J1573D01*
G01X1161126Y275073D02*
X1161274D01*
G01X1159836Y275859D02*
G03X1161126Y275073I1364J787D01*
G01X1157359Y276979D02*
G02X1159836Y275859I459J-2284D01*
G01X1166333Y275452D02*
G03X1164661Y276270I-1672J-1300D01*
G01X1167879Y275073D02*
G02X1166333Y275452I0J3343D01*
G01X1168013Y275073D02*
X1167879D01*
G01X1169323Y275859D02*
G02X1168013Y275073I-1363J787D01*
G01X1171258Y277022D02*
G03X1169323Y275859I81J-2326D01*
G01X1171387Y277022D02*
X1171258D01*
G01X1172703Y277809D02*
G02X1171387Y277022I-1364J787D01*
G01X1176735Y277809D02*
G03X1172703I-2016J-1163D01*
G01X1179463D02*
G02X1176735I-1364J787D01*
G01X1183495D02*
G03X1179463I-2016J-1163D01*
G01X1186223D02*
G02X1183495I-1364J787D01*
G01X1190255D02*
G03X1186223I-2016J-1163D01*
G01X1191571Y277022D02*
G02X1190255Y277809I48J1574D01*
G01X1191700Y277022D02*
X1191571D01*
G01X1193635Y275859D02*
G03X1191700Y277022I-2016J-1163D01*
G01X1194925Y275073D02*
G02X1193635Y275859I74J1573D01*
G01X1195080Y275073D02*
X1194925D01*
G01X1197015Y273910D02*
G03X1195080Y275073I-2016J-1163D01*
G01X1199743Y273910D02*
G02X1197015I-1364J786D01*
G01X1201678Y275073D02*
G03X1199743Y273910I81J-2326D01*
G01X1201840Y275073D02*
X1201678D01*
G01X1203775Y273910D02*
G03X1201840Y275073I-2016J-1163D01*
G01X1206503Y273910D02*
G02X1203775I-1364J786D01*
G01X1206873Y274393D02*
G03X1206503Y273910I1647J-1645D01*
G01X1208785Y275204D02*
G03X1206873Y274393I47J-2770D01*
G01X1210698Y277117D02*
X1208785Y275204D01*
G01X1212508Y277117D02*
X1210698D01*
G01X1217036Y281645D02*
X1212508Y277117D01*
G01X1157377Y272747D02*
X1161200D01*
G01X1215776Y259473D02*
X1221930Y265627D01*
G01X1208438Y259473D02*
X1215776D01*
G01X1206503Y258310D02*
G02X1208438Y259473I2016J-1163D01*
G01X1203775Y258310D02*
G03X1206503I1364J786D01*
G01X1201840Y259473D02*
G02X1203775Y258310I-81J-2326D01*
G01X1201711Y259473D02*
X1201840D01*
G01X1200395Y260260D02*
G03X1201711Y259473I1364J787D01*
G01X1196363Y260260D02*
G02X1200395I2016J-1164D01*
G01X1193635D02*
G03X1196363I1364J787D01*
G01X1189603D02*
G02X1193635I2016J-1164D01*
G01X1186875D02*
G03X1189603I1364J787D01*
G01X1184954Y261422D02*
G02X1186875Y260260I-95J-2326D01*
G01X1184831Y261422D02*
X1184954D01*
G01X1183495Y262210D02*
G03X1184831Y261422I1364J786D01*
G01X1179463Y262210D02*
G02X1183495I2016J-1163D01*
G01X1178692Y261538D02*
G03X1179463Y262210I-593J1458D01*
G01X1177516Y261538D02*
G03X1178692I588J1446D01*
G01X1176000Y262519D02*
G03X1177516Y261538I3335J3491D01*
G01X1174784Y262997D02*
G02X1176000Y262519I-65J-1950D01*
G01X1174717Y262997D02*
X1174784D01*
G01X1173029Y262022D02*
G02X1174717Y262997I1688J-974D01*
G01X1173029Y260072D02*
G02Y262022I1690J975D01*
G01X1173061Y258177D02*
G03X1173029Y260072I-1722J919D01*
G01X1171339Y255196D02*
X1173061Y258177D01*
G01X1208519Y229847D02*
X1228499D01*
G01X1168337Y264570D02*
X1167960Y264947D01*
G01X1171342Y264570D02*
X1168337D01*
G01X1173355Y265733D02*
G02X1171342Y264570I-2013J1161D01*
G01X1174691Y266521D02*
G03X1173355Y265733I28J-1574D01*
G01X1174829Y266521D02*
X1174691D01*
G01X1174946Y266504D02*
X1174829Y266521D01*
G01X1176083Y265733D02*
G03X1174946Y266504I-1363J-787D01*
G01X1180115Y265733D02*
G02X1176083I-2016J1163D01*
G01X1182843Y265734D02*
G03X1180115Y265733I-1364J-787D01*
G01X1184794Y264571D02*
G02X1182843Y265734I65J2327D01*
G01X1184924Y264571D02*
X1184794D01*
G01X1186875Y265734D02*
G02X1184924Y264571I-2016J1164D01*
G01X1189603Y265733D02*
G03X1186875Y265734I-1364J-786D01*
G01X1191538Y264570D02*
G02X1189603Y265733I81J2326D01*
G01X1191667Y264570D02*
X1191538D01*
G01X1192983Y263783D02*
G03X1191667Y264570I-1364J-787D01*
G01X1194904Y262621D02*
G02X1192983Y263783I95J2326D01*
G01X1195094Y262621D02*
X1194904D01*
G01X1197015Y263783D02*
G02X1195094Y262621I-2016J1164D01*
G01X1197265Y264110D02*
G03X1197015Y263783I1115J-1112D01*
G01X1197726Y264571D02*
X1197265Y264110D01*
G01X1198379Y264571D02*
X1197726D01*
G01X1199730Y263806D02*
G03X1198379Y264571I-1351J-810D01*
G01X1199743Y263783D02*
X1199730Y263806D01*
G01X1201664Y262621D02*
G02X1199743Y263783I95J2326D01*
G01X1201787Y262621D02*
X1201664D01*
G01X1203123Y261833D02*
G03X1201787Y262621I-1364J-786D01*
G01X1205058Y260670D02*
G02X1203123Y261833I81J2326D01*
G01X1206532Y260670D02*
X1205058D01*
G01X1207272Y261410D02*
X1206532Y260670D01*
G01X1215886Y261410D02*
X1207272D01*
G01X1221791Y267315D02*
X1215886Y261410D01*
G01X1207774Y221671D02*
X1205139D01*
G01X1197395Y301491D02*
X1197264Y301622D01*
G01X1199128Y301491D02*
X1197395D01*
G01X1202785Y301490D02*
X1199664D01*
G01X1203637Y302342D02*
X1202785Y301490D01*
G01X1212958Y302342D02*
X1203637D01*
G01X1215715Y299585D02*
X1212958Y302342D01*
G01X1298672Y299585D02*
X1215715D01*
G01X1216753Y295366D02*
X1303421D01*
G01X1212110Y300009D02*
X1216753Y295366D01*
G01X1204702Y300009D02*
X1212110D01*
G01X1202414Y297721D02*
X1204702Y300009D01*
G01X1194971Y297721D02*
X1202414D01*
G01X1193635Y296933D02*
G02X1194971Y297721I1364J-786D01*
G01X1189603Y296933D02*
G03X1193635I2016J1163D01*
G01X1186875D02*
G02X1189603I1364J-786D01*
G01X1182843D02*
G03X1186875I2016J1163D01*
G01X1180115D02*
G02X1182843I1364J-786D01*
G01X1176083D02*
G03X1180115I2016J1163D01*
G01X1173355D02*
G02X1176083I1364J-786D01*
G01X1171420Y295770D02*
G03X1173355Y296933I-81J2326D01*
G01X1171339Y295770D02*
X1171420D01*
G01X1169985Y294998D02*
G02X1171339Y295770I1354J-801D01*
G01X1169976Y294983D02*
X1169985Y294998D01*
G01X1168055Y293821D02*
G03X1169976Y294983I-95J2326D01*
G01X1167932Y293821D02*
X1168055D01*
G01X1166596Y293033D02*
G02X1167932Y293821I1364J-786D01*
G01X1162564Y293033D02*
G03X1166596I2016J1163D01*
G01X1159836D02*
G02X1162564I1364J-786D01*
G01X1159331Y281564D02*
G02X1157551Y280944I-1490J1414D01*
G01X1159913Y282146D02*
X1159331Y281564D01*
G01X1163216Y281710D02*
G03X1159913Y282146I-1819J-1048D01*
G01X1165944Y281710D02*
G02X1163216I-1364J786D01*
G01X1167306Y282497D02*
G03X1165944Y281710I0J-1572D01*
G01X1168025Y282497D02*
X1167306D01*
G01X1169650Y283472D02*
G02X1168025Y282497I-1690J975D01*
G01X1171337Y284446D02*
G03X1169650Y283472I0J-1948D01*
G01X1171387Y284446D02*
X1171337D01*
G01X1173029Y285422D02*
G02X1171387Y284446I-1690J974D01*
G01X1174654Y286397D02*
G03X1173029Y285422I65J-1950D01*
G01X1174784Y286397D02*
X1174654D01*
G01X1176409Y285422D02*
G03X1174784Y286397I-1690J-975D01*
G01X1179789Y285422D02*
G02X1176409I-1690J974D01*
G01X1181477Y286397D02*
G03X1179789Y285422I0J-1949D01*
G01X1181544Y286397D02*
X1181477D01*
G01X1183169Y285422D02*
G03X1181544Y286397I-1690J-975D01*
G01X1186549Y285422D02*
G02X1183169I-1690J974D01*
G01X1188174Y286397D02*
G03X1186549Y285422I65J-1950D01*
G01X1188304Y286397D02*
X1188174D01*
G01X1189929Y285422D02*
G03X1188304Y286397I-1690J-975D01*
G01X1191571Y284446D02*
G02X1189929Y285422I48J1950D01*
G01X1191698Y284446D02*
X1191571D01*
G01X1193309Y283472D02*
G03X1191698Y284446I-1690J-976D01*
G01X1194934Y282497D02*
G02X1193309Y283472I65J1950D01*
G01X1195064Y282497D02*
X1194934D01*
G01X1196689Y281522D02*
G03X1195064Y282497I-1690J-975D01*
G01X1200069Y281522D02*
G02X1196689I-1690J974D01*
G01X1201694Y282497D02*
G03X1200069Y281522I65J-1950D01*
G01X1201824Y282497D02*
X1201694D01*
G01X1203449Y281522D02*
G03X1201824Y282497I-1690J-975D01*
G01X1205091Y280546D02*
G02X1203449Y281522I48J1950D01*
G01X1205869Y280546D02*
X1205091D01*
G01X1206979Y281522D02*
G02X1205869Y280546I-1840J974D01*
G01X1208088Y282497D02*
G03X1206979Y281522I731J-1950D01*
G01X1212481Y282497D02*
X1208088D01*
G01X1215334Y285350D02*
X1212481Y282497D01*
G01X1308552Y285350D02*
X1215334D01*
G01X1202468Y302520D02*
X1199586D01*
G01X1203242Y303294D02*
X1202468Y302520D01*
G01X1213473Y303294D02*
X1203242D01*
G01X1216230Y300537D02*
X1213473Y303294D01*
G01X1298974Y300537D02*
X1216230D01*
G01X1164499Y280170D02*
G02X1164133Y280212I82J2326D01*
G01X1165259Y280270D02*
G02X1164499Y280170I-678J2217D01*
G01X1166596Y279760D02*
G03X1165259Y280270I-982J-567D01*
G01X1169323Y279760D02*
X1169314Y279745D01*
G01X1171244Y280922D02*
G03X1169323Y279760I95J-2326D01*
G01X1171367Y280922D02*
X1171244D01*
G01X1172703Y281710D02*
G02X1171367Y280922I-1364J786D01*
G01X1176735Y281710D02*
G03X1172703I-2016J-1163D01*
G01X1179463D02*
G02X1176735I-1364J786D01*
G01X1183495D02*
G03X1179463I-2016J-1163D01*
G01X1186223D02*
G02X1183495I-1364J786D01*
G01X1190255D02*
G03X1186223I-2016J-1163D01*
G01X1191591Y280922D02*
G02X1190255Y281710I28J1574D01*
G01X1191714Y280922D02*
X1191591D01*
G01X1193635Y279760D02*
G03X1191714Y280922I-2016J-1164D01*
G01X1306816Y284144D02*
X1216103D01*
G01X1215986Y287801D02*
X1214033Y289754D01*
G01X1311785Y287801D02*
X1215986D01*
G01X1218485Y316049D02*
X1222787Y311747D01*
G01X1198441Y316049D02*
X1218485D01*
G01X1196733Y315342D02*
G02X1198441Y316049I1708J-1708D01*
G01X1196363Y314860D02*
G02X1196733Y315342I2016J-1164D01*
G01X1193635Y314860D02*
G03X1196363I1364J787D01*
G01X1191714Y316022D02*
G02X1193635Y314860I-95J-2326D01*
G01X1191591Y316022D02*
X1191714D01*
G01X1190255Y316810D02*
G03X1191591Y316022I1364J786D01*
G01X1186223Y316810D02*
G02X1190255I2016J-1163D01*
G01X1183495D02*
G03X1186223I1364J786D01*
G01X1179463D02*
G02X1183495I2016J-1163D01*
G01X1176735D02*
G03X1179463I1364J786D01*
G01X1172703D02*
G02X1176735I2016J-1163D01*
G01X1169997Y316773D02*
G03X1172703Y316810I1342J823D01*
G01X1165944D02*
G02X1169997Y316773I2016J-1163D01*
G01X1164608Y316022D02*
G03X1165944Y316810I-28J1574D01*
G01X1164485Y316022D02*
X1164608D01*
G01X1162564Y314860D02*
G02X1164485Y316022I2016J-1164D01*
G01X1159836Y314860D02*
G03X1162564I1364J787D01*
G01X1157901Y319170D02*
X1157772D01*
G01X1159836Y320333D02*
G02X1157901Y319170I-2016J1163D01*
G01X1161138Y321120D02*
G03X1159836Y320333I62J-1573D01*
G01X1161262Y321120D02*
X1161138D01*
G01X1162564Y320333D02*
G03X1161262Y321120I-1364J-786D01*
G01X1166596Y320333D02*
G02X1162564I-2016J1163D01*
G01X1169323D02*
G03X1166596I-1364J-786D01*
G01X1173355D02*
G02X1169323I-2016J1163D01*
G01X1174657Y321120D02*
G03X1173355Y320333I62J-1573D01*
G01X1174800Y321120D02*
X1174657D01*
G01X1176735Y322283D02*
G02X1174800Y321120I-2016J1163D01*
G01X1178051Y323070D02*
G03X1176735Y322283I48J-1574D01*
G01X1178147Y323070D02*
X1178051D01*
G01X1179463Y322283D02*
G03X1178147Y323070I-1364J-787D01*
G01X1181398Y321120D02*
G02X1179463Y322283I81J2326D01*
G01X1181560Y321120D02*
X1181398D01*
G01X1183495Y322283D02*
G02X1181560Y321120I-2016J1163D01*
G01X1184811Y323070D02*
G03X1183495Y322283I48J-1574D01*
G01X1184907Y323070D02*
X1184811D01*
G01X1186223Y322283D02*
G03X1184907Y323070I-1364J-787D01*
G01X1188158Y321120D02*
G02X1186223Y322283I81J2326D01*
G01X1188301Y321120D02*
X1188158D01*
G01X1189603Y320333D02*
G03X1188301Y321120I-1364J-786D01*
G01X1191538Y319170D02*
G02X1189603Y320333I81J2326D01*
G01X1191667Y319170D02*
X1191538D01*
G01X1192983Y318383D02*
G03X1191667Y319170I-1364J-787D01*
G01X1194904Y317221D02*
G02X1192983Y318383I95J2326D01*
G01X1195649Y317221D02*
X1194904D01*
G01X1196060Y316810D02*
X1195649Y317221D01*
G01X1220414Y316810D02*
X1196060D01*
G01X1163216Y314483D02*
G02X1159184I-2016J1164D01*
G01X1164532Y315270D02*
G03X1163216Y314483I48J-1574D01*
G01X1164661Y315270D02*
X1164532D01*
G01X1166596Y316433D02*
G02X1164661Y315270I-2016J1163D01*
G01X1169302Y316470D02*
G03X1166596Y316433I-1342J-823D01*
G01X1169323D02*
X1169302Y316470D01*
G01X1173355Y316433D02*
G02X1169323I-2016J1163D01*
G01X1176083D02*
G03X1173355I-1364J-786D01*
G01X1180115D02*
G02X1176083I-2016J1163D01*
G01X1182843D02*
G03X1180115I-1364J-786D01*
G01X1186875D02*
G02X1182843I-2016J1163D01*
G01X1189603D02*
G03X1186875I-1364J-786D01*
G01X1191538Y315270D02*
G02X1189603Y316433I81J2326D01*
G01X1191667Y315270D02*
X1191538D01*
G01X1192983Y314483D02*
G03X1191667Y315270I-1364J-787D01*
G01X1197015Y314483D02*
G02X1192983I-2016J1164D01*
G01X1197265Y314810D02*
G03X1197015Y314483I1115J-1112D01*
G01X1198419Y315288D02*
G03X1197265Y314810I0J-1632D01*
G01X1217347Y315288D02*
X1198419D01*
G01X1222378Y310257D02*
X1217347Y315288D01*
G01X1162564Y289133D02*
G03X1159836I-1364J-786D01*
G01X1166596D02*
G02X1162564I-2016J1163D01*
G01X1167932Y289921D02*
G03X1166596Y289133I28J-1574D01*
G01X1168055Y289921D02*
X1167932D01*
G01X1169976Y291083D02*
G02X1168055Y289921I-2016J1164D01*
G01X1169985Y291098D02*
X1169976Y291083D01*
G01X1171339Y291870D02*
G03X1169985Y291098I0J-1573D01*
G01X1171420Y291870D02*
X1171339D01*
G01X1173355Y293033D02*
G02X1171420Y291870I-2016J1163D01*
G01X1176083Y293033D02*
G03X1173355I-1364J-786D01*
G01X1180115D02*
G02X1176083I-2016J1163D01*
G01X1182843D02*
G03X1180115I-1364J-786D01*
G01X1186875D02*
G02X1182843I-2016J1163D01*
G01X1189603D02*
G03X1186875I-1364J-786D01*
G01X1193635D02*
G02X1189603I-2016J1163D01*
G01X1196363D02*
G03X1193635I-1364J-786D01*
G01X1200395D02*
G02X1196363I-2016J1163D01*
G01X1201731Y293821D02*
G03X1200395Y293033I28J-1574D01*
G01X1201840Y293821D02*
X1201731D01*
G01X1203775Y294984D02*
G02X1201840Y293821I-2016J1163D01*
G01X1205111Y295772D02*
G03X1203775Y294984I28J-1574D01*
G01X1212242Y295772D02*
X1205111D01*
G01X1215669Y292345D02*
X1212242Y295772D01*
G01X1303866Y292345D02*
X1215669D01*
G01X1163216Y289510D02*
G03X1159184I-2016J-1163D01*
G01X1165944D02*
G02X1163216I-1364J786D01*
G01X1167879Y290673D02*
G03X1165944Y289510I81J-2326D01*
G01X1167960Y290673D02*
X1167879D01*
G01X1169314Y291445D02*
G02X1167960Y290673I-1354J801D01*
G01X1169323Y291460D02*
X1169314Y291445D01*
G01X1171244Y292622D02*
G03X1169323Y291460I95J-2326D01*
G01X1171367Y292622D02*
X1171244D01*
G01X1172703Y293410D02*
G02X1171367Y292622I-1364J786D01*
G01X1176735Y293410D02*
G03X1172703I-2016J-1163D01*
G01X1179463D02*
G02X1176735I-1364J786D01*
G01X1183495D02*
G03X1179463I-2016J-1163D01*
G01X1186223D02*
G02X1183495I-1364J786D01*
G01X1190255D02*
G03X1186223I-2016J-1163D01*
G01X1192983D02*
G02X1190255I-1364J786D01*
G01X1197015D02*
G03X1192983I-2016J-1163D01*
G01X1199743D02*
G02X1197015I-1364J786D01*
G01X1201678Y294573D02*
G03X1199743Y293410I81J-2326D01*
G01X1201787Y294573D02*
X1201678D01*
G01X1203123Y295361D02*
G02X1201787Y294573I-1364J786D01*
G01X1205058Y296524D02*
G03X1203123Y295361I81J-2326D01*
G01X1213580Y296524D02*
X1205058D01*
G01X1215990Y294114D02*
X1213580Y296524D01*
G01X1303940Y294114D02*
X1215990D01*
G01X1216378Y288753D02*
X1214344Y290787D01*
G01X1311390Y288753D02*
X1216378D01*
G01X1300059Y304405D02*
X1215172D01*
G01X1163216Y293410D02*
G03X1159184I-2016J-1163D01*
G01X1165944D02*
G02X1163216I-1364J786D01*
G01X1167879Y294573D02*
G03X1165944Y293410I81J-2326D01*
G01X1167960Y294573D02*
X1167879D01*
G01X1169314Y295345D02*
G02X1167960Y294573I-1354J801D01*
G01X1169323Y295360D02*
X1169314Y295345D01*
G01X1171244Y296522D02*
G03X1169323Y295360I95J-2326D01*
G01X1171367Y296522D02*
X1171244D01*
G01X1172703Y297310D02*
G02X1171367Y296522I-1364J786D01*
G01X1176735Y297310D02*
G03X1172703I-2016J-1163D01*
G01X1179463D02*
G02X1176735I-1364J786D01*
G01X1183495D02*
G03X1179463I-2016J-1163D01*
G01X1186223D02*
G02X1183495I-1364J786D01*
G01X1190255D02*
G03X1186223I-2016J-1163D01*
G01X1192983D02*
G02X1190255I-1364J786D01*
G01X1195003Y298477D02*
G03X1192983Y297310I0J-2333D01*
G01X1201985Y298477D02*
X1195003D01*
G01X1204414Y300906D02*
X1201985Y298477D01*
G01X1212726Y300906D02*
X1204414D01*
G01X1215401Y298231D02*
X1212726Y300906D01*
G01X1290459Y298231D02*
X1215401D01*
G01X1196472Y317600D02*
X1221412D01*
G01X1196099Y317973D02*
X1196472Y317600D01*
G01X1194951Y317973D02*
X1196099D01*
G01X1193635Y318760D02*
G03X1194951Y317973I1364J787D01*
G01X1191714Y319922D02*
G02X1193635Y318760I-95J-2326D01*
G01X1191591Y319922D02*
X1191714D01*
G01X1190255Y320710D02*
G03X1191591Y319922I1364J786D01*
G01X1188320Y321873D02*
G02X1190255Y320710I-81J-2326D01*
G01X1188165Y321873D02*
X1188320D01*
G01X1186875Y322659D02*
G03X1188165Y321873I1364J787D01*
G01X1184940Y323822D02*
G02X1186875Y322659I-81J-2326D01*
G01X1184778Y323822D02*
X1184940D01*
G01X1182843Y322659D02*
G02X1184778Y323822I2016J-1163D01*
G01X1181553Y321873D02*
G03X1182843Y322659I-74J1573D01*
G01X1181405Y321873D02*
X1181553D01*
G01X1180115Y322659D02*
G03X1181405Y321873I1364J787D01*
G01X1178180Y323822D02*
G02X1180115Y322659I-81J-2326D01*
G01X1178018Y323822D02*
X1178180D01*
G01X1176083Y322659D02*
G02X1178018Y323822I2016J-1163D01*
G01X1174793Y321873D02*
G03X1176083Y322659I-74J1573D01*
G01X1174638Y321873D02*
X1174793D01*
G01X1172703Y320710D02*
G02X1174638Y321873I2016J-1163D01*
G01X1169997Y320673D02*
G03X1172703Y320710I1342J823D01*
G01X1169976D02*
X1169997Y320673D01*
G01X1168041Y321873D02*
G02X1169976Y320710I-81J-2326D01*
G01X1167879Y321873D02*
X1168041D01*
G01X1165944Y320710D02*
G02X1167879Y321873I2016J-1163D01*
G01X1163216Y320710D02*
G03X1165944I1364J786D01*
G01X1161281Y321873D02*
G02X1163216Y320710I-81J-2326D01*
G01X1161119Y321873D02*
X1161281D01*
G01X1159184Y320710D02*
G02X1161119Y321873I2016J-1163D01*
G01X1157848Y319922D02*
G03X1159184Y320710I-28J1574D01*
G01X1157725Y319922D02*
X1157848D01*
G01X1216650Y283100D02*
X1306583D01*
G01X1191538Y280170D02*
X1191667D01*
G01X1189603Y281333D02*
G03X1191538Y280170I2016J1163D01*
G01X1186875Y281333D02*
G02X1189603I1364J-786D01*
G01X1182843D02*
G03X1186875I2016J1163D01*
G01X1180115D02*
G02X1182843I1364J-786D01*
G01X1176083D02*
G03X1180115I2016J1163D01*
G01X1173355D02*
G02X1176083I1364J-786D01*
G01X1171420Y280170D02*
G03X1173355Y281333I-81J2326D01*
G01X1171339Y280170D02*
X1171420D01*
G01X1306146Y281645D02*
X1217036D01*
G01X1213842Y304184D02*
X1200602D01*
G01X1214773Y303253D02*
X1213842Y304184D01*
G01X1300133Y303253D02*
X1214773D01*
G01X1159648Y398189D02*
G02X1158066Y397230I-1439J589D01*
G01X1160843Y399196D02*
G03X1159648Y398189I364J-1645D01*
G01X1161848Y399419D02*
X1160843Y399196D01*
G01X1162565Y400660D02*
X1161848Y399419D01*
G01X1164482Y401821D02*
G03X1162565Y400660I98J-2325D01*
G01X1164624Y401821D02*
X1164482D01*
G01X1165945Y402609D02*
G02X1164624Y401821I-1365J787D01*
G01X1166270Y403174D02*
X1165945Y402609D01*
G01X1158553Y400690D02*
X1157580Y399717D01*
G01X1158553Y402244D02*
Y400690D01*
G01X1165362Y409053D02*
X1158553Y402244D01*
G01X1157848Y390122D02*
X1157725D01*
G01X1159184Y392483D02*
G02X1157848Y390122I-1364J-787D01*
G01X1159132Y394715D02*
G03X1159184Y392483I2068J-1068D01*
G01X1160817Y395630D02*
G03X1159132Y394715I-169J-1698D01*
G01X1162564Y396760D02*
G02X1160817Y395630I-1582J530D01*
G01X1162830Y397221D02*
X1162564Y396760D01*
G01X1162830Y399600D02*
Y397221D01*
G01X1163229Y400306D02*
X1162830Y399600D01*
G01X1164580Y401071D02*
G03X1163229Y400306I0J-1575D01*
G01X1164650Y401071D02*
X1164580D01*
G01X1166595Y402234D02*
G02X1164650Y401071I-2015J1162D01*
G01X1167916Y403022D02*
G03X1166595Y402234I44J-1575D01*
G01X1159447Y401925D02*
X1165769Y408247D01*
G01X1159447Y400498D02*
Y401925D01*
G01X1157908Y398959D02*
X1159447Y400498D01*
G01X1166270Y404371D02*
G02Y403174I-1037J-598D01*
G01Y406270D02*
Y404371D01*
G01X1167000Y407000D02*
X1166270Y406270D01*
G01X1172676Y407000D02*
X1167000D01*
G01X1187797Y422121D02*
X1172676Y407000D01*
G01X1191362Y422121D02*
X1187797D01*
G01X1249694Y480453D02*
X1191362Y422121D01*
G01X1172035Y409053D02*
X1165362D01*
G01X1187007Y424025D02*
X1172035Y409053D01*
G01X1190572Y424025D02*
X1187007D01*
G01X1253690Y487143D02*
X1190572Y424025D01*
G01X1164910Y409826D02*
X1158178Y403094D01*
G01X1171461Y409826D02*
X1164910D01*
G01X1186612Y424977D02*
X1171461Y409826D01*
G01X1190177Y424977D02*
X1186612D01*
G01X1252660Y487460D02*
X1190177Y424977D01*
G01X1167960Y403022D02*
X1167916D01*
G01X1167960Y403021D02*
Y403022D01*
G01X1168055Y403021D02*
X1167960D01*
G01X1169976Y404183D02*
G02X1168055Y403021I-2016J1164D01*
G01X1169976Y404523D02*
Y404183D01*
G01X1170557Y405104D02*
X1169976Y404523D01*
G01X1172127Y405104D02*
X1170557D01*
G01X1188192Y421169D02*
X1172127Y405104D01*
G01X1191757Y421169D02*
X1188192D01*
G01X1250089Y479501D02*
X1191757Y421169D01*
G01X1190967Y423073D02*
X1249299Y481405D01*
G01X1187402Y423073D02*
X1190967D01*
G01X1172576Y408247D02*
X1187402Y423073D01*
G01X1165769Y408247D02*
X1172576D01*
G01X1266733Y-10554D02*
X1263913Y-13374D01*
G01X1266733Y12262D02*
Y-10554D01*
G01X1263544Y15451D02*
X1266733Y12262D01*
G01X1263544Y58484D02*
Y15451D01*
G01X1272347Y-11868D02*
X1267833Y-16382D01*
G01X1276957Y-11868D02*
X1272347D01*
G01X1277922Y-10903D02*
X1276957Y-11868D01*
G01X1277922Y-9597D02*
Y-10903D01*
G01X1277900Y-9575D02*
X1277922Y-9597D01*
G01X1277900Y36294D02*
Y-9575D01*
G01X1272128Y-8917D02*
Y93200D01*
G01X1266167Y-14878D02*
X1272128Y-8917D01*
G01X1260185Y13976D02*
Y57755D01*
G01X1263516Y10645D02*
X1260185Y13976D01*
G01X1263516Y-10425D02*
Y10645D01*
G01X1261319Y-12622D02*
X1263516Y-10425D01*
G01X1255118Y13882D02*
Y16999D01*
G01X1256800Y12200D02*
X1255118Y13882D01*
G01X1256800Y-8219D02*
Y12200D01*
G01X1255118Y-9901D02*
X1256800Y-8219D01*
G01X1279722Y8041D02*
Y35987D01*
G01X1280025Y7738D02*
X1279722Y8041D01*
G01X1280025Y-10825D02*
Y7738D01*
G01X1280676Y-11476D02*
X1280025Y-10825D01*
G01X1278326Y-17886D02*
X1280676Y-15536D01*
G01X1272144Y-13135D02*
X1268145Y-17134D01*
G01X1276754Y-13135D02*
X1272144D01*
G01X1279160Y-10729D02*
X1276754Y-13135D01*
G01X1279160Y7539D02*
Y-10729D01*
G01X1278970Y7729D02*
X1279160Y7539D01*
G01X1278970Y17362D02*
Y7729D01*
G01X1278968Y17364D02*
X1278970Y17362D01*
G01X1278968Y18608D02*
Y17364D01*
G01X1278970Y18610D02*
X1278968Y18608D01*
G01X1278970Y36299D02*
Y18610D01*
G01X1271376Y-8605D02*
Y92888D01*
G01X1265855Y-14126D02*
X1271376Y-8605D01*
G01X1274432Y-8336D02*
X1276346Y-10250D01*
G01X1274432Y98199D02*
Y-8336D01*
G01X1273280Y-9449D02*
X1267099Y-15630D01*
G01X1273280Y97721D02*
Y-9449D01*
G01X1255118Y-1743D02*
Y9157D01*
G01X1270230Y65170D02*
X1263544Y58484D01*
G01X1270230Y86504D02*
Y65170D01*
G01X1266733Y90001D02*
X1270230Y86504D01*
G01X1266733Y96467D02*
Y90001D01*
G01X1284528Y42922D02*
X1277900Y36294D01*
G01X1277121Y65519D02*
X1283586Y59054D01*
G01X1277121Y96985D02*
Y65519D01*
G01X1272128Y93200D02*
X1266172Y99156D01*
G01X1263516Y61086D02*
Y107188D01*
G01X1260185Y57755D02*
X1263516Y61086D01*
G01X1279825Y66641D02*
Y96429D01*
G01X1285108Y61358D02*
X1279825Y66641D01*
G01X1279722Y35987D02*
X1284435Y40700D01*
G01X1284430Y41759D02*
X1278970Y36299D01*
G01X1278273Y65997D02*
X1284064Y60206D01*
G01X1278273Y96507D02*
Y65997D01*
G01X1271376Y92888D02*
X1265420Y98844D01*
G01X1276369Y65207D02*
Y97297D01*
G01X1283462Y58114D02*
X1276369Y65207D01*
G01X1264668Y98532D02*
X1266733Y96467D01*
G01X1264668Y106710D02*
Y98532D01*
G01X1266878Y108920D02*
X1264668Y106710D01*
G01X1266878Y115635D02*
Y108920D01*
G01X1261563Y120950D02*
X1266878Y115635D01*
G01X1261563Y125315D02*
Y120950D01*
G01X1249915Y136963D02*
X1261563Y125315D01*
G01X1248176Y136963D02*
X1249915D01*
G01X1245764Y139375D02*
X1248176Y136963D01*
G01X1245764Y169775D02*
Y139375D01*
G01X1268921Y150540D02*
X1266646D01*
G01X1284081Y165700D02*
X1268921Y150540D01*
G01X1264271Y142125D02*
X1265828Y140568D01*
G01X1260246Y142125D02*
X1264271D01*
G01X1258374Y143997D02*
X1260246Y142125D01*
G01X1258374Y158526D02*
Y143997D01*
G01X1288552Y108416D02*
X1277121Y96985D01*
G01X1248021Y140310D02*
Y168840D01*
G01X1249111Y139220D02*
X1248021Y140310D01*
G01X1251180Y139220D02*
X1249111D01*
G01X1263819Y126581D02*
X1251180Y139220D01*
G01X1263819Y122030D02*
Y126581D01*
G01X1265676Y120173D02*
X1263819Y122030D01*
G01X1268842Y120173D02*
X1265676D01*
G01X1270655Y118360D02*
X1268842Y120173D01*
G01X1270655Y110569D02*
Y118360D01*
G01X1266172Y106086D02*
X1270655Y110569D01*
G01X1266172Y99156D02*
Y106086D01*
G01X1238237Y150173D02*
X1233910D01*
G01X1241902Y146508D02*
X1238237Y150173D01*
G01X1241902Y142173D02*
Y146508D01*
G01X1248209Y135866D02*
X1241902Y142173D01*
G01X1249948Y135866D02*
X1248209D01*
G01X1260811Y125003D02*
X1249948Y135866D01*
G01X1260811Y120638D02*
Y125003D01*
G01X1266126Y115323D02*
X1260811Y120638D01*
G01X1266126Y109798D02*
Y115323D01*
G01X1263516Y107188D02*
X1266126Y109798D01*
G01X1252000Y168900D02*
Y145300D01*
G01X1250000Y144912D02*
Y168571D01*
G01X1255354Y139558D02*
X1250000Y144912D01*
G01X1255354Y136630D02*
Y139558D01*
G01X1263774Y128210D02*
X1255354Y136630D01*
G01X1270956Y128210D02*
X1263774D01*
G01X1274074Y125092D02*
X1270956Y128210D01*
G01X1274074Y112924D02*
Y125092D01*
G01X1266924Y105774D02*
X1274074Y112924D01*
G01X1266924Y99826D02*
Y105774D01*
G01X1268450Y98300D02*
X1266924Y99826D01*
G01X1270350Y98300D02*
X1268450D01*
G01X1279825Y96429D02*
X1290856Y107460D01*
G01X1289704Y107938D02*
X1278273Y96507D01*
G01X1277600Y106200D02*
X1280885Y109485D01*
G01X1246517Y140934D02*
Y169464D01*
G01X1246516Y140933D02*
X1246517Y140934D01*
G01X1246516Y139687D02*
Y140933D01*
G01X1248488Y137715D02*
X1246516Y139687D01*
G01X1249110Y137715D02*
X1248488D01*
G01X1249111Y137716D02*
X1249110Y137715D01*
G01X1250556Y137716D02*
X1249111D01*
G01X1262315Y125957D02*
X1250556Y137716D01*
G01X1262315Y121262D02*
Y125957D01*
G01X1264909Y118668D02*
X1262315Y121262D01*
G01X1265475Y118668D02*
X1264909D01*
G01X1267000Y117143D02*
X1265475Y118668D01*
G01X1267000Y117135D02*
Y117143D01*
G01X1268030Y116105D02*
X1267000Y117135D01*
G01X1268030Y109632D02*
Y116105D01*
G01X1268031Y109631D02*
X1268030Y109632D01*
G01X1268031Y109009D02*
Y109631D01*
G01X1265420Y106398D02*
X1268031Y109009D01*
G01X1265420Y98844D02*
Y106398D01*
G01X1266944Y119420D02*
X1268576Y117788D01*
G01X1265221Y119420D02*
X1266944D01*
G01X1263067Y121574D02*
X1265221Y119420D01*
G01X1263067Y126269D02*
Y121574D01*
G01X1250868Y138468D02*
X1263067Y126269D01*
G01X1248799Y138468D02*
X1250868D01*
G01X1247268Y139999D02*
X1248799Y138468D01*
G01X1247268Y140621D02*
Y139999D01*
G01X1247269Y140622D02*
X1247268Y140621D01*
G01X1247269Y169152D02*
Y140622D01*
G01X1271490Y156078D02*
X1269810Y154398D01*
G01X1272704Y156078D02*
X1271490D01*
G01X1283290Y166664D02*
X1272704Y156078D01*
G01X1275470Y109489D02*
Y99390D01*
G01X1280133Y114152D02*
X1275470Y109489D01*
G01X1280133Y123267D02*
Y114152D01*
G01X1266043Y137357D02*
X1280133Y123267D01*
G01X1261822Y137357D02*
X1266043D01*
G01X1256118Y143061D02*
X1261822Y137357D01*
G01X1256118Y169506D02*
Y143061D01*
G01X1265992Y148738D02*
X1264146Y150584D01*
G01X1268183Y148738D02*
X1265992D01*
G01X1283945Y164500D02*
X1268183Y148738D01*
G01X1265353Y153224D02*
X1269183Y157054D01*
G01X1264186Y153224D02*
X1265353D01*
G01X1261546Y150584D02*
X1264186Y153224D01*
G01X1273894Y98737D02*
X1274432Y98199D01*
G01X1273894Y100043D02*
Y98737D01*
G01X1274228Y100377D02*
X1273894Y100043D01*
G01X1274228Y109311D02*
Y100377D01*
G01X1279381Y114464D02*
X1274228Y109311D01*
G01X1279381Y122955D02*
Y114464D01*
G01X1265731Y136605D02*
X1279381Y122955D01*
G01X1261510Y136605D02*
X1265731D01*
G01X1255366Y142749D02*
X1261510Y136605D01*
G01X1255366Y169818D02*
Y142749D01*
G01X1257622Y143685D02*
Y164543D01*
G01X1262344Y138963D02*
X1257622Y143685D01*
G01X1267492Y138963D02*
X1262344D01*
G01X1270001Y141472D02*
X1267492Y138963D01*
G01X1270001Y142778D02*
Y141472D01*
G01X1268429Y144350D02*
X1270001Y142778D01*
G01X1265420Y144350D02*
X1268429D01*
G01X1262569Y147201D02*
X1265420Y144350D01*
G01X1279576Y146964D02*
X1278030Y148510D01*
G01X1279576Y143273D02*
Y146964D01*
G01X1274514Y138211D02*
X1279576Y143273D01*
G01X1262032Y138211D02*
X1274514D01*
G01X1256870Y143373D02*
X1262032Y138211D01*
G01X1256870Y169194D02*
Y143373D01*
G01X1243511Y155353D02*
Y167483D01*
G01X1243948Y154916D02*
X1243511Y155353D01*
G01X1272742Y98259D02*
X1273280Y97721D01*
G01X1272742Y100521D02*
Y98259D01*
G01X1273076Y100855D02*
X1272742Y100521D01*
G01X1273076Y110089D02*
Y100855D01*
G01X1275524Y112537D02*
X1273076Y110089D01*
G01X1275524Y125182D02*
Y112537D01*
G01X1265253Y135453D02*
X1275524Y125182D01*
G01X1261032Y135453D02*
X1265253D01*
G01X1254214Y142271D02*
X1261032Y135453D01*
G01X1254214Y169917D02*
Y142271D01*
G01X1259950Y155352D02*
Y144650D01*
G01X1264481Y159883D02*
X1259950Y155352D01*
G01X1276369Y97297D02*
X1287800Y108728D01*
G01X1264700Y154800D02*
X1267917Y158017D01*
G01X1252246Y140383D02*
X1252437Y140192D01*
G01X1251657Y140383D02*
X1252246D01*
G01X1249154Y142886D02*
X1251657Y140383D01*
G01X1249154Y168909D02*
Y142886D01*
G01X1248486Y172497D02*
X1245764Y169775D01*
G01X1248486Y173803D02*
Y172497D01*
G01X1247470Y174819D02*
X1248486Y173803D01*
G01X1246002Y174819D02*
X1247470D01*
G01X1245079Y175742D02*
X1246002Y174819D01*
G01X1245079Y177048D02*
Y175742D01*
G01X1251306Y183275D02*
X1245079Y177048D01*
G01X1262619Y183275D02*
X1251306D01*
G01X1284695Y205351D02*
X1262619Y183275D01*
G01X1272591Y168296D02*
X1294395Y190100D01*
G01X1272520Y168296D02*
X1272591D01*
G01X1267800Y163576D02*
X1272520Y168296D01*
G01X1267800Y161800D02*
Y163576D01*
G01X1268896Y169048D02*
X1258374Y158526D01*
G01X1272279Y169048D02*
X1268896D01*
G01X1294611Y191380D02*
X1272279Y169048D01*
G01X1272544Y181017D02*
X1293470Y201943D01*
G01X1262931Y181017D02*
X1272544D01*
G01X1262930Y181018D02*
X1262931Y181017D01*
G01X1254525Y181018D02*
X1262930D01*
G01X1250472Y176965D02*
X1254525Y181018D01*
G01X1250472Y175009D02*
Y176965D01*
G01X1250742Y174739D02*
X1250472Y175009D01*
G01X1250742Y171561D02*
Y174739D01*
G01X1248021Y168840D02*
X1250742Y171561D01*
G01X1263321Y189181D02*
X1285067Y210927D01*
G01X1248868Y189181D02*
X1263321D01*
G01X1246035Y192014D02*
X1248868Y189181D01*
G01X1226146Y192014D02*
X1246035D01*
G01X1263007Y184727D02*
X1284383Y206103D01*
G01X1250098Y184727D02*
X1263007D01*
G01X1241224Y175853D02*
X1250098Y184727D01*
G01X1241224Y172197D02*
Y175853D01*
G01X1241381Y172040D02*
X1241224Y172197D01*
G01X1271967Y169800D02*
X1294300Y192133D01*
G01X1267050Y169800D02*
X1271967D01*
G01X1259998Y176898D02*
X1252000Y168900D01*
G01X1271617Y176898D02*
X1259998D01*
G01X1293717Y198998D02*
X1271617Y176898D01*
G01X1271305Y177650D02*
X1294094Y200439D01*
G01X1259079Y177650D02*
X1271305D01*
G01X1250000Y168571D02*
X1259079Y177650D01*
G01X1272157Y214452D02*
X1320200D01*
G01X1253690Y232919D02*
X1272157Y214452D01*
G01X1231276Y209870D02*
Y219148D01*
G01X1227707Y206301D02*
X1231276Y209870D01*
G01X1225228Y206301D02*
X1227707D01*
G01X1219855Y211674D02*
X1225228Y206301D01*
G01X1262930Y182522D02*
X1285007Y204599D01*
G01X1253901Y182522D02*
X1262930D01*
G01X1248968Y177589D02*
X1253901Y182522D01*
G01X1248968Y174385D02*
Y177589D01*
G01X1249238Y174115D02*
X1248968Y174385D01*
G01X1249238Y172185D02*
Y174115D01*
G01X1246517Y169464D02*
X1249238Y172185D01*
G01X1263300Y171502D02*
Y169450D01*
G01X1264184Y172386D02*
X1263300Y171502D01*
G01X1273489Y172386D02*
X1264184D01*
G01X1294388Y193285D02*
X1273489Y172386D01*
G01X1249990Y171873D02*
X1247269Y169152D01*
G01X1249990Y174427D02*
Y171873D01*
G01X1249720Y174697D02*
X1249990Y174427D01*
G01X1249720Y177277D02*
Y174697D01*
G01X1254213Y181770D02*
X1249720Y177277D01*
G01X1263242Y181770D02*
X1254213D01*
G01X1266744Y185272D02*
X1263242Y181770D01*
G01X1270409Y185272D02*
X1266744D01*
G01X1288984Y203847D02*
X1270409Y185272D01*
G01X1225063Y209708D02*
X1226867Y207904D01*
G01X1225063Y215651D02*
Y209708D01*
G01X1244235Y234823D02*
X1225063Y215651D01*
G01X1221153Y212987D02*
X1243919Y235753D01*
G01X1261254Y174642D02*
X1256118Y169506D01*
G01X1272553Y174642D02*
X1261254D01*
G01X1293853Y195942D02*
X1272553Y174642D01*
G01X1225243Y205149D02*
X1223546Y203452D01*
G01X1228230Y205149D02*
X1225243D01*
G01X1232428Y209347D02*
X1228230Y205149D01*
G01X1232428Y218353D02*
Y209347D01*
G01X1271727Y213252D02*
X1253212Y231767D01*
G01X1332089Y213252D02*
X1271727D01*
G01X1238653Y163556D02*
X1240309Y161900D01*
G01X1238653Y176542D02*
Y163556D01*
G01X1250140Y188029D02*
X1238653Y176542D01*
G01X1263799Y188029D02*
X1250140D01*
G01X1283377Y207607D02*
X1263799Y188029D01*
G01X1242051Y238057D02*
X1220702Y216708D01*
G01X1272226Y157230D02*
X1282812Y167816D01*
G01X1271012Y157230D02*
X1272226D01*
G01X1270836Y157054D02*
X1271012Y157230D01*
G01X1269183Y157054D02*
X1270836D01*
G01X1260942Y175394D02*
X1255366Y169818D01*
G01X1272241Y175394D02*
X1260942D01*
G01X1293541Y196694D02*
X1272241Y175394D01*
G01X1273177Y173138D02*
X1294476Y194437D01*
G01X1263872Y173138D02*
X1273177D01*
G01X1260776Y170042D02*
X1263872Y173138D01*
G01X1260776Y167697D02*
Y170042D01*
G01X1257622Y164543D02*
X1260776Y167697D01*
G01X1227200Y216702D02*
X1244569Y234071D01*
G01X1227200Y215543D02*
Y216702D01*
G01X1261566Y173890D02*
X1256870Y169194D01*
G01X1272865Y173890D02*
X1261566D01*
G01X1294164Y195189D02*
X1272865Y173890D01*
G01X1263193Y185977D02*
X1284071Y206855D01*
G01X1249718Y185977D02*
X1263193D01*
G01X1239805Y176064D02*
X1249718Y185977D01*
G01X1239805Y171189D02*
Y176064D01*
G01X1243511Y167483D02*
X1239805Y171189D01*
G01X1260443Y176146D02*
X1254214Y169917D01*
G01X1271929Y176146D02*
X1260443D01*
G01X1293629Y197846D02*
X1271929Y176146D01*
G01X1268112Y159883D02*
X1264481D01*
G01X1269824Y161595D02*
X1268112Y159883D01*
G01X1269824Y163754D02*
Y161595D01*
G01X1294874Y188804D02*
X1269824Y163754D01*
G01X1273500Y163700D02*
X1295100Y185300D01*
G01X1273500Y161401D02*
Y163700D01*
G01X1270116Y158017D02*
X1273500Y161401D01*
G01X1267917Y158017D02*
X1270116D01*
G01X1225721Y203997D02*
X1224024Y202300D01*
G01X1228708Y203997D02*
X1225721D01*
G01X1233580Y208869D02*
X1228708Y203997D01*
G01X1233580Y217875D02*
Y208869D01*
G01X1246005Y230300D02*
X1233580Y217875D01*
G01X1271249Y212100D02*
X1253049Y230300D01*
G01X1332567Y212100D02*
X1271249D01*
G01X1271400Y163524D02*
X1295128Y187252D01*
G01X1271400Y161900D02*
Y163524D01*
G01X1251494Y171249D02*
X1249154Y168909D01*
G01X1251494Y175051D02*
Y171249D01*
G01X1251224Y175321D02*
X1251494Y175051D01*
G01X1251224Y176653D02*
Y175321D01*
G01X1254836Y180265D02*
X1251224Y176653D01*
G01X1272856Y180265D02*
X1254836D01*
G01X1293782Y201191D02*
X1272856Y180265D01*
G01X1221405Y214869D02*
X1218868D01*
G01X1243441Y236905D02*
X1221405Y214869D01*
G01X1223265Y270300D02*
X1305457D01*
G01X1279917Y234270D02*
X1276628D01*
G01X1283375Y230812D02*
X1279917Y234270D01*
G01X1257659Y244960D02*
X1236390D01*
G01X1268349Y234270D02*
X1257659Y244960D01*
G01X1276628Y234270D02*
X1268349D01*
G01X1271010Y253123D02*
X1267204Y256929D01*
G01X1275577Y253123D02*
X1271010D01*
G01X1276247D02*
X1281174Y258050D01*
G01X1275577Y253123D02*
X1276247D01*
G01X1231684Y261252D02*
X1226595Y256163D01*
G01X1309292Y261252D02*
X1231684D01*
G01X1221388Y254821D02*
X1221387Y254822D01*
G01X1226725Y254821D02*
X1221388D01*
G01X1226915Y255011D02*
X1226725Y254821D01*
G01X1227073Y255011D02*
X1226915D01*
G01X1232162Y260100D02*
X1227073Y255011D01*
G01X1309380Y260100D02*
X1232162D01*
G01X1280036Y236296D02*
X1275154D01*
G01X1284115Y232217D02*
X1280036Y236296D01*
G01X1274954Y236096D02*
X1275154Y236296D01*
G01X1268490Y236096D02*
X1274954D01*
G01X1257750Y246836D02*
X1268490Y236096D01*
G01X1236146Y246836D02*
X1257750D01*
G01X1226250Y236940D02*
X1236146Y246836D01*
G01X1272157Y250346D02*
X1277499D01*
G01X1264794Y257709D02*
X1272157Y250346D01*
G01X1277499Y250351D02*
Y250346D01*
G01X1277509Y250351D02*
X1277499D01*
G01X1282958Y255800D02*
X1277509Y250351D01*
G01X1277499Y250346D02*
X1277504D01*
G01X1273881Y241340D02*
X1281034D01*
G01X1272761Y240220D02*
X1273881Y241340D01*
G01X1269538Y240220D02*
X1272761D01*
G01X1258988Y250770D02*
X1269538Y240220D01*
G01X1233949Y250770D02*
X1258988D01*
G01X1291217Y229338D02*
X1279950D01*
G01X1237490Y243390D02*
X1227911Y233811D01*
G01X1257458Y243390D02*
X1237490D01*
G01X1271510Y229338D02*
X1257458Y243390D01*
G01X1279950Y229338D02*
X1271510D01*
G01X1245047Y232919D02*
X1253690D01*
G01X1231276Y219148D02*
X1245047Y232919D01*
G01X1281454Y249663D02*
X1279393Y247602D01*
G01X1232986Y254348D02*
X1225659Y247021D01*
G01X1265292Y254348D02*
X1232986D01*
G01X1270478Y249162D02*
X1265292Y254348D01*
G01X1270478Y243490D02*
Y249162D01*
G01X1254480Y234823D02*
X1244235D01*
G01X1270151Y219152D02*
X1254480Y234823D01*
G01X1374456Y219152D02*
X1270151D01*
G01X1270463Y219904D02*
X1374768D01*
G01X1254792Y235575D02*
X1270463Y219904D01*
G01X1254789Y235575D02*
X1254792D01*
G01X1254611Y235753D02*
X1254789Y235575D01*
G01X1243919Y235753D02*
X1254611D01*
G01X1227718Y264538D02*
X1222450D01*
G01X1229323Y262933D02*
X1227718Y264538D01*
G01X1308675Y262933D02*
X1229323D01*
G01X1245842Y231767D02*
X1232428Y218353D01*
G01X1253212Y231767D02*
X1245842D01*
G01X1274360Y239590D02*
X1281154D01*
G01X1273414Y238644D02*
X1274360Y239590D01*
G01X1269484Y238644D02*
X1273414D01*
G01X1258788Y249340D02*
X1269484Y238644D01*
G01X1234640Y249340D02*
X1258788D01*
G01X1271367Y223890D02*
X1281330D01*
G01X1256226Y239031D02*
X1271367Y223890D01*
G01X1256223Y239031D02*
X1256226D01*
G01X1256044Y239210D02*
X1256223Y239031D01*
G01X1253178Y239210D02*
X1256044D01*
G01X1253177Y239209D02*
X1253178Y239210D01*
G01X1241507Y239209D02*
X1253177D01*
G01X1221007Y218709D02*
X1241507Y239209D01*
G01X1220548Y218709D02*
X1221007D01*
G01X1219939Y218100D02*
X1220548Y218709D01*
G01X1253655Y238057D02*
X1242051D01*
G01X1253656Y238058D02*
X1253655Y238057D01*
G01X1255566Y238058D02*
X1253656D01*
G01X1255745Y237879D02*
X1255566Y238058D01*
G01X1255748Y237879D02*
X1255745D01*
G01X1271268Y222359D02*
X1255748Y237879D01*
G01X1283002Y222359D02*
X1271268D01*
G01X1239019Y242138D02*
X1229151Y232270D01*
G01X1256939Y242138D02*
X1239019D01*
G01X1272175Y226902D02*
X1256939Y242138D01*
G01X1280800Y226902D02*
X1272175D01*
G01X1232964Y255500D02*
X1225237Y247773D01*
G01X1265231Y255500D02*
X1232964D01*
G01X1272019Y248712D02*
X1265231Y255500D01*
G01X1278259Y248712D02*
X1272019D01*
G01X1282187Y252640D02*
X1278259Y248712D01*
G01X1269839Y218400D02*
X1374144D01*
G01X1254168Y234071D02*
X1269839Y218400D01*
G01X1244569Y234071D02*
X1254168D01*
G01X1274445Y237904D02*
X1280574D01*
G01X1273933Y237392D02*
X1274445Y237904D01*
G01X1268965Y237392D02*
X1273933D01*
G01X1258269Y248088D02*
X1268965Y237392D01*
G01X1235368Y248088D02*
X1258269D01*
G01X1230229Y264179D02*
X1308493D01*
G01X1228781Y265627D02*
X1230229Y264179D01*
G01X1221930Y265627D02*
X1228781D01*
G01X1271378Y225650D02*
X1281319D01*
G01X1256745Y240283D02*
X1271378Y225650D01*
G01X1256742Y240283D02*
X1256745D01*
G01X1256563Y240462D02*
X1256742Y240283D01*
G01X1252659Y240462D02*
X1256563D01*
G01X1252658Y240461D02*
X1252659Y240462D01*
G01X1239113Y240461D02*
X1252658D01*
G01X1228499Y229847D02*
X1239113Y240461D01*
G01X1253049Y230300D02*
X1246005D01*
G01X1228986Y267315D02*
X1221791D01*
G01X1230286Y266015D02*
X1228986Y267315D01*
G01X1231226Y266015D02*
X1230286D01*
G01X1231578Y266367D02*
X1231226Y266015D01*
G01X1231578Y268796D02*
Y266367D01*
G01X1231930Y269148D02*
X1231578Y268796D01*
G01X1233078Y269148D02*
X1231930D01*
G01X1233430Y268796D02*
X1233078Y269148D01*
G01X1233430Y266367D02*
Y268796D01*
G01X1233782Y266015D02*
X1233430Y266367D01*
G01X1234930Y266015D02*
X1233782D01*
G01X1235282Y266367D02*
X1234930Y266015D01*
G01X1235282Y268796D02*
Y266367D01*
G01X1235634Y269148D02*
X1235282Y268796D01*
G01X1236782Y269148D02*
X1235634D01*
G01X1237134Y268796D02*
X1236782Y269148D01*
G01X1237134Y266367D02*
Y268796D01*
G01X1237486Y266015D02*
X1237134Y266367D01*
G01X1238634Y266015D02*
X1237486D01*
G01X1238986Y266367D02*
X1238634Y266015D01*
G01X1238986Y268796D02*
Y266367D01*
G01X1239338Y269148D02*
X1238986Y268796D01*
G01X1240486Y269148D02*
X1239338D01*
G01X1240838Y268796D02*
X1240486Y269148D01*
G01X1240838Y266367D02*
Y268796D01*
G01X1241190Y266015D02*
X1240838Y266367D01*
G01X1242338Y266015D02*
X1241190D01*
G01X1242690Y266367D02*
X1242338Y266015D01*
G01X1242690Y268796D02*
Y266367D01*
G01X1243042Y269148D02*
X1242690Y268796D01*
G01X1244190Y269148D02*
X1243042D01*
G01X1244542Y268796D02*
X1244190Y269148D01*
G01X1244542Y266367D02*
Y268796D01*
G01X1244894Y266015D02*
X1244542Y266367D01*
G01X1246042Y266015D02*
X1244894D01*
G01X1246394Y266367D02*
X1246042Y266015D01*
G01X1246394Y268796D02*
Y266367D01*
G01X1246746Y269148D02*
X1246394Y268796D01*
G01X1247894Y269148D02*
X1246746D01*
G01X1248246Y268796D02*
X1247894Y269148D01*
G01X1248246Y266367D02*
Y268796D01*
G01X1248598Y266015D02*
X1248246Y266367D01*
G01X1249746Y266015D02*
X1248598D01*
G01X1250098Y266367D02*
X1249746Y266015D01*
G01X1250098Y268796D02*
Y266367D01*
G01X1250450Y269148D02*
X1250098Y268796D01*
G01X1251598Y269148D02*
X1250450D01*
G01X1251950Y268796D02*
X1251598Y269148D01*
G01X1251950Y266367D02*
Y268796D01*
G01X1252302Y266015D02*
X1251950Y266367D01*
G01X1253450Y266015D02*
X1252302D01*
G01X1253802Y266367D02*
X1253450Y266015D01*
G01X1253802Y268796D02*
Y266367D01*
G01X1254154Y269148D02*
X1253802Y268796D01*
G01X1255302Y269148D02*
X1254154D01*
G01X1255654Y268796D02*
X1255302Y269148D01*
G01X1255654Y266367D02*
Y268796D01*
G01X1256006Y266015D02*
X1255654Y266367D01*
G01X1257154Y266015D02*
X1256006D01*
G01X1257506Y266367D02*
X1257154Y266015D01*
G01X1257506Y268796D02*
Y266367D01*
G01X1257858Y269148D02*
X1257506Y268796D01*
G01X1259006Y269148D02*
X1257858D01*
G01X1259358Y268796D02*
X1259006Y269148D01*
G01X1259358Y266367D02*
Y268796D01*
G01X1259710Y266015D02*
X1259358Y266367D01*
G01X1260858Y266015D02*
X1259710D01*
G01X1261210Y266367D02*
X1260858Y266015D01*
G01X1261210Y268796D02*
Y266367D01*
G01X1261562Y269148D02*
X1261210Y268796D01*
G01X1262710Y269148D02*
X1261562D01*
G01X1263062Y268796D02*
X1262710Y269148D01*
G01X1263062Y266367D02*
Y268796D01*
G01X1263414Y266015D02*
X1263062Y266367D01*
G01X1264562Y266015D02*
X1263414D01*
G01X1264914Y266367D02*
X1264562Y266015D01*
G01X1264914Y268796D02*
Y266367D01*
G01X1265266Y269148D02*
X1264914Y268796D01*
G01X1266414Y269148D02*
X1265266D01*
G01X1266766Y268796D02*
X1266414Y269148D01*
G01X1266766Y266367D02*
Y268796D01*
G01X1267118Y266015D02*
X1266766Y266367D01*
G01X1268266Y266015D02*
X1267118D01*
G01X1268618Y266367D02*
X1268266Y266015D01*
G01X1268618Y268796D02*
Y266367D01*
G01X1268970Y269148D02*
X1268618Y268796D01*
G01X1270118Y269148D02*
X1268970D01*
G01X1270470Y268796D02*
X1270118Y269148D01*
G01X1270470Y266367D02*
Y268796D01*
G01X1270822Y266015D02*
X1270470Y266367D01*
G01X1271970Y266015D02*
X1270822D01*
G01X1272322Y266367D02*
X1271970Y266015D01*
G01X1272322Y268796D02*
Y266367D01*
G01X1272674Y269148D02*
X1272322Y268796D01*
G01X1273822Y269148D02*
X1272674D01*
G01X1274174Y268796D02*
X1273822Y269148D01*
G01X1274174Y266367D02*
Y268796D01*
G01X1274526Y266015D02*
X1274174Y266367D01*
G01X1275674Y266015D02*
X1274526D01*
G01X1276026Y266367D02*
X1275674Y266015D01*
G01X1276026Y268796D02*
Y266367D01*
G01X1276378Y269148D02*
X1276026Y268796D01*
G01X1277526Y269148D02*
X1276378D01*
G01X1277878Y268796D02*
X1277526Y269148D01*
G01X1277878Y266367D02*
Y268796D01*
G01X1278230Y266015D02*
X1277878Y266367D01*
G01X1279378Y266015D02*
X1278230D01*
G01X1279730Y266367D02*
X1279378Y266015D01*
G01X1279730Y268796D02*
Y266367D01*
G01X1280082Y269148D02*
X1279730Y268796D01*
G01X1281230Y269148D02*
X1280082D01*
G01X1254133Y236905D02*
X1243441D01*
G01X1254134Y236906D02*
X1254133Y236905D01*
G01X1255088Y236906D02*
X1254134D01*
G01X1255267Y236727D02*
X1255088Y236906D01*
G01X1255270Y236727D02*
X1255267D01*
G01X1270790Y221207D02*
X1255270Y236727D01*
G01X1282524Y221207D02*
X1270790D01*
G01X1222787Y311747D02*
X1305886D01*
G01X1224465Y312759D02*
X1220414Y316810D01*
G01X1305751Y312759D02*
X1224465D01*
G01X1302506Y310257D02*
X1222378D01*
G01X1224573Y314439D02*
X1302203D01*
G01X1221412Y317600D02*
X1224573Y314439D01*
G01X1246300Y400400D02*
X1246010Y400110D01*
G01X1266007Y400400D02*
X1246300D01*
G01X1273855Y408248D02*
X1266007Y400400D01*
G01X1246589Y398339D02*
X1243399D01*
G01X1246657Y398407D02*
X1246589Y398339D01*
G01X1246714Y398407D02*
X1246657D01*
G01X1247005Y398698D02*
X1246714Y398407D01*
G01X1266712Y398698D02*
X1247005D01*
G01X1274560Y406546D02*
X1266712Y398698D01*
G01X1265500Y402300D02*
X1273150Y409950D01*
G01X1249508Y402300D02*
X1265500D01*
G01X1249230Y402022D02*
X1249508Y402300D01*
G01X1288155Y408248D02*
X1273855D01*
G01X1288860Y406546D02*
X1274560D01*
G01X1273150Y409950D02*
X1287450D01*
G01X1258653Y480453D02*
X1249694D01*
G01X1262897Y484697D02*
X1258653Y480453D01*
G01X1262897Y488574D02*
Y484697D01*
G01X1266926Y492603D02*
X1262897Y488574D01*
G01X1268594Y492603D02*
X1266926D01*
G01X1269334Y493343D02*
X1268594Y492603D01*
G01X1274035Y493343D02*
X1269334D01*
G01X1277800Y497108D02*
X1274035Y493343D01*
G01X1253690Y491840D02*
Y487143D01*
G01X1255754Y493904D02*
X1253690Y491840D01*
G01X1255754Y493943D02*
Y493904D01*
G01X1256677Y494866D02*
X1255754Y493943D01*
G01X1256716Y494866D02*
X1256677D01*
G01X1256960Y495110D02*
X1256716Y494866D01*
G01X1259460Y495110D02*
X1256960D01*
G01X1259790Y494780D02*
X1259460Y495110D01*
G01X1267971Y494780D02*
X1259790D01*
G01X1269006Y495815D02*
X1267971Y494780D01*
G01X1269006Y496016D02*
Y495815D01*
G01X1252660Y492280D02*
Y487460D01*
G01X1256442Y496062D02*
X1252660Y492280D01*
G01X1259855Y496062D02*
X1256442D01*
G01X1260185Y495732D02*
X1259855Y496062D01*
G01X1265490Y495732D02*
X1260185D01*
G01X1266162Y496404D02*
X1265490Y495732D01*
G01X1259351Y479501D02*
X1250089D01*
G01X1263849Y483999D02*
X1259351Y479501D01*
G01X1263849Y488179D02*
Y483999D01*
G01X1267312Y491642D02*
X1263849Y488179D01*
G01X1268980Y491642D02*
X1267312D01*
G01X1269675Y492337D02*
X1268980Y491642D01*
G01X1274854Y492337D02*
X1269675D01*
G01X1276509Y493992D02*
X1274854Y492337D01*
G01X1278148Y493992D02*
X1276509D01*
G01X1280595Y496439D02*
X1278148Y493992D01*
G01X1279917Y501511D02*
X1282811D01*
G01X1272784Y494378D02*
X1279917Y501511D01*
G01X1268948Y494378D02*
X1272784D01*
G01X1268168Y493598D02*
X1268948Y494378D01*
G01X1266574Y493598D02*
X1268168D01*
G01X1261945Y488969D02*
X1266574Y493598D01*
G01X1261945Y485092D02*
Y488969D01*
G01X1258258Y481405D02*
X1261945Y485092D01*
G01X1249299Y481405D02*
X1258258D01*
G01X1279095Y567305D02*
Y588406D01*
G01X1285400Y561000D02*
X1279095Y567305D01*
G01X1278032Y587468D02*
X1276071Y589429D01*
G01X1278032Y562668D02*
Y587468D01*
G01X1281600Y559100D02*
X1278032Y562668D01*
G01X1279847Y568940D02*
Y588753D01*
G01X1286787Y562000D02*
X1279847Y568940D01*
G01X1273851Y587978D02*
Y608318D01*
G01X1275928Y585901D02*
X1273851Y587978D01*
G01X1275928Y551541D02*
Y585901D01*
G01X1283376Y544093D02*
X1275928Y551541D01*
G01X1253544Y576410D02*
Y611058D01*
G01X1255120Y574834D02*
X1253544Y576410D01*
G01X1276880Y586990D02*
X1274919Y588951D01*
G01X1276880Y551936D02*
Y586990D01*
G01X1283771Y545045D02*
X1276880Y551936D01*
G01X1276892Y609318D02*
X1266513Y619697D01*
G01X1276892Y590609D02*
Y609318D01*
G01X1279095Y588406D02*
X1276892Y590609D01*
G01X1278396Y610603D02*
X1267542Y621457D01*
G01X1278396Y591504D02*
Y610603D01*
G01X1280600Y589300D02*
X1278396Y591504D01*
G01X1276071Y609075D02*
X1266601Y618545D01*
G01X1276071Y589429D02*
Y609075D01*
G01X1277644Y609630D02*
X1266825Y620449D01*
G01X1277644Y590956D02*
Y609630D01*
G01X1279847Y588753D02*
X1277644Y590956D01*
G01X1273851Y608318D02*
X1265728Y616441D01*
G01X1253544Y611058D02*
X1255120Y612634D01*
G01X1274919Y608597D02*
X1266123Y617393D01*
G01X1274919Y588951D02*
Y608597D01*
G01X1296850Y-18023D02*
X1293979Y-20894D01*
G01X1296850Y3602D02*
Y-18023D01*
G01X1298615Y5367D02*
X1296850Y3602D01*
G01X1298615Y17774D02*
Y5367D01*
G01X1303108Y22267D02*
X1298615Y17774D01*
G01X1303108Y33623D02*
Y22267D01*
G01X1280676Y-15536D02*
Y-11476D01*
G01X1304480Y29505D02*
X1322349Y47374D01*
G01X1304480Y21894D02*
Y29505D01*
G01X1299367Y16781D02*
X1304480Y21894D01*
G01X1299367Y4115D02*
Y16781D01*
G01X1297738Y2486D02*
X1299367Y4115D01*
G01X1297738Y-19346D02*
Y2486D01*
G01X1295438Y-21646D02*
X1297738Y-19346D01*
G01X1331000Y-15600D02*
Y40908D01*
G01X1327724Y-18876D02*
X1331000Y-15600D01*
G01X1306547Y-18876D02*
X1327724D01*
G01X1305124Y-17453D02*
X1306547Y-18876D01*
G01X1305124Y-16902D02*
Y-17453D01*
G01X1303801Y-15579D02*
X1305124Y-16902D01*
G01X1299470Y-15579D02*
X1303801D01*
G01X1299369Y-15680D02*
X1299470Y-15579D01*
G01X1292200Y1500D02*
X1292692Y1008D01*
G01X1287327Y1500D02*
X1292200D01*
G01X1280474Y8353D02*
X1287327Y1500D01*
G01X1280474Y35675D02*
Y8353D01*
G01X1287641Y-13971D02*
X1282974Y-18638D01*
G01X1288779Y-13971D02*
X1287641D01*
G01X1294488Y-8262D02*
X1288779Y-13971D01*
G01X1294488Y20378D02*
Y-8262D01*
G01X1299752Y25642D02*
X1294488Y20378D01*
G01X1299752Y39629D02*
Y25642D01*
G01X1287700Y-16571D02*
Y-16700D01*
G01X1295240Y-9031D02*
X1287700Y-16571D01*
G01X1295240Y17284D02*
Y-9031D01*
G01X1301604Y23648D02*
X1295240Y17284D01*
G01X1301604Y39399D02*
Y23648D01*
G01X1295992Y-17817D02*
X1293667Y-20142D01*
G01X1295992Y4091D02*
Y-17817D01*
G01X1297863Y5962D02*
X1295992Y4091D01*
G01X1297863Y18369D02*
Y5962D01*
G01X1302356Y22862D02*
X1297863Y18369D01*
G01X1302356Y33935D02*
Y22862D01*
G01X1303956Y34471D02*
X1303108Y33623D01*
G01X1308382Y34471D02*
X1303956D01*
G01X1322037Y48126D02*
X1308382Y34471D01*
G01X1331484Y48126D02*
X1322037D01*
G01X1340664Y57306D02*
X1331484Y48126D01*
G01X1340664Y72880D02*
Y57306D01*
G01X1343829Y76045D02*
X1340664Y72880D01*
G01X1295461Y42922D02*
X1284528D01*
G01X1298726Y46187D02*
X1295461Y42922D01*
G01X1298726Y53874D02*
Y46187D01*
G01X1293546Y59054D02*
X1298726Y53874D01*
G01X1283586Y59054D02*
X1293546D01*
G01X1304248Y88727D02*
X1298754Y83233D01*
G01X1304248Y104380D02*
Y88727D01*
G01X1301219Y89141D02*
Y97602D01*
G01X1312297Y94698D02*
X1311551Y93952D01*
G01X1293406Y61358D02*
X1285108D01*
G01X1300230Y54534D02*
X1293406Y61358D01*
G01X1300230Y45563D02*
Y54534D01*
G01X1295367Y40700D02*
X1300230Y45563D01*
G01X1284435Y40700D02*
X1295367D01*
G01X1295362Y41759D02*
X1284430D01*
G01X1299478Y45875D02*
X1295362Y41759D01*
G01X1299478Y54222D02*
Y45875D01*
G01X1293494Y60206D02*
X1299478Y54222D01*
G01X1284064Y60206D02*
X1293494D01*
G01X1341578Y72238D02*
X1343340Y74000D01*
G01X1341578Y56740D02*
Y72238D01*
G01X1332226Y47388D02*
X1341578Y56740D01*
G01X1331810Y47388D02*
X1332226D01*
G01X1331796Y47374D02*
X1331810Y47388D01*
G01X1322349Y47374D02*
X1331796D01*
G01X1340148Y50056D02*
X1365640D01*
G01X1331000Y40908D02*
X1340148Y50056D01*
G01X1336554Y84862D02*
X1345730D01*
G01X1329328Y77636D02*
X1336554Y84862D01*
G01X1329328Y63643D02*
Y77636D01*
G01X1327168Y61483D02*
X1329328Y63643D01*
G01X1305000Y83000D02*
Y123291D01*
G01X1308400Y79600D02*
X1305000Y83000D01*
G01X1329044Y84756D02*
X1330300Y83500D01*
G01X1322055Y84756D02*
X1329044D01*
G01X1320323Y83024D02*
X1322055Y84756D01*
G01X1316647Y83024D02*
X1320323D01*
G01X1307396Y92275D02*
X1316647Y83024D01*
G01X1307396Y122050D02*
Y92275D01*
G01X1306644Y86356D02*
Y122362D01*
G01X1309700Y83300D02*
X1306644Y86356D01*
G01X1284611Y39810D02*
X1280474Y35675D01*
G01X1298869Y39810D02*
X1284611D01*
G01X1299347Y40288D02*
X1298869Y39810D01*
G01X1299347Y42673D02*
Y40288D01*
G01X1300982Y44308D02*
X1299347Y42673D01*
G01X1300982Y55418D02*
Y44308D01*
G01X1293890Y62510D02*
X1300982Y55418D01*
G01X1285020Y62510D02*
X1293890D01*
G01X1280577Y66953D02*
X1285020Y62510D01*
G01X1280577Y95551D02*
Y66953D01*
G01X1301734Y41611D02*
X1299752Y39629D01*
G01X1301734Y56865D02*
Y41611D01*
G01X1296846Y61753D02*
X1301734Y56865D01*
G01X1296846Y86120D02*
Y61753D01*
G01X1297724Y86998D02*
X1296846Y86120D01*
G01X1297724Y125717D02*
Y86998D01*
G01X1313500Y93372D02*
Y118579D01*
G01X1311559Y91431D02*
X1313500Y93372D01*
G01X1309976Y47771D02*
X1301604Y39399D01*
G01X1309976Y80795D02*
Y47771D01*
G01X1305892Y84879D02*
X1309976Y80795D01*
G01X1305892Y122674D02*
Y84879D01*
G01X1303644Y35223D02*
X1302356Y33935D01*
G01X1308070Y35223D02*
X1303644D01*
G01X1321739Y48892D02*
X1308070Y35223D01*
G01X1330903Y48892D02*
X1321739D01*
G01X1339712Y57701D02*
X1330903Y48892D01*
G01X1339712Y73275D02*
Y57701D01*
G01X1343434Y76997D02*
X1339712Y73275D01*
G01X1293286Y58114D02*
X1283462D01*
G01X1296935Y54465D02*
X1293286Y58114D01*
G01X1296935Y51335D02*
Y54465D01*
G01X1308983Y93814D02*
Y94504D01*
G01X1331261Y138476D02*
X1398252D01*
G01X1329954Y137169D02*
X1331261Y138476D01*
G01X1326872Y137169D02*
X1329954D01*
G01X1323026Y133323D02*
X1326872Y137169D01*
G01X1288552Y124052D02*
Y108416D01*
G01X1292059Y127559D02*
X1288552Y124052D01*
G01X1292059Y143196D02*
Y127559D01*
G01X1301983Y153120D02*
X1292059Y143196D01*
G01X1310828Y153120D02*
X1301983D01*
G01X1314032Y156324D02*
X1310828Y153120D01*
G01X1310040Y96742D02*
X1308972D01*
G01X1310393Y97095D02*
X1310040Y96742D01*
G01X1310393Y123983D02*
Y97095D01*
G01X1325083Y138673D02*
X1310393Y123983D01*
G01X1329330Y138673D02*
X1325083D01*
G01X1330637Y139980D02*
X1329330Y138673D01*
G01X1398876Y139980D02*
X1330637D01*
G01X1300228Y108400D02*
X1304248Y104380D01*
G01X1300228Y125029D02*
Y108400D01*
G01X1304614Y129415D02*
X1300228Y125029D01*
G01X1307942Y129415D02*
X1304614D01*
G01X1309713Y131186D02*
X1307942Y129415D01*
G01X1309713Y140256D02*
Y131186D01*
G01X1313180Y143723D02*
X1309713Y140256D01*
G01X1313180Y145531D02*
Y143723D01*
G01X1317745Y150096D02*
X1313180Y145531D01*
G01X1322696Y150096D02*
X1317745D01*
G01X1324520Y151920D02*
X1322696Y150096D01*
G01X1389452Y151920D02*
X1324520D01*
G01X1328042Y143060D02*
X1411545D01*
G01X1327900Y142918D02*
X1328042Y143060D01*
G01X1324208Y152672D02*
X1389917D01*
G01X1322384Y150848D02*
X1324208Y152672D01*
G01X1317433Y150848D02*
X1322384D01*
G01X1312428Y145843D02*
X1317433Y150848D01*
G01X1312428Y144035D02*
Y145843D01*
G01X1308931Y140538D02*
X1312428Y144035D01*
G01X1308931Y131468D02*
Y140538D01*
G01X1307631Y130168D02*
X1308931Y131468D01*
G01X1304303Y130168D02*
X1307631D01*
G01X1299476Y125341D02*
X1304303Y130168D01*
G01X1299476Y107853D02*
Y125341D01*
G01X1303496Y103833D02*
X1299476Y107853D01*
G01X1303496Y99879D02*
Y103833D01*
G01X1301219Y97602D02*
X1303496Y99879D01*
G01X1312297Y119006D02*
Y94698D01*
G01X1324369Y131078D02*
X1312297Y119006D01*
G01X1328148Y131078D02*
X1324369D01*
G01X1333642Y136572D02*
X1328148Y131078D01*
G01X1397462Y136572D02*
X1333642D01*
G01X1318820Y154820D02*
X1325576Y161576D01*
G01X1314656Y154820D02*
X1318820D01*
G01X1311452Y151616D02*
X1314656Y154820D01*
G01X1309223Y151616D02*
X1311452D01*
G01X1297444Y139837D02*
X1309223Y151616D01*
G01X1297444Y129684D02*
Y139837D01*
G01X1290856Y123096D02*
X1297444Y129684D01*
G01X1290856Y107460D02*
Y123096D01*
G01X1289704Y123574D02*
Y107938D01*
G01X1296292Y130162D02*
X1289704Y123574D01*
G01X1296292Y139749D02*
Y130162D01*
G01X1308911Y152368D02*
X1296292Y139749D01*
G01X1311140Y152368D02*
X1308911D01*
G01X1314344Y155572D02*
X1311140Y152368D01*
G01X1318508Y155572D02*
X1314344D01*
G01X1325489Y162553D02*
X1318508Y155572D01*
G01X1305387Y156032D02*
X1308155Y158800D01*
G01X1292411Y156032D02*
X1305387D01*
G01X1290143Y158300D02*
X1292411Y156032D01*
G01X1283510Y154894D02*
X1286916Y158300D01*
G01X1283510Y139239D02*
Y154894D01*
G01X1281999Y137728D02*
X1283510Y139239D01*
G01X1281999Y128561D02*
Y137728D01*
G01X1282499Y128061D02*
X1281999Y128561D01*
G01X1282499Y125908D02*
Y128061D01*
G01X1280885Y124294D02*
X1282499Y125908D01*
G01X1280885Y109485D02*
Y124294D01*
G01X1292099Y155280D02*
X1290804Y156575D01*
G01X1306182Y155280D02*
X1292099D01*
G01X1308950Y158048D02*
X1306182Y155280D01*
G01X1319498Y146576D02*
X1385753D01*
G01X1317912Y144990D02*
X1319498Y146576D01*
G01X1317912Y143611D02*
Y144990D01*
G01X1312017Y137716D02*
X1317912Y143611D01*
G01X1312017Y130308D02*
Y137716D01*
G01X1305000Y123291D02*
X1312017Y130308D01*
G01X1325132Y139786D02*
X1307396Y122050D01*
G01X1329379Y139786D02*
X1325132D01*
G01X1330397Y140804D02*
X1329379Y139786D01*
G01X1399236Y140804D02*
X1330397D01*
G01X1330085Y141556D02*
X1399594D01*
G01X1329067Y140538D02*
X1330085Y141556D01*
G01X1324820Y140538D02*
X1329067D01*
G01X1306644Y122362D02*
X1324820Y140538D01*
G01X1319186Y147328D02*
X1386500D01*
G01X1317159Y145301D02*
X1319186Y147328D01*
G01X1317159Y144159D02*
Y145301D01*
G01X1310865Y137865D02*
X1317159Y144159D01*
G01X1310865Y130708D02*
Y137865D01*
G01X1304557Y124400D02*
X1310865Y130708D01*
G01X1301900Y124400D02*
X1304557D01*
G01X1320096Y152396D02*
X1324500Y156800D01*
G01X1316853Y152396D02*
X1320096D01*
G01X1311376Y146919D02*
X1316853Y152396D01*
G01X1310754Y146919D02*
X1311376D01*
G01X1310753Y146920D02*
X1310754Y146919D01*
G01X1309243Y146920D02*
X1310753D01*
G01X1304329Y142006D02*
X1309243Y146920D01*
G01X1304329Y131258D02*
Y142006D01*
G01X1298724Y125653D02*
X1304329Y131258D01*
G01X1298724Y107541D02*
Y125653D01*
G01X1301770Y104495D02*
X1298724Y107541D01*
G01X1301770Y101300D02*
Y104495D01*
G01X1295996Y110970D02*
X1280577Y95551D01*
G01X1295996Y125900D02*
Y110970D01*
G01X1302385Y132289D02*
X1295996Y125900D01*
G01X1302385Y143714D02*
Y132289D01*
G01X1307095Y148424D02*
X1302385Y143714D01*
G01X1310753Y148424D02*
X1307095D01*
G01X1316229Y153900D02*
X1310753Y148424D01*
G01X1319472Y153900D02*
X1316229D01*
G01X1323877Y158305D02*
X1319472Y153900D01*
G01X1303577Y131570D02*
X1297724Y125717D01*
G01X1303577Y142318D02*
Y131570D01*
G01X1308931Y147672D02*
X1303577Y142318D01*
G01X1311065Y147672D02*
X1308931D01*
G01X1316541Y153148D02*
X1311065Y147672D01*
G01X1319784Y153148D02*
X1316541D01*
G01X1324188Y157552D02*
X1319784Y153148D01*
G01X1334120Y135420D02*
X1396984D01*
G01X1328625Y129925D02*
X1334120Y135420D01*
G01X1324846Y129925D02*
X1328625D01*
G01X1313500Y118579D02*
X1324846Y129925D01*
G01X1324508Y141290D02*
X1305892Y122674D01*
G01X1328755Y141290D02*
X1324508D01*
G01X1329773Y142308D02*
X1328755Y141290D01*
G01X1399972Y142308D02*
X1329773D01*
G01X1331573Y137724D02*
X1397940D01*
G01X1330266Y136417D02*
X1331573Y137724D01*
G01X1329120Y136417D02*
X1330266D01*
G01X1326026Y133323D02*
X1329120Y136417D01*
G01X1306947Y154257D02*
X1309986Y157296D01*
G01X1302056Y154257D02*
X1306947D01*
G01X1291307Y143508D02*
X1302056Y154257D01*
G01X1291307Y128507D02*
Y143508D01*
G01X1287800Y125000D02*
X1291307Y128507D01*
G01X1287800Y108728D02*
Y125000D01*
G01X1330949Y139228D02*
X1398564D01*
G01X1329642Y137921D02*
X1330949Y139228D01*
G01X1325395Y137921D02*
X1329642D01*
G01X1311145Y123671D02*
X1325395Y137921D01*
G01X1311145Y96666D02*
Y123671D01*
G01X1308983Y94504D02*
X1311145Y96666D01*
G01X1306900Y139571D02*
Y131744D01*
G01X1311676Y144347D02*
X1306900Y139571D01*
G01X1311676Y146155D02*
Y144347D01*
G01X1317121Y151600D02*
X1311676Y146155D01*
G01X1322072Y151600D02*
X1317121D01*
G01X1323896Y153424D02*
X1322072Y151600D01*
G01X1390688Y153424D02*
X1323896D01*
G01X1338413Y205351D02*
X1284695D01*
G01X1342100Y209038D02*
X1338413Y205351D01*
G01X1291736Y165700D02*
X1284081D01*
G01X1300022Y173986D02*
X1291736Y165700D01*
G01X1308797Y173986D02*
X1300022D01*
G01X1314801Y179990D02*
X1308797Y173986D01*
G01X1410237Y179990D02*
X1314801D01*
G01X1294395Y190100D02*
X1411793D01*
G01X1412009Y191380D02*
X1294611D01*
G01X1318196Y156324D02*
X1314032D01*
G01X1325177Y163305D02*
X1318196Y156324D01*
G01X1391152Y163305D02*
X1325177D01*
G01X1340596Y201942D02*
X1345418Y206764D01*
G01X1329822Y201942D02*
X1340596D01*
G01X1329821Y201943D02*
X1329822Y201942D01*
G01X1293470Y201943D02*
X1329821D01*
G01X1339956Y216656D02*
X1374824D01*
G01X1334227Y210927D02*
X1339956Y216656D01*
G01X1285067Y210927D02*
X1334227D01*
G01X1341348Y212715D02*
X1343185Y214552D01*
G01X1341348Y209448D02*
Y212715D01*
G01X1338003Y206103D02*
X1341348Y209448D01*
G01X1284383Y206103D02*
X1338003D01*
G01X1294300Y192133D02*
X1406674D01*
G01X1404708Y198998D02*
X1293717D01*
G01X1341220Y200438D02*
X1346042Y205260D01*
G01X1331070Y200438D02*
X1341220D01*
G01X1331069Y200437D02*
X1331070Y200438D01*
G01X1329199Y200437D02*
X1331069D01*
G01X1329197Y200439D02*
X1329199Y200437D01*
G01X1294094Y200439D02*
X1329197D01*
G01X1325576Y161576D02*
X1390753D01*
G01X1390840Y162553D02*
X1325489D01*
G01X1330074Y216300D02*
Y216500D01*
G01X1328230Y214456D02*
X1330074Y216300D01*
G01X1320204Y214456D02*
X1328230D01*
G01X1320200Y214452D02*
X1320204Y214456D01*
G01X1323618Y168300D02*
X1398271D01*
G01X1321676Y166358D02*
X1323618Y168300D01*
G01X1321676Y164347D02*
Y166358D01*
G01X1316129Y158800D02*
X1321676Y164347D01*
G01X1308155Y158800D02*
X1316129D01*
G01X1286916Y158300D02*
X1290143D01*
G01X1338725Y204599D02*
X1342852Y208726D01*
G01X1285007Y204599D02*
X1338725D01*
G01X1308017Y163191D02*
X1310061Y165235D01*
G01X1304518Y163191D02*
X1308017D01*
G01X1303595Y164114D02*
X1304518Y163191D01*
G01X1303595Y165420D02*
Y164114D01*
G01X1304518Y166343D02*
X1303595Y165420D01*
G01X1305007Y166343D02*
X1304518D01*
G01X1307939Y169275D02*
X1305007Y166343D01*
G01X1307939Y169884D02*
Y169275D01*
G01X1316141Y178086D02*
X1307939Y169884D01*
G01X1409447Y178086D02*
X1316141D01*
G01X1406762Y193285D02*
X1294388D01*
G01X1330611Y203847D02*
X1288984D01*
G01X1330612Y203846D02*
X1330611Y203847D01*
G01X1339036Y203846D02*
X1330612D01*
G01X1344462Y209272D02*
X1339036Y203846D01*
G01X1291636Y166664D02*
X1283290D01*
G01X1299710Y174738D02*
X1291636Y166664D01*
G01X1308485Y174738D02*
X1299710D01*
G01X1314489Y180742D02*
X1308485Y174738D01*
G01X1410549Y180742D02*
X1314489D01*
G01X1405661Y195942D02*
X1293853D01*
G01X1290804Y156575D02*
X1287790D01*
G01X1316441Y158048D02*
X1308950D01*
G01X1322428Y164035D02*
X1316441Y158048D01*
G01X1322428Y166046D02*
Y164035D01*
G01X1323782Y167400D02*
X1322428Y166046D01*
G01X1394200Y167400D02*
X1323782D01*
G01X1333898Y215061D02*
X1332089Y213252D01*
G01X1333898Y215676D02*
Y215061D01*
G01X1333074Y216500D02*
X1333898Y215676D01*
G01X1291600Y164500D02*
X1283945D01*
G01X1300334Y173234D02*
X1291600Y164500D01*
G01X1309109Y173234D02*
X1300334D01*
G01X1315113Y179238D02*
X1309109Y173234D01*
G01X1409925Y179238D02*
X1315113D01*
G01X1327980Y207607D02*
X1283377D01*
G01X1329324Y208951D02*
X1327980Y207607D01*
G01X1314967Y181894D02*
X1410695D01*
G01X1314966Y181895D02*
X1314967Y181894D01*
G01X1314012Y181895D02*
X1314966D01*
G01X1308007Y175890D02*
X1314012Y181895D01*
G01X1300188Y175890D02*
X1308007D01*
G01X1300187Y175891D02*
X1300188Y175890D01*
G01X1299233Y175891D02*
X1300187D01*
G01X1291158Y167816D02*
X1299233Y175891D01*
G01X1282812Y167816D02*
X1291158D01*
G01X1405349Y196694D02*
X1293541D01*
G01X1324500Y156800D02*
X1390200D01*
G01X1391259Y158305D02*
X1323877D01*
G01X1294476Y194437D02*
X1406284D01*
G01X1390948Y157552D02*
X1324188D01*
G01X1405972Y195189D02*
X1294164D01*
G01X1340522Y215304D02*
X1371260D01*
G01X1336316Y211098D02*
X1340522Y215304D01*
G01X1336316Y208116D02*
Y211098D01*
G01X1335055Y206855D02*
X1336316Y208116D01*
G01X1284071Y206855D02*
X1335055D01*
G01X1405061Y197846D02*
X1293629D01*
G01X1412127Y188804D02*
X1294874D01*
G01X1324094Y166648D02*
X1393888D01*
G01X1323180Y165734D02*
X1324094Y166648D01*
G01X1323180Y163723D02*
Y165734D01*
G01X1316753Y157296D02*
X1323180Y163723D01*
G01X1309986Y157296D02*
X1316753D01*
G01X1295100Y185300D02*
X1412900D01*
G01X1340284Y202694D02*
X1346123Y208533D01*
G01X1330134Y202694D02*
X1340284D01*
G01X1330133Y202695D02*
X1330134Y202694D01*
G01X1291304Y202695D02*
X1330133D01*
G01X1281799Y193190D02*
X1291304Y202695D01*
G01X1308691Y168287D02*
X1305171Y164767D01*
G01X1308691Y169572D02*
Y168287D01*
G01X1316453Y177334D02*
X1308691Y169572D01*
G01X1409135Y177334D02*
X1316453D01*
G01X1335050Y214583D02*
X1332567Y212100D01*
G01X1335050Y215476D02*
Y214583D01*
G01X1336074Y216500D02*
X1335050Y215476D01*
G01X1295128Y187252D02*
X1412205D01*
G01X1329509Y201191D02*
X1293782D01*
G01X1329510Y201190D02*
X1329509Y201191D01*
G01X1340908Y201190D02*
X1329510D01*
G01X1345730Y206012D02*
X1340908Y201190D01*
G01X1322110Y253647D02*
X1398558D01*
G01X1305457Y270300D02*
X1322110Y253647D01*
G01X1290920Y230812D02*
X1283375D01*
G01X1291464Y231356D02*
X1290920Y230812D01*
G01X1299236Y231356D02*
X1291464D01*
G01X1302007Y228585D02*
X1299236Y231356D01*
G01X1391443Y228585D02*
X1302007D01*
G01X1306385Y258050D02*
X1306585Y258250D01*
G01X1281174Y258050D02*
X1306385D01*
G01X1320412Y250132D02*
X1309292Y261252D01*
G01X1396055Y250132D02*
X1320412D01*
G01X1320100Y249380D02*
X1309380Y260100D01*
G01X1395743Y249380D02*
X1320100D01*
G01X1334452Y279448D02*
X1379848D01*
G01X1326105Y287795D02*
X1334452Y279448D01*
G01X1323592Y256151D02*
X1390907D01*
G01X1306172Y273571D02*
X1323592Y256151D01*
G01X1289875Y232217D02*
X1284115D01*
G01X1290558Y232900D02*
X1289875Y232217D01*
G01X1299900Y232900D02*
X1290558D01*
G01X1302913Y229887D02*
X1299900Y232900D01*
G01X1387616Y229887D02*
X1302913D01*
G01X1308200Y255800D02*
X1282958D01*
G01X1315002Y243832D02*
X1406010D01*
G01X1311076Y239906D02*
X1315002Y243832D01*
G01X1311076Y239575D02*
Y239906D01*
G01X1309625Y238124D02*
X1311076Y239575D01*
G01X1284250Y238124D02*
X1309625D01*
G01X1281034Y241340D02*
X1284250Y238124D01*
G01X1327231Y263729D02*
X1306816Y284144D01*
G01X1386362Y263729D02*
X1327231D01*
G01X1291983Y230104D02*
X1291217Y229338D01*
G01X1298717Y230104D02*
X1291983D01*
G01X1301488Y227333D02*
X1298717Y230104D01*
G01X1392073Y227333D02*
X1301488D01*
G01X1322852Y254899D02*
X1391426D01*
G01X1305651Y272100D02*
X1322852Y254899D01*
G01X1324937Y261073D02*
X1305842Y280168D01*
G01X1388017Y261073D02*
X1324937D01*
G01X1315873Y249663D02*
X1281454D01*
G01X1317660Y247876D02*
X1315873Y249663D01*
G01X1395119Y247876D02*
X1317660D01*
G01X1320724Y250884D02*
X1308675Y262933D01*
G01X1396367Y250884D02*
X1320724D01*
G01X1315480Y242680D02*
X1398720D01*
G01X1312228Y239428D02*
X1315480Y242680D01*
G01X1312228Y238969D02*
Y239428D01*
G01X1310230Y236971D02*
X1312228Y238969D01*
G01X1283773Y236971D02*
X1310230D01*
G01X1281154Y239590D02*
X1283773Y236971D01*
G01X1324645Y258612D02*
X1389731D01*
G01X1306955Y276302D02*
X1324645Y258612D01*
G01X1299997Y223511D02*
X1397011D01*
G01X1297160Y226348D02*
X1299997Y223511D01*
G01X1293540Y226348D02*
X1297160D01*
G01X1292638Y225446D02*
X1293540Y226348D01*
G01X1282886Y225446D02*
X1292638D01*
G01X1281330Y223890D02*
X1282886Y225446D01*
G01X1283067Y222294D02*
X1283002Y222359D01*
G01X1284373Y222294D02*
X1283067D01*
G01X1284438Y222359D02*
X1284373Y222294D01*
G01X1398359Y222359D02*
X1284438D01*
G01X1281848Y227950D02*
X1280800Y226902D01*
G01X1291600Y227950D02*
X1281848D01*
G01X1292502Y228852D02*
X1291600Y227950D01*
G01X1298198Y228852D02*
X1292502D01*
G01X1300969Y226081D02*
X1298198Y228852D01*
G01X1393965Y226081D02*
X1300969D01*
G01X1324250Y257660D02*
X1389999D01*
G01X1306560Y275350D02*
X1324250Y257660D01*
G01X1317972Y248628D02*
X1395431D01*
G01X1310950Y255650D02*
X1317972Y248628D01*
G01X1307940Y252640D02*
X1282187D01*
G01X1310950Y255650D02*
X1307940Y252640D01*
G01X1326706Y262977D02*
X1386674D01*
G01X1306583Y283100D02*
X1326706Y262977D01*
G01X1325966Y261825D02*
X1306146Y281645D01*
G01X1387705Y261825D02*
X1325966D01*
G01X1316027Y241428D02*
X1396567D01*
G01X1313480Y238881D02*
X1316027Y241428D01*
G01X1313480Y238450D02*
Y238881D01*
G01X1310749Y235719D02*
X1313480Y238450D01*
G01X1282759Y235719D02*
X1310749D01*
G01X1280574Y237904D02*
X1282759Y235719D01*
G01X1321036Y251636D02*
X1396679D01*
G01X1308493Y264179D02*
X1321036Y251636D01*
G01X1300516Y224763D02*
X1395315D01*
G01X1297679Y227600D02*
X1300516Y224763D01*
G01X1293021Y227600D02*
X1297679D01*
G01X1292119Y226698D02*
X1293021Y227600D01*
G01X1282367Y226698D02*
X1292119D01*
G01X1281319Y225650D02*
X1282367Y226698D01*
G01X1281582Y268796D02*
X1281230Y269148D01*
G01X1281582Y266367D02*
Y268796D01*
G01X1281934Y266015D02*
X1281582Y266367D01*
G01X1283082Y266015D02*
X1281934D01*
G01X1283434Y266367D02*
X1283082Y266015D01*
G01X1283434Y268796D02*
Y266367D01*
G01X1283786Y269148D02*
X1283434Y268796D01*
G01X1284934Y269148D02*
X1283786D01*
G01X1285286Y268796D02*
X1284934Y269148D01*
G01X1285286Y266367D02*
Y268796D01*
G01X1285638Y266015D02*
X1285286Y266367D01*
G01X1286786Y266015D02*
X1285638D01*
G01X1287138Y266367D02*
X1286786Y266015D01*
G01X1287138Y268796D02*
Y266367D01*
G01X1287490Y269148D02*
X1287138Y268796D01*
G01X1288638Y269148D02*
X1287490D01*
G01X1288990Y268796D02*
X1288638Y269148D01*
G01X1288990Y266367D02*
Y268796D01*
G01X1289342Y266015D02*
X1288990Y266367D01*
G01X1290490Y266015D02*
X1289342D01*
G01X1290842Y266367D02*
X1290490Y266015D01*
G01X1290842Y268796D02*
Y266367D01*
G01X1291194Y269148D02*
X1290842Y268796D01*
G01X1292342Y269148D02*
X1291194D01*
G01X1292694Y268796D02*
X1292342Y269148D01*
G01X1292694Y266367D02*
Y268796D01*
G01X1293046Y266015D02*
X1292694Y266367D01*
G01X1294194Y266015D02*
X1293046D01*
G01X1294546Y266367D02*
X1294194Y266015D01*
G01X1294546Y268796D02*
Y266367D01*
G01X1294898Y269148D02*
X1294546Y268796D01*
G01X1296046Y269148D02*
X1294898D01*
G01X1296398Y268796D02*
X1296046Y269148D01*
G01X1296398Y266367D02*
Y268796D01*
G01X1296750Y266015D02*
X1296398Y266367D01*
G01X1302049Y266015D02*
X1296750D01*
G01X1302401Y266367D02*
X1302049Y266015D01*
G01X1302401Y268772D02*
Y266367D01*
G01X1302753Y269124D02*
X1302401Y268772D01*
G01X1303901Y269124D02*
X1302753D01*
G01X1304253Y268772D02*
X1303901Y269124D01*
G01X1304253Y266367D02*
Y268772D01*
G01X1304605Y266015D02*
X1304253Y266367D01*
G01X1308112Y266015D02*
X1304605D01*
G01X1321632Y252495D02*
X1308112Y266015D01*
G01X1396884Y252495D02*
X1321632D01*
G01X1282589Y221142D02*
X1282524Y221207D01*
G01X1284851Y221142D02*
X1282589D01*
G01X1284916Y221207D02*
X1284851Y221142D01*
G01X1400007Y221207D02*
X1284916D01*
G01X1299700Y298557D02*
X1298672Y299585D01*
G01X1326105Y290795D02*
Y287795D01*
G01X1324800Y292100D02*
X1326105Y290795D01*
G01X1313580Y292100D02*
X1324800D01*
G01X1309738Y295942D02*
X1313580Y292100D01*
G01X1303997Y295942D02*
X1309738D01*
G01X1303421Y295366D02*
X1303997Y295942D01*
G01X1308887Y285015D02*
X1308552Y285350D01*
G01X1299735Y301298D02*
X1298974Y300537D01*
G01X1313237Y289253D02*
X1311785Y287801D01*
G01X1318247Y289253D02*
X1313237D01*
G01X1319000Y288500D02*
X1318247Y289253D01*
G01X1321983Y288500D02*
X1319000D01*
G01X1323688Y290205D02*
X1321983Y288500D01*
G01X1312133Y305500D02*
X1316600D01*
G01X1305886Y311747D02*
X1312133Y305500D01*
G01X1310455Y311498D02*
X1305751Y312759D01*
G01X1313869Y309488D02*
X1310455Y311498D01*
G01X1317427Y307393D02*
X1313869Y309488D01*
G01X1321700Y303120D02*
X1317427Y307393D01*
G01X1321700Y302236D02*
Y303120D01*
G01X1321724Y302212D02*
X1321700Y302236D01*
G01X1321724Y297414D02*
Y302212D01*
G01X1327610Y291528D02*
X1321724Y297414D01*
G01X1327610Y288418D02*
Y291528D01*
G01X1334078Y281950D02*
X1327610Y288418D01*
G01X1363750Y281950D02*
X1334078D01*
G01X1303322Y309441D02*
X1302506Y310257D01*
G01X1303380Y309441D02*
X1303322D01*
G01X1304139Y294313D02*
X1303940Y294114D01*
G01X1305558Y294313D02*
X1304139D01*
G01X1312842Y290205D02*
X1311390Y288753D01*
G01X1319888Y290205D02*
X1312842D01*
G01X1303529Y300935D02*
X1300059Y304405D01*
G01X1307439Y300935D02*
X1303529D01*
G01X1313674Y294700D02*
X1307439Y300935D01*
G01X1321600Y294700D02*
X1313674D01*
G01X1292039Y296651D02*
X1290459Y298231D01*
G01X1300151Y296651D02*
X1292039D01*
G01X1302526Y299026D02*
X1300151Y296651D01*
G01X1305519Y299026D02*
X1302526D01*
G01X1306290Y298255D02*
X1305519Y299026D01*
G01X1303361Y300025D02*
X1300133Y303253D01*
G01X1307285Y300025D02*
X1303361D01*
G01X1314458Y292852D02*
X1307285Y300025D01*
G01X1325122Y292852D02*
X1314458D01*
G01X1326857Y291117D02*
X1325122Y292852D01*
G01X1326857Y288107D02*
Y291117D01*
G01X1334764Y280200D02*
X1326857Y288107D01*
G01X1364400Y280200D02*
X1334764D01*
G01X1310983Y463894D02*
Y472446D01*
G01X1308055Y460966D02*
X1310983Y463894D01*
G01X1308055Y456870D02*
Y460966D01*
G01X1306357Y455172D02*
X1308055Y456870D01*
G01X1296276Y455172D02*
X1306357D01*
G01X1286831Y445727D02*
X1296276Y455172D01*
G01X1286831Y443058D02*
Y445727D01*
G01X1331502Y461970D02*
X1337041Y467509D01*
G01X1325388Y461970D02*
X1331502D01*
G01X1323815Y463543D02*
X1325388Y461970D01*
G01X1310231Y464206D02*
Y472758D01*
G01X1307303Y461278D02*
X1310231Y464206D01*
G01X1307303Y457182D02*
Y461278D01*
G01X1306045Y455924D02*
X1307303Y457182D01*
G01X1295964Y455924D02*
X1306045D01*
G01X1285255Y445215D02*
X1295964Y455924D01*
G01X1285255Y440576D02*
Y445215D01*
G01X1285769Y440062D02*
X1285255Y440576D01*
G01X1332055Y460061D02*
X1338751Y466757D01*
G01X1322349Y460061D02*
X1332055D01*
G01X1321172Y461238D02*
X1322349Y460061D01*
G01X1321172Y464474D02*
Y461238D01*
G01X1298807Y418900D02*
X1288155Y408248D01*
G01X1316820Y418900D02*
X1298807D01*
G01X1299512Y417198D02*
X1288860Y406546D01*
G01X1317618Y417198D02*
X1299512D01*
G01X1319320Y418900D02*
X1317618Y417198D01*
G01X1311735Y455600D02*
Y472134D01*
G01X1310387Y454252D02*
X1311735Y455600D01*
G01X1297585Y454252D02*
X1310387D01*
G01X1288671Y445338D02*
X1297585Y454252D01*
G01X1316024Y420604D02*
X1316820Y421400D01*
G01X1298104Y420604D02*
X1316024D01*
G01X1287450Y409950D02*
X1298104Y420604D01*
G01X1344005Y466005D02*
X1341528Y463528D01*
G01X1322321Y480065D02*
X1352834D01*
G01X1322320Y480064D02*
X1322321Y480065D01*
G01X1318809Y480064D02*
X1322320D01*
G01X1318571Y479826D02*
X1318809Y480064D01*
G01X1318363Y479826D02*
X1318571D01*
G01X1310983Y472446D02*
X1318363Y479826D01*
G01X1337041Y467509D02*
X1360106D01*
G01X1318290Y480817D02*
X1353429D01*
G01X1310231Y472758D02*
X1318290Y480817D01*
G01X1338751Y466757D02*
X1360418D01*
G01X1319121Y479312D02*
X1351721D01*
G01X1318883Y479074D02*
X1319121Y479312D01*
G01X1318675Y479074D02*
X1318883D01*
G01X1311735Y472134D02*
X1318675Y479074D01*
G01X1308273Y523527D02*
Y535857D01*
G01X1310950Y520850D02*
X1308273Y523527D01*
G01X1310950Y517300D02*
Y520850D01*
G01X1298632Y504982D02*
X1310950Y517300D01*
G01X1286282Y504982D02*
X1298632D01*
G01X1282811Y501511D02*
X1286282Y504982D01*
G01X1280600Y580500D02*
Y589300D01*
G01X1281800Y579300D02*
X1280600Y580500D01*
G01X1283200Y579300D02*
X1281800D01*
G01X1285600Y581700D02*
X1283200Y579300D01*
G01X1290500Y581700D02*
X1285600D01*
G01X1295800Y576400D02*
X1290500Y581700D01*
G01X1295800Y558700D02*
Y576400D01*
G01X1298400Y556100D02*
X1295800Y558700D01*
G01X1298400Y550871D02*
Y556100D01*
G01X1300871Y548400D02*
X1298400Y550871D01*
G01X1314716Y548400D02*
X1300871D01*
G01X1318216Y544900D02*
X1314716Y548400D01*
G01X1321297Y544900D02*
X1318216D01*
G01X1322457Y543740D02*
X1321297Y544900D01*
G01X1328449Y543740D02*
X1322457D01*
G01X1329093Y544384D02*
X1328449Y543740D01*
G01X1381765Y544384D02*
X1329093D01*
G01X1290400Y559100D02*
X1281600D01*
G01X1295500Y554000D02*
X1290400Y559100D01*
G01X1295500Y552460D02*
Y554000D01*
G01X1303660Y544300D02*
X1295500Y552460D01*
G01X1315200Y544300D02*
X1303660D01*
G01X1316100Y543400D02*
X1315200Y544300D01*
G01X1296252Y580522D02*
Y613112D01*
G01X1295090Y579360D02*
X1296252Y580522D01*
G01X1288100Y562000D02*
X1286787D01*
G01X1295500Y583370D02*
Y612800D01*
G01X1293290Y581160D02*
X1295500Y583370D01*
G01X1300037Y544093D02*
X1283376D01*
G01X1308273Y535857D02*
X1300037Y544093D01*
G01X1300432Y545045D02*
X1283771D01*
G01X1307308Y538169D02*
X1300432Y545045D01*
G01X1316769Y538169D02*
X1307308D01*
G01X1318500Y539900D02*
X1316769Y538169D01*
G01X1296712Y621900D02*
X1373600D01*
G01X1294552Y619740D02*
X1296712Y621900D01*
G01X1294552Y614812D02*
Y619740D01*
G01X1296252Y613112D02*
X1294552Y614812D01*
G01X1296600Y622852D02*
X1373995D01*
G01X1293800Y620052D02*
X1296600Y622852D01*
G01X1293800Y614500D02*
Y620052D01*
G01X1295500Y612800D02*
X1293800Y614500D01*
G01X1403396Y16055D02*
X1405246Y17905D01*
G01X1403396Y13296D02*
Y16055D01*
G01X1400100Y10000D02*
X1403396Y13296D01*
G01X1402600Y10000D02*
X1404348Y11748D01*
G01X1354368Y76045D02*
X1343829D01*
G01X1357976Y79653D02*
X1354368Y76045D01*
G01X1357976Y82648D02*
Y79653D01*
G01X1358328Y83000D02*
X1357976Y82648D01*
G01X1359500Y83000D02*
X1358328D01*
G01X1343340Y74000D02*
X1351488D01*
G01X1397080Y94100D02*
X1402050Y99070D01*
G01X1387905Y94100D02*
X1397080D01*
G01X1378993Y85188D02*
X1387905Y94100D01*
G01X1374751Y85188D02*
X1378993D01*
G01X1373700Y84137D02*
X1374751Y85188D01*
G01X1373700Y75200D02*
Y84137D01*
G01X1376032Y72868D02*
X1373700Y75200D01*
G01X1376032Y60448D02*
Y72868D01*
G01X1365640Y50056D02*
X1376032Y60448D01*
G01X1347500Y83092D02*
Y83000D01*
G01X1345730Y84862D02*
X1347500Y83092D01*
G01X1353973Y76997D02*
X1343434D01*
G01X1357024Y80048D02*
X1353973Y76997D01*
G01X1357024Y82648D02*
Y80048D01*
G01X1356672Y83000D02*
X1357024Y82648D01*
G01X1355500Y83000D02*
X1356672D01*
G01X1398252Y138476D02*
X1427737Y108991D01*
G01X1398853Y155604D02*
X1391152Y163305D01*
G01X1404248Y155604D02*
X1398853D01*
G01X1430019Y108837D02*
X1398876Y139980D01*
G01X1401321Y126400D02*
X1399400D01*
G01X1402770Y124951D02*
X1401321Y126400D01*
G01X1402770Y120111D02*
Y124951D01*
G01X1402624Y119965D02*
X1402770Y120111D01*
G01X1402624Y118547D02*
Y119965D01*
G01X1421400Y99771D02*
X1402624Y118547D01*
G01X1395615Y145757D02*
X1389452Y151920D01*
G01X1405780Y145757D02*
X1395615D01*
G01X1396080Y146509D02*
X1405468D01*
G01X1389917Y152672D02*
X1396080Y146509D01*
G01X1425175Y108859D02*
X1397462Y136572D01*
G01X1398229Y154100D02*
X1404910D01*
G01X1390753Y161576D02*
X1398229Y154100D01*
G01X1398541Y154852D02*
X1390840Y162553D01*
G01X1404598Y154852D02*
X1398541D01*
G01X1396200Y118500D02*
X1396780Y119080D01*
G01X1396200Y115900D02*
Y118500D01*
G01X1397400Y114700D02*
X1396200Y115900D01*
G01X1398331Y114700D02*
X1397400D01*
G01X1402050Y110981D02*
X1398331Y114700D01*
G01X1402050Y99070D02*
Y110981D01*
G01X1388499Y143830D02*
X1411689D01*
G01X1385753Y146576D02*
X1388499Y143830D01*
G01X1431218Y108822D02*
X1399236Y140804D01*
G01X1399594Y141556D02*
X1431971Y109179D01*
G01X1389223Y144605D02*
X1406913D01*
G01X1386500Y147328D02*
X1389223Y144605D01*
G01X1400900Y115499D02*
X1418300Y98099D01*
G01X1400900Y119871D02*
Y115499D01*
G01X1401876Y120847D02*
X1400900Y119871D01*
G01X1401876Y123624D02*
Y120847D01*
G01X1401200Y124300D02*
X1401876Y123624D01*
G01X1398987Y148013D02*
X1404844D01*
G01X1390200Y156800D02*
X1398987Y148013D01*
G01X1396264Y153300D02*
X1391259Y158305D01*
G01X1405174Y153300D02*
X1396264D01*
G01X1403000Y116300D02*
X1420000Y99300D01*
G01X1402500Y116300D02*
X1403000D01*
G01X1395952Y152548D02*
X1390948Y157552D01*
G01X1405486Y152548D02*
X1395952D01*
G01X1396984Y135420D02*
X1424022Y108382D01*
G01X1433122Y109158D02*
X1399972Y142308D01*
G01X1397940Y137724D02*
X1426785Y108879D01*
G01X1398600Y116500D02*
X1416700Y98400D01*
G01X1398564Y139228D02*
X1429066Y108726D01*
G01X1396511Y147602D02*
X1390688Y153424D01*
G01X1397026Y147261D02*
X1396511Y147602D01*
G01X1405156Y147261D02*
X1397026D01*
G01X1342100Y212403D02*
Y209038D01*
G01X1343497Y213800D02*
X1342100Y212403D01*
G01X1370636Y213800D02*
X1343497D01*
G01X1377248Y207188D02*
X1370636Y213800D01*
G01X1398377Y207188D02*
X1377248D01*
G01X1401618Y210429D02*
X1398377Y207188D01*
G01X1417104Y210429D02*
X1401618D01*
G01X1402961Y200593D02*
X1406671Y204303D01*
G01X1380651Y200593D02*
X1402961D01*
G01X1369700Y211544D02*
X1380651Y200593D01*
G01X1366611Y211544D02*
X1369700D01*
G01X1361831Y206764D02*
X1366611Y211544D01*
G01X1345418Y206764D02*
X1361831D01*
G01X1396933Y213329D02*
Y215763D01*
G01X1393509Y209905D02*
X1396933Y213329D01*
G01X1381575Y209905D02*
X1393509D01*
G01X1374824Y216656D02*
X1381575Y209905D01*
G01X1401306Y211181D02*
X1415689D01*
G01X1398065Y207940D02*
X1401306Y211181D01*
G01X1377560Y207940D02*
X1398065D01*
G01X1370948Y214552D02*
X1377560Y207940D01*
G01X1343185Y214552D02*
X1370948D01*
G01X1367789Y208024D02*
Y209216D01*
G01X1365025Y205260D02*
X1367789Y208024D01*
G01X1346042Y205260D02*
X1365025D01*
G01X1398501Y168530D02*
X1414426D01*
G01X1398271Y168300D02*
X1398501Y168530D01*
G01X1377030Y206342D02*
X1403962D01*
G01X1370324Y213048D02*
X1377030Y206342D01*
G01X1343809Y213048D02*
X1370324D01*
G01X1342852Y212091D02*
X1343809Y213048D01*
G01X1342852Y208726D02*
Y212091D01*
G01X1382199Y211409D02*
X1374456Y219152D01*
G01X1388271Y211409D02*
X1382199D01*
G01X1394967Y218105D02*
X1388271Y211409D01*
G01X1399745Y216996D02*
X1398636Y218105D01*
G01X1414232Y216996D02*
X1399745D01*
G01X1400057Y217748D02*
X1411848D01*
G01X1398948Y218857D02*
X1400057Y217748D01*
G01X1387863Y212161D02*
X1394559Y218857D01*
G01X1382511Y212161D02*
X1387863D01*
G01X1374768Y219904D02*
X1382511Y212161D01*
G01X1396276Y165324D02*
X1394200Y167400D01*
G01X1401783Y165324D02*
X1396276D01*
G01X1402020Y165561D02*
X1401783Y165324D01*
G01X1399097Y216244D02*
X1414544D01*
G01X1397988Y217353D02*
X1399097Y216244D01*
G01X1395285Y217353D02*
X1397988D01*
G01X1388589Y210657D02*
X1395285Y217353D01*
G01X1381887Y210657D02*
X1388589D01*
G01X1374144Y218400D02*
X1381887Y210657D01*
G01X1401203Y212142D02*
X1413890D01*
G01X1397754Y208693D02*
X1401203Y212142D01*
G01X1377871Y208693D02*
X1397754D01*
G01X1371260Y215304D02*
X1377871Y208693D01*
G01X1396551Y163985D02*
X1404307D01*
G01X1393888Y166648D02*
X1396551Y163985D01*
G01X1402598Y201560D02*
X1405825Y204787D01*
G01X1380748Y201560D02*
X1402598D01*
G01X1370012Y212296D02*
X1380748Y201560D01*
G01X1348713Y212296D02*
X1370012D01*
G01X1346123Y209706D02*
X1348713Y212296D01*
G01X1346123Y208533D02*
Y209706D01*
G01X1362143Y206012D02*
X1345730D01*
G01X1366923Y210792D02*
X1362143Y206012D01*
G01X1369039Y210792D02*
X1366923D01*
G01X1380081Y199750D02*
X1369039Y210792D01*
G01X1403489Y199750D02*
X1380081D01*
G01X1408247Y204508D02*
X1403489Y199750D01*
G01X1398558Y253647D02*
X1399852Y252353D01*
G01X1393159Y230301D02*
X1391443Y228585D01*
G01X1398095Y230301D02*
X1393159D01*
G01X1400100Y232306D02*
X1398095Y230301D01*
G01X1400100Y233653D02*
Y232306D01*
G01X1399978Y233775D02*
X1400100Y233653D01*
G01X1397843Y248344D02*
X1396055Y250132D01*
G01X1401573Y248344D02*
X1397843D01*
G01X1404384Y251155D02*
X1401573Y248344D01*
G01X1397531Y247592D02*
X1395743Y249380D01*
G01X1401885Y247592D02*
X1397531D01*
G01X1404426Y250133D02*
X1401885Y247592D01*
G01X1379848Y279448D02*
X1386384Y285984D01*
G01X1399836Y265080D02*
X1412726D01*
G01X1390907Y256151D02*
X1399836Y265080D01*
G01X1388518Y230789D02*
X1387616Y229887D01*
G01X1398926Y276293D02*
X1386362Y263729D01*
G01X1398926Y281582D02*
Y276293D01*
G01X1393788Y229049D02*
X1392073Y227333D01*
G01X1398251Y229049D02*
X1393788D01*
G01X1398600Y228700D02*
X1398251Y229049D01*
G01X1402200Y262669D02*
X1424770D01*
G01X1391426Y254899D02*
X1402200Y262669D01*
G01X1405878Y278934D02*
X1388017Y261073D01*
G01X1396907Y246088D02*
X1395119Y247876D01*
G01X1401885Y246088D02*
X1396907D01*
G01X1401886Y246087D02*
X1401885Y246088D01*
G01X1402508Y246087D02*
X1401886D01*
G01X1405050Y248629D02*
X1402508Y246087D01*
G01X1398636Y218105D02*
X1394967D01*
G01X1394559Y218857D02*
X1398948D01*
G01X1398155Y249096D02*
X1396367Y250884D01*
G01X1401261Y249096D02*
X1398155D01*
G01X1404134Y251969D02*
X1401261Y249096D01*
G01X1402200Y230070D02*
X1401565Y229435D01*
G01X1402200Y239200D02*
Y230070D01*
G01X1398720Y242680D02*
X1402200Y239200D01*
G01X1398761Y267642D02*
X1409128D01*
G01X1389731Y258612D02*
X1398761Y267642D01*
G01X1398700Y225200D02*
X1406900D01*
G01X1397011Y223511D02*
X1398700Y225200D01*
G01X1399600Y223600D02*
X1398359Y222359D01*
G01X1394881Y226997D02*
X1393965Y226081D01*
G01X1399119Y266780D02*
X1409486D01*
G01X1389999Y257660D02*
X1399119Y266780D01*
G01X1402197Y246840D02*
X1404738Y249381D01*
G01X1397219Y246840D02*
X1402197D01*
G01X1395431Y248628D02*
X1397219Y246840D01*
G01X1401295Y277598D02*
Y281442D01*
G01X1386674Y262977D02*
X1401295Y277598D01*
G01X1404286Y278406D02*
X1387705Y261825D01*
G01X1400057Y236274D02*
X1400066D01*
G01X1400057Y237938D02*
Y236274D01*
G01X1396567Y241428D02*
X1400057Y237938D01*
G01X1400949Y249848D02*
X1403994Y252893D01*
G01X1398467Y249848D02*
X1400949D01*
G01X1396679Y251636D02*
X1398467Y249848D01*
G01X1396593Y226041D02*
X1397211D01*
G01X1395315Y224763D02*
X1396593Y226041D01*
G01X1398779Y250600D02*
X1396884Y252495D01*
G01X1400599Y250600D02*
X1398779D01*
G01X1401527Y251528D02*
X1400599Y250600D01*
G01X1401527Y253728D02*
Y251528D01*
G01X1401879Y254080D02*
X1401527Y253728D01*
G01X1416548Y254080D02*
X1401879D01*
G01X1398065Y255932D02*
X1416548D01*
G01X1397652Y256345D02*
X1398065Y255932D01*
G01X1397652Y257432D02*
Y256345D01*
G01X1398004Y257784D02*
X1397652Y257432D01*
G01X1403777Y257784D02*
X1398004D01*
G01X1402400Y223600D02*
X1400007Y221207D01*
G01X1402774Y282446D02*
X1403816Y283488D01*
G01X1401439Y282446D02*
X1402774D01*
G01X1400516Y283369D02*
X1401439Y282446D01*
G01X1400516Y284779D02*
Y283369D01*
G01X1399311Y285984D02*
X1400516Y284779D01*
G01X1386384Y285984D02*
X1399311D01*
G01X1367635Y285835D02*
X1363750Y281950D01*
G01X1384371Y285835D02*
X1367635D01*
G01X1385639Y287103D02*
X1384371Y285835D01*
G01X1399310Y287103D02*
X1385639D01*
G01X1402092Y284321D02*
X1399310Y287103D01*
G01X1402092Y284022D02*
Y284321D01*
G01X1398714Y284023D02*
X1398347D01*
G01X1401295Y281442D02*
X1398714Y284023D01*
G01X1368200Y284000D02*
X1364400Y280200D01*
G01X1363501Y462537D02*
X1469067D01*
G01X1362560Y463478D02*
X1363501Y462537D01*
G01X1360468Y463615D02*
X1361907Y465054D01*
G01X1346739Y463615D02*
X1360468D01*
G01X1344090Y463630D02*
X1345713Y465253D01*
G01X1358562Y473118D02*
X1443832D01*
G01X1358009Y472565D02*
X1358562Y473118D01*
G01X1353809Y472565D02*
X1358009D01*
G01X1352424Y473950D02*
X1353809Y472565D01*
G01X1352424Y475405D02*
Y473950D01*
G01X1350932Y476897D02*
X1352424Y475405D01*
G01X1347546Y476897D02*
X1350932D01*
G01X1402756Y475845D02*
X1412234Y485323D01*
G01X1357054Y475845D02*
X1402756D01*
G01X1352834Y480065D02*
X1357054Y475845D01*
G01X1360659Y468062D02*
X1446495D01*
G01X1360106Y467509D02*
X1360659Y468062D01*
G01X1402161Y476597D02*
X1411839Y486275D01*
G01X1357649Y476597D02*
X1402161D01*
G01X1353429Y480817D02*
X1357649Y476597D01*
G01X1358957Y472166D02*
X1444227D01*
G01X1358404Y471613D02*
X1358957Y472166D01*
G01X1353414Y471613D02*
X1358404D01*
G01X1350500Y474527D02*
X1353414Y471613D01*
G01X1350500Y475100D02*
Y474527D01*
G01X1360971Y467310D02*
X1446807D01*
G01X1360418Y466757D02*
X1360971Y467310D01*
G01X1354462Y474141D02*
X1443508D01*
G01X1355940Y475093D02*
X1443113D01*
G01X1351721Y479312D02*
X1355940Y475093D01*
G01X1361907Y465054D02*
X1448006D01*
G01X1361595Y465806D02*
X1447431D01*
G01X1361042Y465253D02*
X1361595Y465806D01*
G01X1345713Y465253D02*
X1361042D01*
G01X1360181Y469214D02*
X1446017D01*
G01X1359628Y468661D02*
X1360181Y469214D01*
G01X1351476Y468661D02*
X1359628D01*
G01X1347196Y472941D02*
X1351476Y468661D01*
G01X1360730Y466005D02*
X1344005D01*
G01X1361283Y466558D02*
X1360730Y466005D01*
G01X1447119Y466558D02*
X1361283D01*
G01X1382331Y543818D02*
X1381765Y544384D01*
G01X1390170Y546549D02*
X1387907Y544286D01*
G01X1391551Y546549D02*
X1390170D01*
G01X1396843Y541257D02*
X1391551Y546549D01*
G01X1407357Y541257D02*
X1396843D01*
G01X1388973Y552566D02*
X1414465D01*
G01X1382719Y546312D02*
X1388973Y552566D01*
G01X1365380Y546312D02*
X1382719D01*
G01X1365028Y546664D02*
X1365380Y546312D01*
G01X1365028Y547954D02*
Y546664D01*
G01X1389309Y551614D02*
X1414860D01*
G01X1383161Y545466D02*
X1389309Y551614D01*
G01X1365016Y545466D02*
X1383161D01*
G01X1362528Y547954D02*
X1365016Y545466D01*
G01X1398820Y597080D02*
X1407914D01*
G01X1390800Y605100D02*
X1398820Y597080D01*
G01X1390800Y614300D02*
Y605100D01*
G01X1387700Y617400D02*
X1390800Y614300D01*
G01X1378100Y617400D02*
X1387700D01*
G01X1373600Y621900D02*
X1378100Y617400D01*
G01X1399215Y598032D02*
X1408309D01*
G01X1391752Y605495D02*
X1399215Y598032D01*
G01X1391752Y614695D02*
Y605495D01*
G01X1388095Y618352D02*
X1391752Y614695D01*
G01X1378495Y618352D02*
X1388095D01*
G01X1373995Y622852D02*
X1378495Y618352D01*
G01X1458754Y34812D02*
X1465772Y27794D01*
G01X1439807Y9404D02*
X1486093D01*
G01X1431307Y17904D02*
X1439807Y9404D01*
G01X1406035Y17904D02*
X1431307D01*
G01X1406034Y17905D02*
X1406035Y17904D01*
G01X1405246Y17905D02*
X1406034D01*
G01X1468325Y29298D02*
X1463515Y34108D01*
G01X1453151Y32173D02*
Y36526D01*
G01X1463320Y22004D02*
X1453151Y32173D01*
G01X1507286Y22004D02*
X1463320D01*
G01X1426058Y9100D02*
X1410600D01*
G01X1434658Y500D02*
X1426058Y9100D01*
G01X1502163Y500D02*
X1434658D01*
G01X1465264Y25608D02*
X1456650Y34222D01*
G01X1506808Y25608D02*
X1465264D01*
G01X1439412Y8452D02*
X1486488D01*
G01X1430912Y16952D02*
X1439412Y8452D01*
G01X1405640Y16952D02*
X1430912D01*
G01X1404348Y15660D02*
X1405640Y16952D01*
G01X1404348Y11748D02*
Y15660D01*
G01X1447988Y15448D02*
X1496888D01*
G01X1423888Y39548D02*
X1447988Y15448D01*
G01X1453793Y18548D02*
X1425081Y47260D01*
G01X1498752Y18548D02*
X1453793D01*
G01X1439100Y7700D02*
X1486800D01*
G01X1430600Y16200D02*
X1439100Y7700D01*
G01X1405952Y16200D02*
X1430600D01*
G01X1405100Y15348D02*
X1405952Y16200D01*
G01X1405100Y10000D02*
Y15348D01*
G01X1460999Y19700D02*
X1499500D01*
G01X1418300Y62399D02*
X1460999Y19700D01*
G01X1454345Y32609D02*
Y37456D01*
G01X1463798Y23156D02*
X1454345Y32609D01*
G01X1507764Y23156D02*
X1463798D01*
G01X1462842Y20852D02*
X1500648D01*
G01X1420000Y63694D02*
X1462842Y20852D01*
G01X1464934Y24308D02*
X1508242D01*
G01X1455498Y33744D02*
X1464934Y24308D01*
G01X1448300Y16200D02*
X1497200D01*
G01X1424200Y40300D02*
X1448300Y16200D01*
G01X1457802Y34700D02*
X1465460Y27042D01*
G01X1452716Y17396D02*
X1498274D01*
G01X1416700Y53412D02*
X1452716Y17396D01*
G01X1462563Y33996D02*
X1468013Y28546D01*
G01X1458754Y40446D02*
Y34812D01*
G01X1427737Y71463D02*
X1458754Y40446D01*
G01X1427737Y108991D02*
Y71463D01*
G01X1461944Y84768D02*
X1499914Y46798D01*
G01X1461944Y104800D02*
Y84768D01*
G01X1430019Y72381D02*
Y108837D01*
G01X1463515Y38885D02*
X1430019Y72381D01*
G01X1463515Y34108D02*
Y38885D01*
G01X1421400Y68277D02*
Y99771D01*
G01X1453151Y36526D02*
X1421400Y68277D01*
G01X1448933Y83272D02*
X1470862Y61343D01*
G01X1448933Y114791D02*
Y83272D01*
G01X1425174Y70663D02*
Y107904D01*
G01X1456650Y39187D02*
X1425174Y70663D01*
G01X1456650Y34222D02*
Y39187D01*
G01X1447781Y81808D02*
X1455889Y73700D01*
G01X1447781Y114206D02*
Y81808D01*
G01X1455889Y73700D02*
X1468652Y60937D01*
G01X1421988Y39548D02*
X1423888D01*
G01X1418600Y42936D02*
X1421988Y39548D01*
G01X1418600Y43714D02*
Y42936D01*
G01X1416837Y45477D02*
X1418600Y43714D01*
G01X1463848Y85558D02*
X1500704Y48702D01*
G01X1463848Y105590D02*
Y85558D01*
G01X1460792Y84290D02*
X1499436Y45646D01*
G01X1460792Y84292D02*
Y84290D01*
G01X1458942Y86142D02*
X1460792Y84292D01*
G01X1458942Y102790D02*
Y86142D01*
G01X1467498Y59473D02*
X1453221Y73750D01*
G01X1446351Y80620D02*
X1453221Y73750D01*
G01X1446351Y115469D02*
Y80620D01*
G01X1425081Y47260D02*
Y48412D01*
G01X1431218Y72812D02*
Y108822D01*
G01X1464670Y39360D02*
X1431218Y72812D01*
G01X1464670Y34017D02*
Y39360D01*
G01X1468637Y30050D02*
X1464670Y34017D01*
G01X1431971Y77713D02*
X1465979Y43705D01*
G01X1431971Y109179D02*
Y77713D01*
G01X1418300Y98099D02*
Y62399D01*
G01X1422870Y68931D02*
Y100530D01*
G01X1454345Y37456D02*
X1422870Y68931D01*
G01X1420000Y99300D02*
Y63694D01*
G01X1455498Y38709D02*
Y33744D01*
G01X1424022Y70185D02*
X1455498Y38709D01*
G01X1424022Y108382D02*
Y70185D01*
G01X1433122Y77626D02*
Y109158D01*
G01X1466746Y44002D02*
X1433122Y77626D01*
G01X1422300Y40300D02*
X1424200D01*
G01X1419352Y43248D02*
X1422300Y40300D01*
G01X1419352Y44492D02*
Y43248D01*
G01X1420337Y45477D02*
X1419352Y44492D01*
G01X1457802Y40051D02*
Y34700D01*
G01X1426785Y71068D02*
X1457802Y40051D01*
G01X1426785Y108879D02*
Y71068D01*
G01X1416700Y98400D02*
Y53412D01*
G01X1462563Y38490D02*
Y33996D01*
G01X1429066Y71987D02*
X1462563Y38490D01*
G01X1429066Y108726D02*
Y71987D01*
G01X1462896Y85163D02*
X1500309Y47750D01*
G01X1462896Y105195D02*
Y85163D01*
G01X1440571Y191927D02*
X1404248Y155604D01*
G01X1456290Y110454D02*
X1461944Y104800D01*
G01X1456290Y134804D02*
Y110454D01*
G01X1457849Y136363D02*
X1456290Y134804D01*
G01X1457849Y178372D02*
Y136363D01*
G01X1453830Y119688D02*
X1448933Y114791D01*
G01X1453830Y135321D02*
Y119688D01*
G01X1455545Y137036D02*
X1453830Y135321D01*
G01X1455545Y155515D02*
Y137036D01*
G01X1451880Y159180D02*
X1455545Y155515D01*
G01X1438375Y178352D02*
X1405780Y145757D01*
G01X1465296Y131835D02*
X1466313Y132852D01*
G01X1465296Y114850D02*
Y131835D01*
G01X1472191Y107955D02*
X1465296Y114850D01*
G01X1415855Y138750D02*
X1451590D01*
G01X1411545Y143060D02*
X1415855Y138750D01*
G01X1405468Y146509D02*
X1443326Y184367D01*
G01X1425175Y107905D02*
Y108859D01*
G01X1425174Y107904D02*
X1425175Y107905D01*
G01X1404910Y154100D02*
X1441233Y190423D01*
G01X1440921Y191175D02*
X1404598Y154852D01*
G01X1447780Y114207D02*
X1447781Y114206D01*
G01X1447780Y115161D02*
Y114207D01*
G01X1447781Y115162D02*
X1447780Y115161D01*
G01X1447781Y115269D02*
Y115162D01*
G01X1452678Y120166D02*
X1447781Y115269D01*
G01X1452678Y135799D02*
Y120166D01*
G01X1454393Y137514D02*
X1452678Y135799D01*
G01X1454393Y155037D02*
Y137514D01*
G01X1449600Y159830D02*
X1454393Y155037D01*
G01X1462440Y113665D02*
X1469333Y106772D01*
G01X1462440Y133020D02*
Y113665D01*
G01X1463457Y134037D02*
X1462440Y133020D01*
G01X1463457Y175763D02*
Y134037D01*
G01X1458612Y110826D02*
X1463848Y105590D01*
G01X1458612Y134432D02*
Y110826D01*
G01X1459753Y135573D02*
X1458612Y134432D01*
G01X1459753Y177582D02*
Y135573D01*
G01X1462305Y134515D02*
Y176241D01*
G01X1461164Y133374D02*
X1462305Y134515D01*
G01X1461164Y113311D02*
Y133374D01*
G01X1468181Y106294D02*
X1461164Y113311D01*
G01X1452232Y109500D02*
X1458942Y102790D01*
G01X1451526Y120644D02*
X1446351Y115469D01*
G01X1451526Y136277D02*
Y120644D01*
G01X1453241Y137992D02*
X1451526Y136277D01*
G01X1453241Y154559D02*
Y137992D01*
G01X1448133Y159667D02*
X1453241Y154559D01*
G01X1411689Y143830D02*
X1452712Y184853D01*
G01X1464344Y132230D02*
X1465361Y133247D01*
G01X1464344Y114455D02*
Y132230D01*
G01X1471238Y107561D02*
X1464344Y114455D01*
G01X1406913Y144605D02*
X1439508Y177200D01*
G01X1463392Y114060D02*
X1470285Y107167D01*
G01X1463392Y132625D02*
Y114060D01*
G01X1464409Y133642D02*
X1463392Y132625D01*
G01X1464409Y175368D02*
Y133642D01*
G01X1404844Y148013D02*
X1442705Y185874D01*
G01X1441545Y189671D02*
X1405174Y153300D01*
G01X1422870Y100530D02*
X1404200Y119200D01*
G01X1441857Y188919D02*
X1405486Y152548D01*
G01X1457660Y110431D02*
X1462896Y105195D01*
G01X1457660Y134827D02*
Y110431D01*
G01X1458801Y135968D02*
X1457660Y134827D01*
G01X1458801Y177977D02*
Y135968D01*
G01X1443017Y185122D02*
X1405156Y147261D01*
G01X1432251Y225576D02*
X1417104Y210429D01*
G01X1410238Y179989D02*
X1410237Y179990D01*
G01X1411484Y179989D02*
X1410238D01*
G01X1436117Y204622D02*
X1411484Y179989D01*
G01X1443719Y204622D02*
X1436117D01*
G01X1446344Y207247D02*
X1443719Y204622D01*
G01X1451705Y207247D02*
X1446344D01*
G01X1470950Y226492D02*
X1451705Y207247D01*
G01X1445329Y214961D02*
X1463346Y232976D01*
G01X1441026Y214961D02*
X1445329D01*
G01X1441025Y214960D02*
X1441026Y214961D01*
G01X1440403Y214960D02*
X1441025D01*
G01X1440402Y214961D02*
X1440403Y214960D01*
G01X1436654Y214961D02*
X1440402D01*
G01X1411793Y190100D02*
X1436654Y214961D01*
G01X1436342Y215713D02*
X1412009Y191380D01*
G01X1444864Y215713D02*
X1436342D01*
G01X1462992Y233841D02*
X1444864Y215713D01*
G01X1445330Y191927D02*
X1440571D01*
G01X1459269Y205866D02*
X1445330Y191927D01*
G01X1459269Y209491D02*
Y205866D01*
G01X1471057Y221279D02*
X1459269Y209491D01*
G01X1418099Y207846D02*
X1433573Y223320D01*
G01X1407594Y207846D02*
X1418099D01*
G01X1406671Y206923D02*
X1407594Y207846D01*
G01X1406671Y204303D02*
Y206923D01*
G01X1464132Y184655D02*
X1457849Y178372D01*
G01X1464132Y187233D02*
Y184655D01*
G01X1469560Y192661D02*
X1464132Y187233D01*
G01X1451880Y163500D02*
Y159180D01*
G01X1453000Y164620D02*
X1451880Y163500D01*
G01X1453000Y167520D02*
Y164620D01*
G01X1455745Y170265D02*
X1453000Y167520D01*
G01X1455745Y179245D02*
Y170265D01*
G01X1462028Y185528D02*
X1455745Y179245D01*
G01X1462028Y188126D02*
Y185528D01*
G01X1469100Y195198D02*
X1462028Y188126D01*
G01X1422196Y217688D02*
Y218052D01*
G01X1415689Y211181D02*
X1422196Y217688D01*
G01X1443332Y178352D02*
X1438375D01*
G01X1453758Y188778D02*
X1443332Y178352D01*
G01X1457497Y188778D02*
X1453758D01*
G01X1469888Y201169D02*
X1457497Y188778D01*
G01X1443073Y216812D02*
X1466089Y239826D01*
G01X1436231Y216812D02*
X1443073D01*
G01X1421249Y201830D02*
X1436231Y216812D01*
G01X1416371Y201830D02*
X1421249D01*
G01X1406674Y192133D02*
X1416371Y201830D01*
G01X1412804Y207094D02*
X1404708Y198998D01*
G01X1418553Y207094D02*
X1412804D01*
G01X1434027Y222568D02*
X1418553Y207094D01*
G01X1448126Y184367D02*
X1469136Y205377D01*
G01X1443326Y184367D02*
X1448126D01*
G01X1460773Y208867D02*
X1471681Y219775D01*
G01X1460773Y205242D02*
Y208867D01*
G01X1445954Y190423D02*
X1460773Y205242D01*
G01X1441233Y190423D02*
X1445954D01*
G01X1445642Y191175D02*
X1440921D01*
G01X1460021Y205554D02*
X1445642Y191175D01*
G01X1460021Y209179D02*
Y205554D01*
G01X1471369Y220527D02*
X1460021Y209179D01*
G01X1457765Y210115D02*
X1471720Y224070D01*
G01X1457765Y206491D02*
Y210115D01*
G01X1447907Y196633D02*
X1457765Y206491D01*
G01X1447907Y196632D02*
Y196633D01*
G01X1446984Y195709D02*
X1447907Y196632D01*
G01X1446983Y195709D02*
X1446984D01*
G01X1444705Y193431D02*
X1446983Y195709D01*
G01X1439327Y193431D02*
X1444705D01*
G01X1414426Y168530D02*
X1439327Y193431D01*
G01X1449600Y174400D02*
Y159830D01*
G01X1451214Y176014D02*
X1449600Y174400D01*
G01X1451365Y176014D02*
X1451214D01*
G01X1417367Y209350D02*
X1432841Y224824D01*
G01X1406970Y209350D02*
X1417367D01*
G01X1403962Y206342D02*
X1406970Y209350D01*
G01X1470387Y182693D02*
X1463457Y175763D01*
G01X1409448Y178085D02*
X1409447Y178086D01*
G01X1412274Y178085D02*
X1409448D01*
G01X1435689Y201500D02*
X1412274Y178085D01*
G01X1446360Y201500D02*
X1435689D01*
G01X1450671Y205811D02*
X1446360Y201500D01*
G01X1451333Y205811D02*
X1450671D01*
G01X1471097Y225575D02*
X1451333Y205811D01*
G01X1416059Y202582D02*
X1406762Y193285D01*
G01X1420937Y202582D02*
X1416059D01*
G01X1435919Y217564D02*
X1420937Y202582D01*
G01X1442761Y217564D02*
X1435919D01*
G01X1465988Y240789D02*
X1442761Y217564D01*
G01X1466036Y183865D02*
X1459753Y177582D01*
G01X1462305Y176241D02*
X1469235Y183171D01*
G01X1434836Y237600D02*
X1414232Y216996D01*
G01X1448133Y175973D02*
Y159667D01*
G01X1450532Y178372D02*
X1448133Y175973D01*
G01X1410550Y180741D02*
X1410549Y180742D01*
G01X1411172Y180741D02*
X1410550D01*
G01X1436203Y205772D02*
X1411172Y180741D01*
G01X1440131Y205772D02*
X1436203D01*
G01X1442358Y207999D02*
X1440131Y205772D01*
G01X1451298Y207999D02*
X1442358D01*
G01X1464835Y221536D02*
X1451298Y207999D01*
G01X1411848Y217748D02*
X1432600Y238500D01*
G01X1414557Y204838D02*
X1405661Y195942D01*
G01X1420001Y204838D02*
X1414557D01*
G01X1435410Y220247D02*
X1420001Y204838D01*
G01X1409926Y179237D02*
X1409925Y179238D01*
G01X1411796Y179237D02*
X1409926D01*
G01X1435825Y203266D02*
X1411796Y179237D01*
G01X1444700Y203266D02*
X1435825D01*
G01X1447079Y205645D02*
X1444700Y203266D01*
G01X1447999Y205645D02*
X1447079D01*
G01X1460524Y188778D02*
X1473165Y201419D01*
G01X1460524Y186220D02*
Y188778D01*
G01X1459157Y184853D02*
X1460524Y186220D01*
G01X1452712Y184853D02*
X1459157D01*
G01X1465361Y174973D02*
X1472291Y181903D01*
G01X1450725Y209151D02*
X1461124Y219550D01*
G01X1441880Y209151D02*
X1450725D01*
G01X1439653Y206924D02*
X1441880Y209151D01*
G01X1435725Y206924D02*
X1439653D01*
G01X1410695Y181894D02*
X1435725Y206924D01*
G01X1458903Y187704D02*
X1458908Y187699D01*
G01X1458903Y188543D02*
Y187704D01*
G01X1471609Y201249D02*
X1458903Y188543D01*
G01X1458835Y187626D02*
X1458908Y187699D01*
G01X1454326Y187626D02*
X1458835D01*
G01X1443900Y177200D02*
X1454326Y187626D01*
G01X1439508Y177200D02*
X1443900D01*
G01X1471339Y182298D02*
X1464409Y175368D01*
G01X1414245Y205590D02*
X1405349Y196694D01*
G01X1419689Y205590D02*
X1414245D01*
G01X1435098Y220999D02*
X1419689Y205590D01*
G01X1447505Y185874D02*
X1467543Y205912D01*
G01X1442705Y185874D02*
X1447505D01*
G01X1446266Y189671D02*
X1441545D01*
G01X1461525Y204930D02*
X1446266Y189671D01*
G01X1461525Y208555D02*
Y204930D01*
G01X1471993Y219023D02*
X1461525Y208555D01*
G01X1420625Y203334D02*
X1435870Y218579D01*
G01X1415181Y203334D02*
X1420625D01*
G01X1406284Y194437D02*
X1415181Y203334D01*
G01X1414544Y216244D02*
X1430700Y232400D01*
G01X1446578Y188919D02*
X1441857D01*
G01X1462277Y204618D02*
X1446578Y188919D01*
G01X1462277Y208243D02*
Y204618D01*
G01X1472305Y218271D02*
X1462277Y208243D01*
G01X1414869Y204086D02*
X1405972Y195189D01*
G01X1420313Y204086D02*
X1414869D01*
G01X1435558Y219331D02*
X1420313Y204086D01*
G01X1413890Y212142D02*
X1421449Y219701D01*
G01X1413557Y206342D02*
X1405061Y197846D01*
G01X1419141Y206342D02*
X1413557D01*
G01X1434550Y221751D02*
X1419141Y206342D01*
G01X1437132Y213809D02*
X1412127Y188804D01*
G01X1439924Y213809D02*
X1437132D01*
G01X1439925Y213808D02*
X1439924Y213809D01*
G01X1441503Y213808D02*
X1439925D01*
G01X1441504Y213809D02*
X1441503Y213808D01*
G01X1444371Y213809D02*
X1441504D01*
G01X1444372Y213808D02*
X1444371Y213809D01*
G01X1445950Y213808D02*
X1444372D01*
G01X1445951Y213809D02*
X1445950Y213808D01*
G01X1447309Y213809D02*
X1445951D01*
G01X1458500Y225000D02*
X1447309Y213809D01*
G01X1458517Y209803D02*
X1471214Y222500D01*
G01X1458517Y206178D02*
Y209803D01*
G01X1445018Y192679D02*
X1458517Y206178D01*
G01X1439639Y192679D02*
X1445018D01*
G01X1414738Y167778D02*
X1439639Y192679D01*
G01X1408100Y167778D02*
X1414738D01*
G01X1404307Y163985D02*
X1408100Y167778D01*
G01X1448040Y210223D02*
X1459548Y221731D01*
G01X1437823Y210223D02*
X1448040D01*
G01X1412900Y185300D02*
X1437823Y210223D01*
G01X1465084Y184260D02*
X1458801Y177977D01*
G01X1465084Y186814D02*
Y184260D01*
G01X1469455Y191185D02*
X1465084Y186814D01*
G01X1417679Y208598D02*
X1433153Y224072D01*
G01X1407282Y208598D02*
X1417679D01*
G01X1405825Y207141D02*
X1407282Y208598D01*
G01X1405825Y204787D02*
Y207141D01*
G01X1409136Y177333D02*
X1409135Y177334D01*
G01X1412586Y177333D02*
X1409136D01*
G01X1435330Y200077D02*
X1412586Y177333D01*
G01X1449831Y200077D02*
X1435330D01*
G01X1457013Y207259D02*
X1449831Y200077D01*
G01X1457013Y210427D02*
Y207259D01*
G01X1471408Y224822D02*
X1457013Y210427D01*
G01X1448055Y212555D02*
X1459000Y223500D01*
G01X1437508Y212555D02*
X1448055D01*
G01X1412205Y187252D02*
X1437508Y212555D01*
G01X1408247Y206270D02*
Y204508D01*
G01X1447817Y185122D02*
X1443017D01*
G01X1468384Y205689D02*
X1447817Y185122D01*
G01X1438291Y225576D02*
X1432251D01*
G01X1455248Y242533D02*
X1438291Y225576D01*
G01X1455248Y248954D02*
Y242533D01*
G01X1460376Y254082D02*
X1455248Y248954D01*
G01X1460376Y255876D02*
Y254082D01*
G01X1462200Y257700D02*
X1460376Y255876D01*
G01X1469856Y257700D02*
X1462200D01*
G01X1464983Y232976D02*
X1470314Y238307D01*
G01X1463346Y232976D02*
X1464983D01*
G01X1464784Y233841D02*
X1462992D01*
G01X1470002Y239059D02*
X1464784Y233841D01*
G01X1421554Y251155D02*
X1404384D01*
G01X1430399Y260000D02*
X1421554Y251155D01*
G01X1433871Y260000D02*
X1430399D01*
G01X1438471Y255400D02*
X1433871Y260000D01*
G01X1438500Y255400D02*
X1438471D01*
G01X1459736Y248217D02*
X1465063Y253544D01*
G01X1459736Y243733D02*
Y248217D01*
G01X1459976Y243493D02*
X1459736Y243733D01*
G01X1459976Y242311D02*
Y243493D01*
G01X1440979Y223320D02*
X1459976Y242311D01*
G01X1438745Y223320D02*
X1440979D01*
G01X1438743Y223318D02*
X1438745Y223320D01*
G01X1437497Y223318D02*
X1438743D01*
G01X1437496Y223319D02*
X1437497Y223318D01*
G01X1436874Y223319D02*
X1437496D01*
G01X1436873Y223320D02*
X1436874Y223319D01*
G01X1433573Y223320D02*
X1436873D01*
G01X1425802Y250133D02*
X1404426D01*
G01X1433057Y257388D02*
X1425802Y250133D01*
G01X1414691Y267045D02*
X1426905D01*
G01X1412726Y265080D02*
X1414691Y267045D01*
G01X1436561Y222568D02*
X1434027D01*
G01X1436562Y222567D02*
X1436561Y222568D01*
G01X1437184Y222567D02*
X1436562D01*
G01X1437185Y222566D02*
X1437184Y222567D01*
G01X1439055Y222566D02*
X1437185D01*
G01X1439057Y222568D02*
X1439055Y222566D01*
G01X1441292Y222568D02*
X1439057D01*
G01X1461348Y242619D02*
X1441292Y222568D01*
G01X1461348Y244350D02*
Y242619D01*
G01X1407274Y245096D02*
Y245652D01*
G01X1406010Y243832D02*
X1407274Y245096D01*
G01X1423800Y272729D02*
Y283455D01*
G01X1428600Y267929D02*
X1423800Y272729D01*
G01X1428600Y266499D02*
Y267929D01*
G01X1424770Y262669D02*
X1428600Y266499D01*
G01X1456582Y264532D02*
Y280511D01*
G01X1455826Y263776D02*
X1456582Y264532D01*
G01X1453697Y263776D02*
X1455826D01*
G01X1452121Y262200D02*
X1453697Y263776D01*
G01X1451850Y262200D02*
X1452121D01*
G01X1452697Y266169D02*
X1454056D01*
G01X1452361Y265833D02*
X1452697Y266169D01*
G01X1441694Y265833D02*
X1452361D01*
G01X1438506Y269021D02*
X1441694Y265833D01*
G01X1438506Y286093D02*
Y269021D01*
G01X1405878Y283536D02*
Y278934D01*
G01X1428129Y248629D02*
X1405050D01*
G01X1433700Y254200D02*
X1428129Y248629D01*
G01X1461664Y256100D02*
X1464700D01*
G01X1461128Y255564D02*
X1461664Y256100D01*
G01X1461128Y253770D02*
Y255564D01*
G01X1456000Y248642D02*
X1461128Y253770D01*
G01X1456000Y242221D02*
Y248642D01*
G01X1438603Y224824D02*
X1456000Y242221D01*
G01X1438121Y224824D02*
X1438603D01*
G01X1438120Y224823D02*
X1438121Y224824D01*
G01X1437498Y224823D02*
X1438120D01*
G01X1437497Y224824D02*
X1437498Y224823D01*
G01X1432841Y224824D02*
X1437497D01*
G01X1431700Y273471D02*
Y283500D01*
G01X1442371Y262800D02*
X1431700Y273471D01*
G01X1445629Y262800D02*
X1442371D01*
G01X1450076Y258353D02*
X1445629Y262800D01*
G01X1450076Y257047D02*
Y258353D01*
G01X1448329Y255300D02*
X1450076Y257047D01*
G01X1447310Y255300D02*
X1448329D01*
G01X1444180Y252170D02*
X1447310Y255300D01*
G01X1444180Y243400D02*
Y252170D01*
G01X1444850Y242730D02*
X1444180Y243400D01*
G01X1439720Y237600D02*
X1434836D01*
G01X1444850Y242730D02*
X1439720Y237600D01*
G01X1464835Y224618D02*
Y221536D01*
G01X1469200Y228983D02*
X1464835Y224618D01*
G01X1443428Y252628D02*
X1448500Y257700D01*
G01X1443428Y250418D02*
Y252628D01*
G01X1441240Y248230D02*
X1443428Y250418D01*
G01X1441240Y241711D02*
Y248230D01*
G01X1438029Y238500D02*
X1441240Y241711D01*
G01X1432600Y238500D02*
X1438029D01*
G01X1419710Y251969D02*
X1404134D01*
G01X1430365Y262624D02*
X1419710Y251969D01*
G01X1442166Y220247D02*
X1435410D01*
G01X1464828Y242907D02*
X1442166Y220247D01*
G01X1464828Y246338D02*
Y242907D01*
G01X1465840Y247350D02*
X1464828Y246338D01*
G01X1410979Y269493D02*
Y270473D01*
G01X1409128Y267642D02*
X1410979Y269493D01*
G01X1434300Y252548D02*
Y251600D01*
G01X1434652Y252900D02*
X1434300Y252548D01*
G01X1436400Y252900D02*
X1434652D01*
G01X1438250Y251050D02*
X1436400Y252900D01*
G01X1440679Y251050D02*
X1438250D01*
G01X1441276Y251647D02*
X1440679Y251050D01*
G01X1441276Y257475D02*
Y251647D01*
G01X1433548Y265203D02*
X1441276Y257475D01*
G01X1433548Y268013D02*
Y265203D01*
G01X1429123Y272438D02*
X1433548Y268013D01*
G01X1429123Y285052D02*
Y272438D01*
G01X1434350Y251600D02*
X1434300D01*
G01X1438983Y246967D02*
X1434350Y251600D01*
G01X1438983Y242618D02*
Y246967D01*
G01X1438000Y241635D02*
X1438983Y242618D01*
G01X1423335Y241635D02*
X1438000D01*
G01X1406900Y225200D02*
X1423335Y241635D01*
G01X1461124Y222353D02*
X1468448Y229677D01*
G01X1461124Y219550D02*
Y222353D01*
G01X1441853Y220999D02*
X1435098D01*
G01X1464076Y243219D02*
X1441853Y220999D01*
G01X1464076Y247252D02*
Y243219D01*
G01X1466824Y250000D02*
X1464076Y247252D01*
G01X1410979Y268273D02*
X1412579D01*
G01X1409486Y266780D02*
X1410979Y268273D01*
G01X1462800Y271900D02*
Y280900D01*
G01X1461300Y270400D02*
X1462800Y271900D01*
G01X1453432Y272133D02*
X1454902Y273603D01*
G01X1441695Y272133D02*
X1453432D01*
G01X1440008Y273820D02*
X1441695Y272133D01*
G01X1440008Y285469D02*
Y273820D01*
G01X1459572Y262922D02*
Y280351D01*
G01X1454674Y258024D02*
X1459572Y262922D01*
G01X1453252Y258024D02*
X1454674D01*
G01X1447154Y251926D02*
X1453252Y258024D01*
G01X1447154Y251710D02*
Y251926D01*
G01X1442708Y218579D02*
X1467324Y243193D01*
G01X1435870Y218579D02*
X1442708D01*
G01X1439257Y271421D02*
Y285781D01*
G01X1441694Y268984D02*
X1439257Y271421D01*
G01X1447133Y268984D02*
X1441694D01*
G01X1448603Y270454D02*
X1447133Y268984D01*
G01X1437900Y253100D02*
X1439700D01*
G01X1435200Y255800D02*
X1437900Y253100D01*
G01X1433001Y255800D02*
X1435200D01*
G01X1426582Y249381D02*
X1433001Y255800D01*
G01X1404738Y249381D02*
X1426582D01*
G01X1463284Y266174D02*
X1468074Y270964D01*
G01X1463284Y264505D02*
Y266174D01*
G01X1461399Y262620D02*
X1463284Y264505D01*
G01X1461165Y262620D02*
X1461399D01*
G01X1453776Y255231D02*
X1461165Y262620D01*
G01X1453776Y253847D02*
Y255231D01*
G01X1448600Y248671D02*
X1453776Y253847D01*
G01X1448600Y240600D02*
Y248671D01*
G01X1440400Y232400D02*
X1448600Y240600D01*
G01X1430700Y232400D02*
X1440400D01*
G01X1442315Y219331D02*
X1435558D01*
G01X1466404Y243419D02*
X1442315Y219331D01*
G01X1404286Y281729D02*
Y278406D01*
G01X1444207Y278000D02*
X1445454Y276753D01*
G01X1442127Y278000D02*
X1444207D01*
G01X1440788Y279339D02*
X1442127Y278000D01*
G01X1440788Y284357D02*
Y279339D01*
G01X1462046Y260357D02*
X1467040D01*
G01X1457176Y255487D02*
X1462046Y260357D01*
G01X1457176Y251946D02*
Y255487D01*
G01X1454496Y249266D02*
X1457176Y251946D01*
G01X1454496Y242845D02*
Y249266D01*
G01X1437979Y226328D02*
X1454496Y242845D01*
G01X1431605Y226328D02*
X1437979D01*
G01X1424978Y219701D02*
X1431605Y226328D01*
G01X1421449Y219701D02*
X1424978D01*
G01X1441540Y221751D02*
X1434550D01*
G01X1462924Y243131D02*
X1441540Y221751D01*
G01X1462924Y247630D02*
Y243131D01*
G01X1468194Y252900D02*
X1462924Y247630D01*
G01X1460140Y225000D02*
X1458500D01*
G01X1466076Y230936D02*
X1460140Y225000D01*
G01X1450100Y276100D02*
Y308889D01*
G01X1449283Y275283D02*
X1450100Y276100D01*
G01X1443984Y275283D02*
X1449283D01*
G01X1442304Y273603D02*
X1443984Y275283D01*
G01X1433362Y272873D02*
Y278244D01*
G01X1442135Y264100D02*
X1433362Y272873D01*
G01X1446364Y264100D02*
X1442135D01*
G01X1450828Y259636D02*
X1446364Y264100D01*
G01X1450828Y256664D02*
Y259636D01*
G01X1448712Y254548D02*
X1450828Y256664D01*
G01X1447622Y254548D02*
X1448712D01*
G01X1445260Y252186D02*
X1447622Y254548D01*
G01X1445260Y249510D02*
Y252186D01*
G01X1447300Y247470D02*
X1445260Y249510D01*
G01X1447300Y242350D02*
Y247470D01*
G01X1441750Y236800D02*
X1447300Y242350D01*
G01X1431900Y264200D02*
X1437800Y258300D01*
G01X1429499Y264200D02*
X1431900D01*
G01X1418192Y252893D02*
X1429499Y264200D01*
G01X1403994Y252893D02*
X1418192D01*
G01X1457844Y243000D02*
X1458318D01*
G01X1456093Y241249D02*
X1457844Y243000D01*
G01X1456092Y241249D02*
X1456093D01*
G01X1438915Y224072D02*
X1456092Y241249D01*
G01X1438433Y224072D02*
X1438915D01*
G01X1438431Y224070D02*
X1438433Y224072D01*
G01X1437809Y224070D02*
X1438431D01*
G01X1437808Y224071D02*
X1437809Y224070D01*
G01X1437186Y224071D02*
X1437808D01*
G01X1437185Y224072D02*
X1437186Y224071D01*
G01X1433153Y224072D02*
X1437185D01*
G01X1460270Y223500D02*
X1467229Y230459D01*
G01X1459000Y223500D02*
X1460270D01*
G01X1416900Y254432D02*
X1416548Y254080D01*
G01X1416900Y255580D02*
Y254432D01*
G01X1416548Y255932D02*
X1416900Y255580D01*
G01X1404129Y258136D02*
X1403777Y257784D01*
G01X1404129Y261065D02*
Y258136D01*
G01X1404481Y261417D02*
X1404129Y261065D01*
G01X1405629Y261417D02*
X1404481D01*
G01X1405981Y261065D02*
X1405629Y261417D01*
G01X1405981Y258136D02*
Y261065D01*
G01X1406333Y257784D02*
X1405981Y258136D01*
G01X1407481Y257784D02*
X1406333D01*
G01X1407833Y258136D02*
X1407481Y257784D01*
G01X1407833Y261065D02*
Y258136D01*
G01X1408185Y261417D02*
X1407833Y261065D01*
G01X1409333Y261417D02*
X1408185D01*
G01X1409685Y261065D02*
X1409333Y261417D01*
G01X1409685Y258136D02*
Y261065D01*
G01X1410037Y257784D02*
X1409685Y258136D01*
G01X1411185Y257784D02*
X1410037D01*
G01X1411537Y258136D02*
X1411185Y257784D01*
G01X1411537Y261065D02*
Y258136D01*
G01X1411889Y261417D02*
X1411537Y261065D01*
G01X1413037Y261417D02*
X1411889D01*
G01X1413389Y261065D02*
X1413037Y261417D01*
G01X1413389Y258136D02*
Y261065D01*
G01X1413741Y257784D02*
X1413389Y258136D01*
G01X1414889Y257784D02*
X1413741D01*
G01X1415241Y258136D02*
X1414889Y257784D01*
G01X1415241Y261065D02*
Y258136D01*
G01X1415593Y261417D02*
X1415241Y261065D01*
G01X1416741Y261417D02*
X1415593D01*
G01X1417093Y261065D02*
X1416741Y261417D01*
G01X1417093Y258136D02*
Y261065D01*
G01X1417445Y257784D02*
X1417093Y258136D01*
G01X1418593Y257784D02*
X1417445D01*
G01X1418945Y258136D02*
X1418593Y257784D01*
G01X1418945Y261065D02*
Y258136D01*
G01X1419297Y261417D02*
X1418945Y261065D01*
G01X1420445Y261417D02*
X1419297D01*
G01X1420797Y261065D02*
X1420445Y261417D01*
G01X1420797Y258136D02*
Y261065D01*
G01X1421149Y257784D02*
X1420797Y258136D01*
G01X1421684Y257784D02*
X1421149D01*
G01X1429900Y266000D02*
X1421684Y257784D01*
G01X1429900Y268400D02*
Y266000D01*
G01X1425082Y273218D02*
X1429900Y268400D01*
G01X1425082Y282641D02*
Y273218D01*
G01X1465603Y279902D02*
X1464351D01*
G01X1456554Y325994D02*
X1465377Y334817D01*
G01X1456554Y303600D02*
Y325994D01*
G01X1454902Y301948D02*
X1456554Y303600D01*
G01X1431315Y335958D02*
Y392134D01*
G01X1428515Y333158D02*
X1431315Y335958D01*
G01X1428515Y315284D02*
Y333158D01*
G01X1429135Y312186D02*
X1428515Y315284D01*
G01X1429287Y311429D02*
X1429135Y312186D01*
G01X1429289Y311427D02*
X1429287Y311429D01*
G01X1430051Y307608D02*
X1429289Y311427D01*
G01X1430267Y306522D02*
X1430051Y307608D01*
G01X1430286Y306429D02*
X1430267Y306522D01*
G01X1430355Y306083D02*
X1430286Y306429D01*
G01X1430360Y306058D02*
X1430355Y306083D01*
G01X1430360Y294760D02*
Y306058D01*
G01X1422500Y286900D02*
X1430360Y294760D01*
G01X1405364Y286900D02*
X1422500D01*
G01X1403816Y285352D02*
X1405364Y286900D01*
G01X1403816Y283488D02*
Y285352D01*
G01X1458400Y324801D02*
Y318500D01*
G01X1467803Y334204D02*
X1458400Y324801D01*
G01X1434083Y333911D02*
Y391801D01*
G01X1431113Y330941D02*
X1434083Y333911D01*
G01X1431113Y315479D02*
Y330941D01*
G01X1433213Y304960D02*
X1431113Y315479D01*
G01X1433213Y292868D02*
Y304960D01*
G01X1423800Y283455D02*
X1433213Y292868D01*
G01X1459600Y312998D02*
X1458052Y314546D01*
G01X1459600Y295063D02*
Y312998D01*
G01X1459732Y294931D02*
X1459600Y295063D01*
G01X1459732Y281795D02*
Y294931D01*
G01X1459309Y281372D02*
X1459732Y281795D01*
G01X1457443Y281372D02*
X1459309D01*
G01X1456582Y280511D02*
X1457443Y281372D01*
G01X1439101Y286688D02*
X1438506Y286093D01*
G01X1439101Y304664D02*
Y286688D01*
G01X1437174Y314290D02*
X1439101Y304664D01*
G01X1437174Y328056D02*
Y314290D01*
G01X1440500Y331382D02*
X1437174Y328056D01*
G01X1440500Y355438D02*
Y331382D01*
G01X1405392Y284022D02*
X1405878Y283536D01*
G01X1439100Y331046D02*
Y355668D01*
G01X1436422Y328368D02*
X1439100Y331046D01*
G01X1436422Y314215D02*
Y328368D01*
G01X1438350Y304574D02*
X1436422Y314215D01*
G01X1438350Y290150D02*
Y304574D01*
G01X1431700Y283500D02*
X1438350Y290150D01*
G01X1435798Y291727D02*
X1429123Y285052D01*
G01X1435798Y304307D02*
Y291727D01*
G01X1433870Y313957D02*
X1435798Y304307D01*
G01X1433870Y330100D02*
Y313957D01*
G01X1436525Y332755D02*
X1433870Y330100D01*
G01X1436525Y357068D02*
Y332755D01*
G01X1445454Y312433D02*
Y311397D01*
G01X1443131Y314756D02*
X1445454Y312433D01*
G01X1443131Y319045D02*
Y314756D01*
G01X1444176Y320090D02*
X1443131Y319045D01*
G01X1444176Y324231D02*
Y320090D01*
G01X1444311Y324366D02*
X1444176Y324231D01*
G01X1464960Y281582D02*
X1466100Y282722D01*
G01X1463482Y281582D02*
X1464960D01*
G01X1462800Y280900D02*
X1463482Y281582D01*
G01X1440603Y286064D02*
X1440008Y285469D01*
G01X1440603Y305288D02*
Y286064D01*
G01X1438678Y314909D02*
X1440603Y305288D01*
G01X1438678Y326614D02*
Y314909D01*
G01X1442634Y330570D02*
X1438678Y326614D01*
G01X1442634Y352734D02*
Y330570D01*
G01X1465349Y324109D02*
X1469797Y328557D01*
G01X1464102Y317452D02*
X1465349Y318699D01*
G01X1464102Y313458D02*
Y317452D01*
G01X1462672Y312028D02*
X1464102Y313458D01*
G01X1462672Y304372D02*
Y312028D01*
G01X1461202Y302902D02*
X1462672Y304372D01*
G01X1461202Y301948D02*
Y302902D01*
G01Y301098D02*
Y301948D01*
G01X1462881Y299419D02*
X1461202Y301098D01*
G01X1462881Y282652D02*
Y299419D01*
G01X1461811Y281582D02*
X1462881Y282652D01*
G01X1460803Y281582D02*
X1461811D01*
G01X1459572Y280351D02*
X1460803Y281582D01*
G01X1447064Y284662D02*
X1442304Y279902D01*
G01X1447064Y309279D02*
Y284662D01*
G01X1446508Y309835D02*
X1447064Y309279D01*
G01X1444915Y309835D02*
X1446508D01*
G01X1444563Y310187D02*
X1444915Y309835D01*
G01X1444563Y310209D02*
Y310187D01*
G01X1443984Y310788D02*
X1444563Y310209D01*
G01X1443984Y311828D02*
Y310788D01*
G01X1442380Y313432D02*
X1443984Y311828D01*
G01X1442380Y319357D02*
Y313432D01*
G01X1443211Y320188D02*
X1442380Y319357D01*
G01X1443211Y323237D02*
Y320188D01*
G01X1442735Y323713D02*
X1443211Y323237D01*
G01X1442735Y325019D02*
Y323713D01*
G01X1444040Y326324D02*
X1442735Y325019D01*
G01X1444401Y326324D02*
X1444040D01*
G01X1445076Y326999D02*
X1444401Y326324D01*
G01X1445076Y329225D02*
Y326999D01*
G01X1444138Y330163D02*
X1445076Y329225D01*
G01X1444138Y343142D02*
Y330163D01*
G01X1441882Y330882D02*
Y355256D01*
G01X1437926Y326926D02*
X1441882Y330882D01*
G01X1437926Y314365D02*
Y326926D01*
G01X1439852Y304745D02*
X1437926Y314365D01*
G01X1439852Y286376D02*
Y304745D01*
G01X1439257Y285781D02*
X1439852Y286376D01*
G01X1446400Y332400D02*
Y342900D01*
G01X1447236Y331564D02*
X1446400Y332400D01*
G01X1447236Y318859D02*
Y331564D01*
G01X1446970Y318593D02*
X1447236Y318859D01*
G01X1446970Y318409D02*
Y318593D01*
G01X1446998Y318381D02*
X1446970Y318409D01*
G01X1446998Y317163D02*
Y318381D01*
G01X1446970Y317135D02*
X1446998Y317163D01*
G01X1446970Y313804D02*
Y317135D01*
G01X1447698Y313076D02*
X1446970Y313804D01*
G01X1448988Y313076D02*
X1447698D01*
G01X1449197Y312867D02*
X1448988Y313076D01*
G01X1449212Y312867D02*
X1449197D01*
G01X1450073Y312006D02*
X1449212Y312867D01*
G01X1450073Y310179D02*
Y312006D01*
G01X1453281Y306971D02*
X1450073Y310179D01*
G01X1453281Y285744D02*
Y306971D01*
G01X1454293Y284732D02*
X1453281Y285744D01*
G01X1456582Y284732D02*
X1454293D01*
G01X1458052Y286202D02*
X1456582Y284732D01*
G01X1443939Y287508D02*
X1440788Y284357D01*
G01X1443939Y308854D02*
Y287508D01*
G01X1443039Y309754D02*
X1443939Y308854D01*
G01X1441875Y309754D02*
X1443039D01*
G01X1441702Y309927D02*
X1441875Y309754D01*
G01X1441695Y309927D02*
X1441702D01*
G01X1440834Y310788D02*
X1441695Y309927D01*
G01X1440834Y310795D02*
Y310788D01*
G01X1440760Y310869D02*
X1440834Y310795D01*
G01X1440760Y313965D02*
Y310869D01*
G01X1439430Y315295D02*
X1440760Y313965D01*
G01X1439430Y319420D02*
Y315295D01*
G01X1441935Y321925D02*
X1439430Y319420D01*
G01X1441935Y327236D02*
Y321925D01*
G01X1441924Y327247D02*
X1441935Y327236D01*
G01X1441924Y328553D02*
Y327247D01*
G01X1441935Y328564D02*
X1441924Y328553D01*
G01X1441935Y328807D02*
Y328564D01*
G01X1443386Y330258D02*
X1441935Y328807D01*
G01X1443386Y343582D02*
Y330258D01*
G01X1444890Y330796D02*
Y342750D01*
G01X1446294Y329392D02*
X1444890Y330796D01*
G01X1446294Y320598D02*
Y329392D01*
G01X1444938Y319242D02*
X1446294Y320598D01*
G01X1444919Y319242D02*
X1444938D01*
G01X1444058Y318381D02*
X1444919Y319242D01*
G01X1444058Y318362D02*
Y318381D01*
G01X1444025Y318329D02*
X1444058Y318362D01*
G01X1444025Y315375D02*
Y318329D01*
G01X1447000Y312400D02*
X1444025Y315375D01*
G01X1447000Y310815D02*
Y312400D01*
G01X1448081Y309734D02*
X1447000Y310815D01*
G01X1449255Y309734D02*
X1448081D01*
G01X1450100Y308889D02*
X1449255Y309734D01*
G01X1434529Y292088D02*
X1425082Y282641D01*
G01X1434529Y304772D02*
Y292088D01*
G01X1432365Y315605D02*
X1434529Y304772D01*
G01X1432365Y330225D02*
Y315605D01*
G01X1435373Y333233D02*
X1432365Y330225D01*
G01X1435373Y357546D02*
Y333233D01*
G01X1461202Y312201D02*
Y311397D01*
G01X1462672Y313671D02*
X1461202Y312201D01*
G01X1462672Y315328D02*
Y313671D01*
G01X1461306Y316694D02*
X1462672Y315328D01*
G01X1461306Y324903D02*
Y316694D01*
G01X1470850Y334447D02*
X1461306Y324903D01*
G01X1448603Y319107D02*
Y317696D01*
G01X1464225Y334729D02*
X1448603Y319107D01*
G01X1464225Y347455D02*
Y334729D01*
G01X1465377Y346977D02*
X1468100Y349700D01*
G01X1431315Y392134D02*
X1453600Y414419D01*
G01X1434083Y391801D02*
X1463872Y421590D01*
G01X1452600Y367538D02*
X1440500Y355438D01*
G01X1452600Y376700D02*
Y367538D01*
G01X1456174Y380274D02*
X1452600Y376700D01*
G01X1457403Y380274D02*
X1456174D01*
G01X1461904Y384775D02*
X1457403Y380274D01*
G01X1461904Y385604D02*
Y384775D01*
G01X1464525Y388225D02*
X1461904Y385604D01*
G01X1465975Y388225D02*
X1464525D01*
G01X1464868Y365068D02*
X1468198Y368398D01*
G01X1464868Y364114D02*
Y365068D01*
G01X1464869Y364113D02*
X1464868Y364114D01*
G01X1464869Y360669D02*
Y364113D01*
G01X1463942Y359742D02*
X1464869Y360669D01*
G01X1464400Y390750D02*
Y390800D01*
G01X1463950Y390300D02*
X1464400Y390750D01*
G01X1457371Y390300D02*
X1463950D01*
G01X1452500Y385429D02*
X1457371Y390300D01*
G01X1452500Y377900D02*
Y385429D01*
G01X1451500Y376900D02*
X1452500Y377900D01*
G01X1451500Y368068D02*
Y376900D01*
G01X1439100Y355668D02*
X1451500Y368068D01*
G01X1447750Y368293D02*
X1436525Y357068D01*
G01X1447750Y372250D02*
Y368293D01*
G01X1445100Y374900D02*
X1447750Y372250D01*
G01X1454504Y364604D02*
X1442634Y352734D01*
G01X1454504Y374950D02*
Y364604D01*
G01X1456054Y376500D02*
X1454504Y374950D01*
G01X1459300Y376500D02*
X1456054D01*
G01X1464850Y370950D02*
X1459300Y376500D01*
G01X1468500Y370950D02*
X1464850D01*
G01X1450400Y349404D02*
X1444138Y343142D01*
G01X1450400Y354300D02*
Y349404D01*
G01X1463350Y379200D02*
X1466950Y382800D01*
G01X1456900Y379200D02*
X1463350D01*
G01X1453600Y375900D02*
X1456900Y379200D01*
G01X1453600Y366974D02*
Y375900D01*
G01X1441882Y355256D02*
X1453600Y366974D01*
G01X1457300Y370650D02*
Y373600D01*
G01X1457850Y370100D02*
X1457300Y370650D01*
G01X1457850Y360000D02*
Y370100D01*
G01X1456250Y358400D02*
X1457850Y360000D01*
G01X1456250Y352750D02*
Y358400D01*
G01X1446400Y342900D02*
X1456250Y352750D01*
G01X1447685Y347881D02*
X1443386Y343582D01*
G01X1447685Y352025D02*
Y347881D01*
G01X1463579Y369550D02*
X1472950D01*
G01X1457953Y375176D02*
X1463579Y369550D01*
G01X1456647Y375176D02*
X1457953D01*
G01X1455724Y374253D02*
X1456647Y375176D01*
G01X1455724Y362924D02*
Y374253D01*
G01X1451600Y358800D02*
X1455724Y362924D01*
G01X1451600Y355450D02*
Y358800D01*
G01X1452000Y355050D02*
X1451600Y355450D01*
G01X1452000Y349860D02*
Y355050D01*
G01X1444890Y342750D02*
X1452000Y349860D01*
G01X1436574Y358747D02*
X1435373Y357546D01*
G01X1436574Y359245D02*
Y358747D01*
G01X1435834Y359985D02*
X1436574Y359245D01*
G01X1435834Y360483D02*
Y359985D01*
G01X1436646Y361295D02*
X1435834Y360483D01*
G01X1437144Y361295D02*
X1436646D01*
G01X1437884Y360555D02*
X1437144Y361295D01*
G01X1438382Y360555D02*
X1437884D01*
G01X1439194Y361367D02*
X1438382Y360555D01*
G01X1439194Y361865D02*
Y361367D01*
G01X1438454Y362605D02*
X1439194Y361865D01*
G01X1438454Y363103D02*
Y362605D01*
G01X1439266Y363915D02*
X1438454Y363103D01*
G01X1439764Y363915D02*
X1439266D01*
G01X1440504Y363175D02*
X1439764Y363915D01*
G01X1441002Y363175D02*
X1440504D01*
G01X1441814Y363987D02*
X1441002Y363175D01*
G01X1441814Y364485D02*
Y363987D01*
G01X1441074Y365225D02*
X1441814Y364485D01*
G01X1441074Y365723D02*
Y365225D01*
G01X1441886Y366535D02*
X1441074Y365723D01*
G01X1442384Y366535D02*
X1441886D01*
G01X1443124Y365795D02*
X1442384Y366535D01*
G01X1443622Y365795D02*
X1443124D01*
G01X1445250Y367423D02*
X1443622Y365795D01*
G01X1445250Y370750D02*
Y367423D01*
G01X1444400Y371600D02*
X1445250Y370750D01*
G01X1466353Y349583D02*
X1464225Y347455D01*
G01X1463203Y430563D02*
X1472980D01*
G01X1453600Y420960D02*
X1463203Y430563D01*
G01X1453600Y414419D02*
Y420960D01*
G01X1458300Y442600D02*
Y442675D01*
G01X1452900Y448000D02*
X1458300Y442600D01*
G01X1451002Y448000D02*
X1452900D01*
G01X1443026Y455976D02*
X1451002Y448000D01*
G01X1423076Y455976D02*
X1443026D01*
G01X1414367Y447267D02*
X1423076Y455976D01*
G01X1414107Y447267D02*
X1414367D01*
G01X1463872Y421590D02*
X1465486D01*
G01X1416000Y522600D02*
X1414800Y521400D01*
G01X1416000Y540254D02*
Y522600D01*
G01X1464789Y505325D02*
X1470974D01*
G01X1453845Y494381D02*
X1464789Y505325D01*
G01X1453845Y483131D02*
Y494381D01*
G01X1443832Y473118D02*
X1453845Y483131D01*
G01X1462257Y510470D02*
X1468753D01*
G01X1459368Y507581D02*
X1462257Y510470D01*
G01X1455511Y507581D02*
X1459368D01*
G01X1445504Y497574D02*
X1455511Y507581D01*
G01X1435530Y497574D02*
X1445504D01*
G01X1423279Y485323D02*
X1435530Y497574D01*
G01X1412234Y485323D02*
X1423279D01*
G01X1464561Y495692D02*
X1469478Y500609D01*
G01X1464561Y483083D02*
Y495692D01*
G01X1460410Y478932D02*
X1464561Y483083D01*
G01X1457365Y478932D02*
X1460410D01*
G01X1446495Y468062D02*
X1457365Y478932D01*
G01X1461862Y511422D02*
X1468358D01*
G01X1458973Y508533D02*
X1461862Y511422D01*
G01X1455116Y508533D02*
X1458973D01*
G01X1445109Y498526D02*
X1455116Y508533D01*
G01X1435135Y498526D02*
X1445109D01*
G01X1422884Y486275D02*
X1435135Y498526D01*
G01X1411839Y486275D02*
X1422884D01*
G01X1465184Y504373D02*
X1472102D01*
G01X1454797Y493986D02*
X1465184Y504373D01*
G01X1454797Y482736D02*
Y493986D01*
G01X1444227Y472166D02*
X1454797Y482736D01*
G01X1465313Y495380D02*
X1469790Y499857D01*
G01X1460721Y478179D02*
X1465313Y482771D01*
G01X1457676Y478179D02*
X1460721D01*
G01X1446807Y467310D02*
X1457676Y478179D01*
G01X1464394Y506277D02*
X1469738D01*
G01X1446293Y488176D02*
X1464394Y506277D01*
G01X1446293Y486405D02*
Y488176D01*
G01X1445898Y486010D02*
X1446293Y486405D01*
G01X1445898Y476531D02*
Y486010D01*
G01X1443508Y474141D02*
X1445898Y476531D01*
G01X1463096Y507229D02*
X1467273D01*
G01X1454427Y498560D02*
X1463096Y507229D01*
G01X1451260Y498560D02*
X1454427D01*
G01X1443899Y491199D02*
X1451260Y498560D01*
G01X1443899Y488587D02*
Y491199D01*
G01X1443817Y488505D02*
X1443899Y488587D01*
G01X1443817Y488487D02*
Y488505D01*
G01X1442777Y487447D02*
X1443817Y488487D01*
G01X1442759Y487447D02*
X1442777D01*
G01X1442385Y487073D02*
X1442759Y487447D01*
G01X1442385Y484960D02*
Y487073D01*
G01X1443899Y483446D02*
X1442385Y484960D01*
G01X1443899Y478377D02*
Y483446D01*
G01X1443917Y478359D02*
X1443899Y478377D01*
G01X1443917Y476887D02*
Y478359D01*
G01X1443899Y476869D02*
X1443917Y476887D01*
G01X1443899Y475879D02*
Y476869D01*
G01X1443113Y475093D02*
X1443899Y475879D01*
G01X1461656Y475922D02*
X1467657Y481923D01*
G01X1458874Y475922D02*
X1461656D01*
G01X1448006Y465054D02*
X1458874Y475922D01*
G01X1461344Y476674D02*
X1466817Y482147D01*
G01X1458299Y476674D02*
X1461344D01*
G01X1447431Y465806D02*
X1458299Y476674D01*
G01X1463409Y496170D02*
X1468674Y501435D01*
G01X1463409Y483561D02*
Y496170D01*
G01X1460023Y480175D02*
X1463409Y483561D01*
G01X1456978Y480175D02*
X1460023D01*
G01X1446017Y469214D02*
X1456978Y480175D01*
G01X1457987Y477426D02*
X1447119Y466558D01*
G01X1461032Y477426D02*
X1457987D01*
G01X1466065Y482459D02*
X1461032Y477426D01*
G01X1417152Y522148D02*
Y539776D01*
G01X1417800Y521500D02*
X1417152Y522148D01*
G01X1430414Y554668D02*
X1416000Y540254D01*
G01X1432706Y554668D02*
X1430414D01*
G01X1438336Y560298D02*
X1432706Y554668D01*
G01X1438336Y562225D02*
Y560298D01*
G01X1448511Y572400D02*
X1438336Y562225D01*
G01X1450350Y572400D02*
X1448511D01*
G01X1451150Y573200D02*
X1450350Y572400D01*
G01X1418900Y552800D02*
X1407357Y541257D01*
G01X1423000Y552800D02*
X1418900D01*
G01X1430100Y559900D02*
X1423000Y552800D01*
G01X1430100Y563100D02*
Y559900D01*
G01X1445310Y578310D02*
X1430100Y563100D01*
G01X1452190Y578310D02*
X1445310D01*
G01X1457600Y572900D02*
X1452190Y578310D01*
G01X1461330Y572900D02*
X1457600D01*
G01X1465755Y577325D02*
X1461330Y572900D01*
G01X1465092Y579858D02*
X1488958D01*
G01X1460238Y575004D02*
X1465092Y579858D01*
G01X1458473Y575004D02*
X1460238D01*
G01X1453063Y580414D02*
X1458473Y575004D01*
G01X1444437Y580414D02*
X1453063D01*
G01X1427995Y563972D02*
X1444437Y580414D01*
G01X1427995Y560772D02*
Y563972D01*
G01X1422796Y555573D02*
X1427995Y560772D01*
G01X1417472Y555573D02*
X1422796D01*
G01X1414465Y552566D02*
X1417472Y555573D01*
G01X1450035Y571015D02*
X1451150Y569900D01*
G01X1448729Y571015D02*
X1450035D01*
G01X1439452Y561738D02*
X1448729Y571015D01*
G01X1439452Y559952D02*
Y561738D01*
G01X1433015Y553515D02*
X1439452Y559952D01*
G01X1430891Y553515D02*
X1433015D01*
G01X1417152Y539776D02*
X1430891Y553515D01*
G01X1465201Y578520D02*
X1489160D01*
G01X1460733Y574052D02*
X1465201Y578520D01*
G01X1458078Y574052D02*
X1460733D01*
G01X1452668Y579462D02*
X1458078Y574052D01*
G01X1444832Y579462D02*
X1452668D01*
G01X1428947Y563577D02*
X1444832Y579462D01*
G01X1428947Y560377D02*
Y563577D01*
G01X1423191Y554621D02*
X1428947Y560377D01*
G01X1417867Y554621D02*
X1423191D01*
G01X1414860Y551614D02*
X1417867Y554621D01*
G01X1465237Y622935D02*
X1546235D01*
G01X1461543Y619241D02*
X1465237Y622935D01*
G01X1446138Y619241D02*
X1461543D01*
G01X1436766Y609869D02*
X1446138Y619241D01*
G01X1436766Y603344D02*
Y609869D01*
G01X1426458Y593036D02*
X1436766Y603344D01*
G01X1411958Y593036D02*
X1426458D01*
G01X1407914Y597080D02*
X1411958Y593036D01*
G01X1464428Y623726D02*
X1546874D01*
G01X1460895Y620193D02*
X1464428Y623726D01*
G01X1445743Y620193D02*
X1460895D01*
G01X1435814Y610264D02*
X1445743Y620193D01*
G01X1435814Y603739D02*
Y610264D01*
G01X1426063Y593988D02*
X1435814Y603739D01*
G01X1412353Y593988D02*
X1426063D01*
G01X1408309Y598032D02*
X1412353Y593988D01*
G01X1495574Y27794D02*
X1502290Y34510D01*
G01X1465772Y27794D02*
X1495574D01*
G01X1505300Y1404D02*
X1541504D01*
G01X1495700Y11004D02*
X1505300Y1404D01*
G01X1487693Y11004D02*
X1495700D01*
G01X1486093Y9404D02*
X1487693Y11004D01*
G01X1488851Y29298D02*
X1468325D01*
G01X1496308Y36755D02*
X1488851Y29298D01*
G01X1512290Y17000D02*
X1507286Y22004D01*
G01X1670500Y17000D02*
X1512290D01*
G01X1504463Y-1800D02*
X1502163Y500D01*
G01X1569200Y-1800D02*
X1504463D01*
G01X1509500Y28300D02*
X1506808Y25608D01*
G01X1509500Y31900D02*
Y28300D01*
G01X1504905Y452D02*
X1573832D01*
G01X1495305Y10052D02*
X1504905Y452D01*
G01X1488088Y10052D02*
X1495305D01*
G01X1486488Y8452D02*
X1488088Y10052D01*
G01X1505254Y7082D02*
X1513700D01*
G01X1496888Y15448D02*
X1505254Y7082D01*
G01X1503852Y13448D02*
X1498752Y18548D01*
G01X1531522Y13448D02*
X1503852D01*
G01X1504593Y-300D02*
X1570394D01*
G01X1494993Y9300D02*
X1504593Y-300D01*
G01X1488400Y9300D02*
X1494993D01*
G01X1486800Y7700D02*
X1488400Y9300D01*
G01X1481316Y30050D02*
X1468637D01*
G01X1488773Y37507D02*
X1481316Y30050D01*
G01X1480438Y30802D02*
X1490907Y41271D01*
G01X1468949Y30802D02*
X1480438D01*
G01X1465979Y33772D02*
X1468949Y30802D01*
G01X1504600Y14600D02*
X1532000D01*
G01X1499500Y19700D02*
X1504600Y14600D01*
G01X1512696Y18224D02*
X1507764Y23156D01*
G01X1539163Y18224D02*
X1512696D01*
G01X1505676Y15824D02*
X1669473D01*
G01X1500648Y20852D02*
X1505676Y15824D01*
G01X1512924Y19626D02*
X1537617D01*
G01X1508242Y24308D02*
X1512924Y19626D01*
G01X1469261Y31554D02*
X1466746Y34069D01*
G01X1479252Y31554D02*
X1469261D01*
G01X1489721Y42023D02*
X1479252Y31554D01*
G01X1516600Y7100D02*
X1520700D01*
G01X1514900Y8800D02*
X1516600Y7100D01*
G01X1504600Y8800D02*
X1514900D01*
G01X1497200Y16200D02*
X1504600Y8800D01*
G01X1496169Y27042D02*
X1502885Y33758D01*
G01X1465460Y27042D02*
X1496169D01*
G01X1503374Y12296D02*
X1531044D01*
G01X1498274Y17396D02*
X1503374Y12296D01*
G01X1489446Y28546D02*
X1496903Y36003D01*
G01X1468013Y28546D02*
X1489446D01*
G01X1515240Y-3260D02*
X1544862D01*
G01X1507600Y-10900D02*
X1515240Y-3260D01*
G01X1497300Y-10900D02*
X1507600D01*
G01X1496652Y-10252D02*
X1497300Y-10900D01*
G01X1496660Y-10252D02*
X1496652D01*
G01X1483027Y88639D02*
Y109234D01*
G01X1496945Y74721D02*
X1483027Y88639D01*
G01X1496945Y72598D02*
Y74721D01*
G01X1507873Y61670D02*
X1496945Y72598D01*
G01X1544140Y61670D02*
X1507873D01*
G01X1502290Y34510D02*
X1537632D01*
G01X1479613Y89076D02*
Y132881D01*
G01X1494840Y73849D02*
X1479613Y89076D01*
G01X1494840Y71726D02*
Y73849D01*
G01X1507296Y59270D02*
X1494840Y71726D01*
G01X1574711Y59270D02*
X1507296D01*
G01X1499914Y46798D02*
X1572892D01*
G01X1539767Y36755D02*
X1496308D01*
G01X1504298Y56414D02*
X1575896D01*
G01X1476757Y83955D02*
X1504298Y56414D01*
G01X1476757Y134066D02*
Y83955D01*
G01X1470862Y61343D02*
Y38209D01*
G01X1472190Y87175D02*
Y107166D01*
G01X1503903Y55462D02*
X1472190Y87175D01*
G01X1576291Y55462D02*
X1503903D01*
G01X1481216Y44049D02*
X1552951D01*
G01X1473800Y36633D02*
X1481216Y44049D01*
G01X1469867Y36633D02*
X1473800D01*
G01X1468652Y37848D02*
X1469867Y36633D01*
G01X1468652Y60937D02*
Y37848D01*
G01X1502718Y52606D02*
X1575106D01*
G01X1469333Y85991D02*
X1502718Y52606D01*
G01X1469333Y106772D02*
Y85991D01*
G01X1500704Y48702D02*
X1573682D01*
G01X1468181Y85513D02*
Y106294D01*
G01X1502240Y51454D02*
X1468181Y85513D01*
G01X1574540Y51454D02*
X1502240D01*
G01X1499634Y45450D02*
X1561499D01*
G01X1499438Y45646D02*
X1499634Y45450D01*
G01X1499436Y45646D02*
X1499438D01*
G01X1467498Y34802D02*
Y59473D01*
G01X1469200Y33100D02*
X1467498Y34802D01*
G01X1471400Y33100D02*
X1469200D01*
G01X1473781Y35481D02*
X1471400Y33100D01*
G01X1474278Y35481D02*
X1473781D01*
G01X1481694Y42897D02*
X1474278Y35481D01*
G01X1552473Y42897D02*
X1481694D01*
G01X1471237Y86781D02*
Y106772D01*
G01X1503508Y54510D02*
X1471237Y86781D01*
G01X1575896Y54510D02*
X1503508D01*
G01X1540275Y37507D02*
X1488773D01*
G01X1490907Y41271D02*
X1547225D01*
G01X1465979Y43705D02*
Y33772D01*
G01X1503113Y53558D02*
X1575501D01*
G01X1470285Y86386D02*
X1503113Y53558D01*
G01X1470285Y107167D02*
Y86386D01*
G01X1478661Y88681D02*
Y133276D01*
G01X1493888Y73454D02*
X1478661Y88681D01*
G01X1493888Y71331D02*
Y73454D01*
G01X1506901Y58318D02*
X1493888Y71331D01*
G01X1575106Y58318D02*
X1506901D01*
G01X1466746Y34069D02*
Y44002D01*
G01X1547537Y42023D02*
X1489721D01*
G01X1502885Y33758D02*
X1537037D01*
G01X1480565Y89471D02*
Y132462D01*
G01X1495792Y74244D02*
X1480565Y89471D01*
G01X1495792Y72121D02*
Y74244D01*
G01X1507691Y60222D02*
X1495792Y72121D01*
G01X1574316Y60222D02*
X1507691D01*
G01X1504693Y57366D02*
X1575501D01*
G01X1477709Y84350D02*
X1504693Y57366D01*
G01X1477709Y133671D02*
Y84350D01*
G01X1496903Y36003D02*
X1539172D01*
G01X1500309Y47750D02*
X1573287D01*
G01X1510850Y126100D02*
X1511800Y127050D01*
G01X1504317Y126100D02*
X1510850D01*
G01X1500714Y122497D02*
X1504317Y126100D01*
G01X1494837Y122497D02*
X1500714D01*
G01X1493310Y120970D02*
X1494837Y122497D01*
G01X1493310Y119517D02*
Y120970D01*
G01X1483027Y109234D02*
X1493310Y119517D01*
G01X1489285Y151819D02*
Y156741D01*
G01X1492476Y148628D02*
X1489285Y151819D01*
G01X1492476Y145744D02*
Y148628D01*
G01X1479613Y132881D02*
X1492476Y145744D01*
G01X1475805Y123708D02*
X1473096Y120999D01*
G01X1475805Y134461D02*
Y123708D01*
G01X1483676Y142332D02*
X1475805Y134461D01*
G01X1483676Y165275D02*
Y142332D01*
G01X1484628Y141937D02*
X1476757Y134066D01*
G01X1484628Y164605D02*
Y141937D01*
G01X1481393Y143304D02*
Y167834D01*
G01X1472508Y134419D02*
X1481393Y143304D01*
G01X1472508Y132492D02*
Y134419D01*
G01X1473100Y131900D02*
X1472508Y132492D01*
G01X1466313Y132852D02*
Y174578D01*
G01X1472191Y107167D02*
Y107955D01*
G01X1472190Y107166D02*
X1472191Y107167D01*
G01X1479089Y144260D02*
Y168790D01*
G01X1470166Y135337D02*
X1479089Y144260D01*
G01X1470166Y129296D02*
Y135337D01*
G01X1470550Y128912D02*
X1470166Y129296D01*
G01X1470550Y120950D02*
Y128912D01*
G01X1473200Y118300D02*
X1470550Y120950D01*
G01X1473354Y153246D02*
Y167146D01*
G01X1482545Y142826D02*
Y167356D01*
G01X1474800Y135081D02*
X1482545Y142826D01*
G01X1474800Y126000D02*
Y135081D01*
G01X1472500Y123700D02*
X1474800Y126000D01*
G01X1467014Y130219D02*
X1468755Y128478D01*
G01X1467014Y131923D02*
Y130219D01*
G01X1467465Y132374D02*
X1467014Y131923D01*
G01X1467465Y140975D02*
Y132374D01*
G01X1474930Y148440D02*
X1467465Y140975D01*
G01X1474930Y167270D02*
Y148440D01*
G01X1493965Y155718D02*
X1498271Y160024D01*
G01X1493965Y154169D02*
Y155718D01*
G01X1494633Y153501D02*
X1493965Y154169D01*
G01X1494633Y153499D02*
Y153501D01*
G01X1494645Y153487D02*
X1494633Y153499D01*
G01X1494645Y152181D02*
Y153487D01*
G01X1493500Y151036D02*
X1494645Y152181D01*
G01X1493500Y150298D02*
Y151036D01*
G01X1494435Y149363D02*
X1493500Y150298D01*
G01X1494435Y143567D02*
Y149363D01*
G01X1487480Y136612D02*
X1494435Y143567D01*
G01X1487480Y134878D02*
Y136612D01*
G01X1485863Y133261D02*
X1487480Y134878D01*
G01X1482711Y133261D02*
X1485863D01*
G01X1481517Y132067D02*
X1482711Y133261D01*
G01X1481517Y125160D02*
Y132067D01*
G01X1482455Y124222D02*
X1481517Y125160D01*
G01X1465361Y133247D02*
Y174973D01*
G01X1471238Y106773D02*
Y107561D01*
G01X1471237Y106772D02*
X1471238Y106773D01*
G01X1478337Y150122D02*
Y169102D01*
G01X1475200Y146985D02*
X1478337Y150122D01*
G01X1475200Y142600D02*
Y146985D01*
G01X1486532Y141147D02*
Y163681D01*
G01X1478661Y133276D02*
X1486532Y141147D01*
G01X1490237Y152214D02*
Y156346D01*
G01X1493428Y149023D02*
X1490237Y152214D01*
G01X1493428Y145325D02*
Y149023D01*
G01X1480565Y132462D02*
X1493428Y145325D01*
G01X1485580Y141542D02*
X1477709Y133671D01*
G01X1485580Y164210D02*
Y141542D01*
G01X1472230Y128950D02*
X1473100D01*
G01X1471318Y129862D02*
X1472230Y128950D01*
G01X1471318Y134859D02*
Y129862D01*
G01X1480241Y143782D02*
X1471318Y134859D01*
G01X1480241Y168312D02*
Y143782D01*
G01X1525930Y194086D02*
X1531069Y199225D01*
G01X1525930Y190131D02*
Y194086D01*
G01X1513299Y177500D02*
X1525930Y190131D01*
G01X1505771Y177500D02*
X1513299D01*
G01X1491160Y162889D02*
X1505771Y177500D01*
G01X1491160Y158616D02*
Y162889D01*
G01X1489285Y156741D02*
X1491160Y158616D01*
G01X1472138Y192661D02*
X1469560D01*
G01X1488273Y208796D02*
X1472138Y192661D01*
G01X1494381Y208796D02*
X1488273D01*
G01X1503268Y217683D02*
X1494381Y208796D01*
G01X1503268Y218955D02*
Y217683D01*
G01X1485420Y167019D02*
X1483676Y165275D01*
G01X1485420Y174019D02*
Y167019D01*
G01X1487457Y176056D02*
X1485420Y174019D01*
G01X1487500Y176056D02*
X1487457D01*
G01X1487500Y179118D02*
Y176056D01*
G01X1487439Y179179D02*
X1487500Y179118D01*
G01X1487439Y180485D02*
Y179179D01*
G01X1488362Y181408D02*
X1487439Y180485D01*
G01X1489079Y181408D02*
X1488362D01*
G01X1494849Y187178D02*
X1489079Y181408D01*
G01X1503102Y187178D02*
X1494849D01*
G01X1506664Y190740D02*
X1503102Y187178D01*
G01X1507101Y190740D02*
X1506664D01*
G01X1507102Y190741D02*
X1507101Y190740D01*
G01X1508680Y190741D02*
X1507102D01*
G01X1508681Y190740D02*
X1508680Y190741D01*
G01X1515894Y190740D02*
X1508681D01*
G01X1520225Y195071D02*
X1515894Y190740D01*
G01X1520225Y195682D02*
Y195071D01*
G01X1524610Y200067D02*
X1520225Y195682D01*
G01X1524610Y206812D02*
Y200067D01*
G01X1541002Y223204D02*
X1524610Y206812D01*
G01X1486372Y166349D02*
X1484628Y164605D01*
G01X1486372Y173624D02*
Y166349D01*
G01X1487852Y175104D02*
X1486372Y173624D01*
G01X1490142Y175104D02*
X1487852D01*
G01X1490820Y175782D02*
X1490142Y175104D01*
G01X1490820Y179704D02*
Y175782D01*
G01X1490893Y179777D02*
X1490820Y179704D01*
G01X1490893Y180040D02*
Y179777D01*
G01X1491816Y180963D02*
X1490893Y180040D01*
G01X1492079Y180963D02*
X1491816D01*
G01X1497342Y186226D02*
X1492079Y180963D01*
G01X1503497Y186226D02*
X1497342D01*
G01X1507059Y189788D02*
X1503497Y186226D01*
G01X1507496Y189788D02*
X1507059D01*
G01X1507497Y189789D02*
X1507496Y189788D01*
G01X1508285Y189789D02*
X1507497D01*
G01X1508286Y189788D02*
X1508285Y189789D01*
G01X1519633Y189788D02*
X1508286D01*
G01X1521177Y191332D02*
X1519633Y189788D01*
G01X1521177Y195287D02*
Y191332D01*
G01X1525562Y199672D02*
X1521177Y195287D01*
G01X1525562Y206417D02*
Y199672D01*
G01X1549626Y230481D02*
X1525562Y206417D01*
G01X1521856Y208115D02*
X1535817Y222076D01*
G01X1521856Y201098D02*
Y208115D01*
G01X1515958Y195200D02*
X1521856Y201098D01*
G01X1507566Y195200D02*
X1515958D01*
G01X1502148Y189782D02*
X1507566Y195200D01*
G01X1493383Y189782D02*
X1502148D01*
G01X1485500Y181899D02*
X1493383Y189782D01*
G01X1485500Y179543D02*
Y181899D01*
G01X1483448Y177491D02*
X1485500Y179543D01*
G01X1483448Y174278D02*
Y177491D01*
G01X1483447Y174277D02*
X1483448Y174278D01*
G01X1483447Y173323D02*
Y174277D01*
G01X1483448Y173322D02*
X1483447Y173323D01*
G01X1483448Y169889D02*
Y173322D01*
G01X1481393Y167834D02*
X1483448Y169889D01*
G01X1471506Y195198D02*
X1469100D01*
G01X1487208Y210900D02*
X1471506Y195198D01*
G01X1491419Y210900D02*
X1487208D01*
G01X1497237Y216718D02*
X1491419Y210900D01*
G01X1497237Y217281D02*
Y216718D01*
G01X1469888Y206854D02*
Y201169D01*
G01X1475438Y212404D02*
X1469888Y206854D01*
G01X1490497Y212404D02*
X1475438D01*
G01X1494382Y216289D02*
X1490497Y212404D01*
G01X1494382Y224311D02*
Y216289D01*
G01X1520935Y215436D02*
Y224010D01*
G01X1514101Y208602D02*
X1520935Y215436D01*
G01X1514101Y208291D02*
Y208602D01*
G01X1513178Y207368D02*
X1514101Y208291D01*
G01X1510100Y207368D02*
X1513178D01*
G01X1497584Y194852D02*
X1510100Y207368D01*
G01X1485141Y194852D02*
X1497584D01*
G01X1473243Y182954D02*
X1485141Y194852D01*
G01X1473243Y181508D02*
Y182954D01*
G01X1466313Y174578D02*
X1473243Y181508D01*
G01X1493628Y216599D02*
Y218947D01*
G01X1490185Y213156D02*
X1493628Y216599D01*
G01X1475126Y213156D02*
X1490185D01*
G01X1469136Y207166D02*
X1475126Y213156D01*
G01X1469136Y205377D02*
Y207166D01*
G01X1519552Y209071D02*
X1533913Y223432D01*
G01X1519552Y202054D02*
Y209071D01*
G01X1515002Y197504D02*
X1519552Y202054D01*
G01X1506610Y197504D02*
X1515002D01*
G01X1501192Y192086D02*
X1506610Y197504D01*
G01X1489306Y192086D02*
X1501192D01*
G01X1480690Y183470D02*
X1489306Y192086D01*
G01X1480690Y170391D02*
Y183470D01*
G01X1479089Y168790D02*
X1480690Y170391D01*
G01X1516628Y216869D02*
Y230331D01*
G01X1514255Y214496D02*
X1516628Y216869D01*
G01X1511431Y214496D02*
X1514255D01*
G01X1500667Y203732D02*
X1511431Y214496D01*
G01X1498992Y203732D02*
X1500667D01*
G01X1494385Y199125D02*
X1498992Y203732D01*
G01X1492136Y199125D02*
X1494385D01*
G01X1474883Y181518D02*
Y182275D01*
G01X1468660Y175295D02*
X1474883Y181518D01*
G01X1468660Y171840D02*
Y175295D01*
G01X1473354Y167146D02*
X1468660Y171840D01*
G01X1470387Y184139D02*
Y182693D01*
G01X1487148Y200900D02*
X1470387Y184139D01*
G01X1494530Y200900D02*
X1487148D01*
G01X1513003Y219373D02*
X1494530Y200900D01*
G01X1523008Y207637D02*
X1540010Y224639D01*
G01X1523008Y200687D02*
Y207637D01*
G01X1523007Y200686D02*
X1523008Y200687D01*
G01X1523007Y200619D02*
Y200686D01*
G01X1516407Y194019D02*
X1523007Y200619D01*
G01X1514023Y194019D02*
X1516407D01*
G01X1511504Y191500D02*
X1514023Y194019D01*
G01X1505496Y191500D02*
X1511504D01*
G01X1502626Y188630D02*
X1505496Y191500D01*
G01X1493890Y188630D02*
X1502626D01*
G01X1486687Y181427D02*
X1493890Y188630D01*
G01X1486687Y179100D02*
Y181427D01*
G01X1484600Y177013D02*
X1486687Y179100D01*
G01X1484600Y169411D02*
Y177013D01*
G01X1482545Y167356D02*
X1484600Y169411D01*
G01X1469812Y172388D02*
X1474930Y167270D01*
G01X1469812Y174413D02*
Y172388D01*
G01X1476459Y181060D02*
X1469812Y174413D01*
G01X1476459Y183532D02*
Y181060D01*
G01X1486627Y193700D02*
X1476459Y183532D01*
G01X1499100Y193700D02*
X1486627D01*
G01X1505237Y199837D02*
X1499100Y193700D01*
G01X1512500Y199837D02*
X1505237D01*
G01X1466036Y186419D02*
Y183865D01*
G01X1469850Y190233D02*
X1466036Y186419D01*
G01X1472803Y190233D02*
X1469850D01*
G01X1489462Y206892D02*
X1472803Y190233D01*
G01X1495171Y206892D02*
X1489462D01*
G01X1505173Y216894D02*
X1495171Y206892D01*
G01X1505173Y217798D02*
Y216894D01*
G01X1505172Y217799D02*
X1505173Y217798D01*
G01X1505172Y219745D02*
Y217799D01*
G01X1494052Y202052D02*
X1511851Y219851D01*
G01X1486670Y202052D02*
X1494052D01*
G01X1469234Y184616D02*
X1486670Y202052D01*
G01X1469234Y183662D02*
Y184616D01*
G01X1469235Y183661D02*
X1469234Y183662D01*
G01X1469235Y183171D02*
Y183661D01*
G01X1526882Y193691D02*
X1532021Y198830D01*
G01X1526882Y189736D02*
Y193691D01*
G01X1513694Y176548D02*
X1526882Y189736D01*
G01X1507048Y176548D02*
X1513694D01*
G01X1493200Y162700D02*
X1507048Y176548D01*
G01X1507705Y167775D02*
X1529004Y189074D01*
G01X1506324Y167775D02*
X1507705D01*
G01X1506323Y167776D02*
X1506324Y167775D01*
G01X1501775Y167776D02*
X1506323D01*
G01X1498955Y164956D02*
X1501775Y167776D01*
G01X1498955Y162845D02*
Y164956D01*
G01X1499069Y162731D02*
X1498955Y162845D01*
G01X1499069Y162460D02*
Y162731D01*
G01X1499276Y162253D02*
X1499069Y162460D01*
G01X1499276Y160947D02*
Y162253D01*
G01X1498353Y160024D02*
X1499276Y160947D01*
G01X1498271Y160024D02*
X1498353D01*
G01X1495134Y215977D02*
Y223999D01*
G01X1490809Y211652D02*
X1495134Y215977D01*
G01X1477910Y211652D02*
X1490809D01*
G01X1477035Y210777D02*
X1477910Y211652D01*
G01X1477035Y207720D02*
Y210777D01*
G01X1473165Y203850D02*
X1477035Y207720D01*
G01X1473165Y201419D02*
Y203850D01*
G01X1519983Y216747D02*
Y224405D01*
G01X1515428Y212192D02*
X1519983Y216747D01*
G01X1513387Y212192D02*
X1515428D01*
G01X1502473Y201278D02*
X1513387Y212192D01*
G01X1499549Y201278D02*
X1502473D01*
G01X1494075Y195804D02*
X1499549Y201278D01*
G01X1485536Y195804D02*
X1494075D01*
G01X1485535Y195805D02*
X1485536Y195804D01*
G01X1484747Y195805D02*
X1485535D01*
G01X1472291Y183349D02*
X1484747Y195805D01*
G01X1472291Y181903D02*
Y183349D01*
G01X1526877Y217460D02*
Y228177D01*
G01X1518800Y209383D02*
X1526877Y217460D01*
G01X1518800Y202366D02*
Y209383D01*
G01X1514690Y198256D02*
X1518800Y202366D01*
G01X1506298Y198256D02*
X1514690D01*
G01X1500880Y192838D02*
X1506298Y198256D01*
G01X1488994Y192838D02*
X1500880D01*
G01X1479938Y183782D02*
X1488994Y192838D01*
G01X1479938Y170703D02*
Y183782D01*
G01X1478337Y169102D02*
X1479938Y170703D01*
G01X1471609Y204791D02*
Y201249D01*
G01X1474439Y207621D02*
X1471609Y204791D01*
G01X1471339Y183744D02*
Y182298D01*
G01X1484352Y196757D02*
X1471339Y183744D01*
G01X1493647Y196757D02*
X1484352D01*
G01X1499320Y202430D02*
X1493647Y196757D01*
G01X1501279Y202430D02*
X1499320D01*
G01X1512193Y213344D02*
X1501279Y202430D01*
G01X1515233Y213344D02*
X1512193D01*
G01X1518830Y216941D02*
X1515233Y213344D01*
G01X1518830Y224882D02*
Y216941D01*
G01X1481195Y214718D02*
X1489398Y222921D01*
G01X1474560Y214718D02*
X1481195D01*
G01X1474496Y214654D02*
X1474560Y214718D01*
G01X1474374Y214654D02*
X1474496D01*
G01X1467543Y207823D02*
X1474374Y214654D01*
G01X1467543Y205912D02*
Y207823D01*
G01X1523082Y194498D02*
X1527467Y198883D01*
G01X1523082Y190543D02*
Y194498D01*
G01X1520423Y187884D02*
X1523082Y190543D01*
G01X1510480Y187884D02*
X1520423D01*
G01X1499600Y177004D02*
X1510480Y187884D01*
G01X1499600Y175511D02*
Y177004D01*
G01X1497366Y173277D02*
X1499600Y175511D01*
G01X1494185Y173277D02*
X1497366D01*
G01X1493250Y174212D02*
X1494185Y173277D01*
G01X1491944Y174212D02*
X1493250D01*
G01X1491021Y173289D02*
X1491944Y174212D01*
G01X1491021Y168170D02*
Y173289D01*
G01X1486532Y163681D02*
X1491021Y168170D01*
G01X1507221Y168728D02*
X1527834Y189341D01*
G01X1501380Y168728D02*
X1507221D01*
G01X1495437Y162785D02*
X1501380Y168728D01*
G01X1495437Y162227D02*
Y162785D01*
G01X1493363Y160153D02*
X1495437Y162227D01*
G01X1493363Y159472D02*
Y160153D01*
G01X1490237Y156346D02*
X1493363Y159472D01*
G01X1487324Y165954D02*
X1485580Y164210D01*
G01X1487324Y173229D02*
Y165954D01*
G01X1488247Y174152D02*
X1487324Y173229D01*
G01X1490537Y174152D02*
X1488247D01*
G01X1491549Y175164D02*
X1490537Y174152D01*
G01X1494219Y175164D02*
X1491549D01*
G01X1495360Y176305D02*
X1494219Y175164D01*
G01X1495378Y176305D02*
X1495360D01*
G01X1495404Y176331D02*
X1495378Y176305D01*
G01X1495436Y176331D02*
X1495404D01*
G01X1496359Y177254D02*
X1495436Y176331D01*
G01X1496359Y177304D02*
Y177254D01*
G01X1507891Y188836D02*
X1496359Y177304D01*
G01X1520028Y188836D02*
X1507891D01*
G01X1522130Y190938D02*
X1520028Y188836D01*
G01X1522130Y194893D02*
Y190938D01*
G01X1526515Y199278D02*
X1522130Y194893D01*
G01X1526515Y206023D02*
Y199278D01*
G01X1550805Y230313D02*
X1526515Y206023D01*
G01X1524234Y194020D02*
X1528619Y198405D01*
G01X1524234Y190065D02*
Y194020D01*
G01X1518801Y184632D02*
X1524234Y190065D01*
G01X1512743Y184632D02*
X1518801D01*
G01X1511100Y186275D02*
X1512743Y184632D01*
G01X1493155Y172078D02*
X1492597Y172636D01*
G01X1497847Y172078D02*
X1493155D01*
G01X1511100Y185331D02*
X1497847Y172078D01*
G01X1511100Y186275D02*
Y185331D01*
G01X1472009Y191185D02*
X1469455D01*
G01X1488668Y207844D02*
X1472009Y191185D01*
G01X1494776Y207844D02*
X1488668D01*
G01X1504220Y217288D02*
X1494776Y207844D01*
G01X1504220Y219350D02*
Y217288D01*
G01X1481843Y169914D02*
X1480241Y168312D01*
G01X1481843Y170868D02*
Y169914D01*
G01X1481842Y170869D02*
X1481843Y170868D01*
G01X1481842Y182992D02*
Y170869D01*
G01X1489784Y190934D02*
X1481842Y182992D01*
G01X1501670Y190934D02*
X1489784D01*
G01X1507088Y196352D02*
X1501670Y190934D01*
G01X1515480Y196352D02*
X1507088D01*
G01X1520704Y201576D02*
X1515480Y196352D01*
G01X1520704Y208593D02*
Y201576D01*
G01X1534665Y222554D02*
X1520704Y208593D01*
G01X1468384Y207478D02*
Y205689D01*
G01X1474872Y213966D02*
X1468384Y207478D01*
G01X1482577Y213966D02*
X1474872D01*
G01X1482578Y213965D02*
X1482577Y213966D01*
G01X1483200Y213965D02*
X1482578D01*
G01X1483201Y213966D02*
X1483200Y213965D01*
G01X1488671Y213966D02*
X1483201D01*
G01X1489596Y214891D02*
X1488671Y213966D01*
G01X1489596Y222055D02*
Y214891D01*
G01X1470556Y257000D02*
X1469856Y257700D01*
G01X1470556Y256900D02*
Y257000D01*
G01X1470950Y229669D02*
Y226492D01*
G01X1525226Y281914D02*
X1521962Y278650D01*
G01X1482847Y278223D02*
X1478628Y282442D01*
G01X1483856Y278223D02*
X1482847D01*
G01X1484717Y277362D02*
X1483856Y278223D01*
G01X1484717Y269845D02*
Y277362D01*
G01X1483646Y268774D02*
X1484717Y269845D01*
G01X1482638Y268774D02*
X1483646D01*
G01X1481568Y267704D02*
X1482638Y268774D01*
G01X1481568Y266695D02*
Y267704D01*
G01X1479847Y264974D02*
X1481568Y266695D01*
G01X1479847Y255882D02*
Y264974D01*
G01X1480576Y255153D02*
X1479847Y255882D01*
G01X1480576Y251847D02*
Y255153D01*
G01X1478084Y249355D02*
X1480576Y251847D01*
G01X1478084Y243163D02*
Y249355D01*
G01X1473228Y238307D02*
X1478084Y243163D01*
G01X1470314Y238307D02*
X1473228D01*
G01X1472916Y239059D02*
X1470002D01*
G01X1477332Y243475D02*
X1472916Y239059D01*
G01X1477332Y250332D02*
Y243475D01*
G01X1478500Y251500D02*
X1477332Y250332D01*
G01X1478500Y252000D02*
Y251500D01*
G01X1480800Y221279D02*
X1471057D01*
G01X1482004Y222483D02*
X1480800Y221279D01*
G01X1503267Y218956D02*
X1503268Y218955D01*
G01X1503267Y220534D02*
Y218956D01*
G01X1505168Y222435D02*
X1503267Y220534D01*
G01X1505168Y235552D02*
Y222435D01*
G01X1502000Y238720D02*
X1505168Y235552D01*
G01X1502000Y250223D02*
Y238720D01*
G01X1502165Y250388D02*
X1502000Y250223D01*
G01X1502165Y251200D02*
Y250388D01*
G01X1498516Y228445D02*
X1494382Y224311D01*
G01X1500690Y228445D02*
X1498516D01*
G01X1502602Y230357D02*
X1500690Y228445D01*
G01X1502602Y231311D02*
Y230357D01*
G01X1502601Y231312D02*
X1502602Y231311D01*
G01X1502601Y235708D02*
Y231312D01*
G01X1500015Y238294D02*
X1502601Y235708D01*
G01X1500015Y245800D02*
Y238294D01*
G01X1500002Y245800D02*
X1500015D01*
G01X1499988Y245814D02*
X1500002Y245800D01*
G01X1499988Y245865D02*
Y245814D01*
G01X1496984Y248869D02*
X1499988Y245865D01*
G01X1496992Y248877D02*
X1496984Y248869D01*
G01X1496992Y251461D02*
Y248877D01*
G01X1497701Y252170D02*
X1496992Y251461D01*
G01X1498451Y253000D02*
X1497701Y252170D01*
G01X1498657Y253206D02*
X1498451Y253000D01*
G01X1500416Y253206D02*
X1498657D01*
G01X1502097Y254887D02*
X1500416Y253206D01*
G01X1502097Y255841D02*
Y254887D01*
G01X1502096Y255842D02*
X1502097Y255841D01*
G01X1502096Y259870D02*
Y255842D01*
G01X1509878Y267652D02*
X1502096Y259870D01*
G01X1509878Y277080D02*
Y267652D01*
G01X1509879Y277081D02*
X1509878Y277080D01*
G01X1509879Y278035D02*
Y277081D01*
G01X1509121Y278793D02*
X1509879Y278035D01*
G01X1509121Y282367D02*
Y278793D01*
G01X1520386Y279303D02*
X1524101Y283018D01*
G01X1520386Y273349D02*
Y279303D01*
G01X1525699Y268036D02*
X1520386Y273349D01*
G01X1525699Y254437D02*
Y268036D01*
G01X1529626Y250510D02*
X1525699Y254437D01*
G01X1520935Y224010D02*
X1529213Y232288D01*
G01X1472119Y264710D02*
Y303628D01*
G01X1475130Y261699D02*
X1472119Y264710D01*
G01X1475130Y257901D02*
Y261699D01*
G01X1475672Y257359D02*
X1475130Y257901D01*
G01X1475672Y253828D02*
Y257359D01*
G01X1476580Y252920D02*
X1475672Y253828D01*
G01X1476580Y243787D02*
Y252920D01*
G01X1472619Y239826D02*
X1476580Y243787D01*
G01X1466089Y239826D02*
X1472619D01*
G01X1493628Y218947D02*
X1491438Y221137D01*
G01X1519300Y241900D02*
Y245196D01*
G01X1518600Y241200D02*
X1519300Y241900D01*
G01X1518600Y239252D02*
Y241200D01*
G01X1514958Y235610D02*
X1518600Y239252D01*
G01X1514958Y232001D02*
Y235610D01*
G01X1516628Y230331D02*
X1514958Y232001D01*
G01X1500192Y257056D02*
X1499070Y255934D01*
G01X1500192Y260660D02*
Y257056D01*
G01X1505410Y265878D02*
X1500192Y260660D01*
G01X1505410Y272903D02*
Y265878D01*
G01X1506065Y273558D02*
X1505410Y272903D01*
G01X1506065Y289838D02*
Y273558D01*
G01X1495242Y278368D02*
X1496698Y279824D01*
G01X1495242Y275489D02*
Y278368D01*
G01X1495285Y275446D02*
X1495242Y275489D01*
G01X1495285Y274412D02*
Y275446D01*
G01X1495242Y274369D02*
X1495285Y274412D01*
G01X1495242Y273067D02*
Y274369D01*
G01X1495285Y273024D02*
X1495242Y273067D01*
G01X1495285Y271215D02*
Y273024D01*
G01X1497500Y269000D02*
X1495285Y271215D01*
G01X1497500Y267056D02*
Y269000D01*
G01X1496544Y266100D02*
X1497500Y267056D01*
G01X1496300Y266100D02*
X1496544D01*
G01X1494704Y264504D02*
X1496300Y266100D01*
G01X1491246Y264504D02*
X1494704D01*
G01X1487780Y261038D02*
X1491246Y264504D01*
G01X1487780Y250532D02*
Y261038D01*
G01X1488078Y250234D02*
X1487780Y250532D01*
G01X1488078Y250213D02*
Y250234D01*
G01X1490063Y248228D02*
X1488078Y250213D01*
G01X1490063Y234930D02*
Y248228D01*
G01X1487142Y232009D02*
X1490063Y234930D01*
G01X1487142Y223857D02*
Y232009D01*
G01X1483060Y219775D02*
X1487142Y223857D01*
G01X1471681Y219775D02*
X1483060D01*
G01X1482748Y220527D02*
X1471369D01*
G01X1486390Y224169D02*
X1482748Y220527D01*
G01X1486390Y232819D02*
Y224169D01*
G01X1489076Y235505D02*
X1486390Y232819D01*
G01X1489076Y245684D02*
Y235505D01*
G01X1486926Y247834D02*
X1489076Y245684D01*
G01X1487735Y244265D02*
X1487500Y244500D01*
G01X1487735Y237812D02*
Y244265D01*
G01X1473993Y224070D02*
X1487735Y237812D01*
G01X1471720Y224070D02*
X1473993D01*
G01X1506817Y272435D02*
Y289526D01*
G01X1507003Y272249D02*
X1506817Y272435D01*
G01X1513003Y220233D02*
Y219373D01*
G01X1513806Y221036D02*
X1513003Y220233D01*
G01X1513806Y235854D02*
Y221036D01*
G01X1511155Y238505D02*
X1513806Y235854D01*
G01X1511155Y241355D02*
Y238505D01*
G01X1512612Y242812D02*
X1511155Y241355D01*
G01X1512612Y255251D02*
Y242812D01*
G01X1517530Y260169D02*
X1512612Y255251D01*
G01X1517530Y280488D02*
Y260169D01*
G01X1472900Y225575D02*
X1471097D01*
G01X1484310Y236985D02*
X1472900Y225575D01*
G01X1484310Y243192D02*
Y236985D01*
G01X1485033Y243915D02*
X1484310Y243192D01*
G01X1485033Y245221D02*
Y243915D01*
G01X1484310Y245944D02*
X1485033Y245221D01*
G01X1484310Y249110D02*
Y245944D01*
G01X1486276Y251076D02*
X1484310Y249110D01*
G01X1486276Y261662D02*
Y251076D01*
G01X1490973Y266359D02*
X1486276Y261662D01*
G01X1490973Y268023D02*
Y266359D01*
G01X1492009Y269059D02*
X1490973Y268023D01*
G01X1492009Y271184D02*
Y269059D01*
G01X1491082Y272111D02*
X1492009Y271184D01*
G01X1491082Y284666D02*
Y272111D01*
G01X1472518Y240789D02*
X1465988D01*
G01X1473876Y242147D02*
X1472518Y240789D01*
G01X1473876Y243753D02*
Y242147D01*
G01X1473180Y244449D02*
X1473876Y243753D01*
G01X1473180Y248080D02*
Y244449D01*
G01X1472600Y248660D02*
X1473180Y248080D01*
G01X1472600Y255210D02*
Y248660D01*
G01X1474096Y256706D02*
X1472600Y255210D01*
G01X1507072Y221645D02*
X1505172Y219745D01*
G01X1507072Y236342D02*
Y221645D01*
G01X1505554Y237860D02*
X1507072Y236342D01*
G01X1505554Y250446D02*
Y237860D01*
G01X1504215Y251785D02*
X1505554Y250446D01*
G01X1504215Y254828D02*
Y251785D01*
G01X1504196Y254847D02*
X1504215Y254828D01*
G01X1504196Y258653D02*
Y254847D01*
G01X1504772Y259229D02*
X1504196Y258653D01*
G01X1513906Y258186D02*
Y281453D01*
G01X1511460Y255740D02*
X1513906Y258186D01*
G01X1511460Y243290D02*
Y255740D01*
G01X1510003Y241833D02*
X1511460Y243290D01*
G01X1510003Y238027D02*
Y241833D01*
G01X1511851Y236179D02*
X1510003Y238027D01*
G01X1511851Y219851D02*
Y236179D01*
G01X1504813Y277241D02*
Y301504D01*
G01X1502672Y275100D02*
X1504813Y277241D01*
G01X1502672Y264911D02*
Y275100D01*
G01X1497363Y259602D02*
X1502672Y264911D01*
G01X1497363Y255313D02*
Y259602D01*
G01X1494336Y252286D02*
X1497363Y255313D01*
G01X1494336Y248116D02*
Y252286D01*
G01X1497584Y244868D02*
X1494336Y248116D01*
G01X1497584Y244817D02*
Y244868D01*
G01X1497610Y244791D02*
X1497584Y244817D01*
G01X1497610Y237298D02*
Y244791D01*
G01X1500196Y234712D02*
X1497610Y237298D01*
G01X1500196Y231810D02*
Y234712D01*
G01X1499559Y231173D02*
X1500196Y231810D01*
G01X1469200Y230148D02*
Y228983D01*
G01X1473144Y234092D02*
X1469200Y230148D01*
G01X1478504Y234092D02*
X1473144D01*
G01X1483457Y239045D02*
X1478504Y234092D01*
G01X1483457Y244568D02*
Y239045D01*
G01X1467941Y247350D02*
X1465840D01*
G01X1469004Y246287D02*
X1467941Y247350D01*
G01X1509873Y279105D02*
Y282055D01*
G01X1510631Y278347D02*
X1509873Y279105D01*
G01X1510631Y276769D02*
Y278347D01*
G01X1510630Y276768D02*
X1510631Y276769D01*
G01X1510630Y267340D02*
Y276768D01*
G01X1502848Y259558D02*
X1510630Y267340D01*
G01X1502848Y256154D02*
Y259558D01*
G01X1502849Y256153D02*
X1502848Y256154D01*
G01X1502849Y254575D02*
Y256153D01*
G01X1502848Y254574D02*
X1502849Y254575D01*
G01X1502848Y254549D02*
Y254574D01*
G01X1500245Y251946D02*
X1502848Y254549D01*
G01X1498819Y251946D02*
X1500245D01*
G01X1497896Y251023D02*
X1498819Y251946D01*
G01X1497896Y249504D02*
Y251023D01*
G01X1500800Y246600D02*
X1497896Y249504D01*
G01X1500800Y238573D02*
Y246600D01*
G01X1503353Y236020D02*
X1500800Y238573D01*
G01X1503353Y231624D02*
Y236020D01*
G01X1503354Y231623D02*
X1503353Y231624D01*
G01X1503354Y230045D02*
Y231623D01*
G01X1501002Y227693D02*
X1503354Y230045D01*
G01X1498828Y227693D02*
X1501002D01*
G01X1495134Y223999D02*
X1498828Y227693D01*
G01X1519434Y272749D02*
Y279698D01*
G01X1524747Y267436D02*
X1519434Y272749D01*
G01X1524747Y253832D02*
Y267436D01*
G01X1527874Y250705D02*
X1524747Y253832D01*
G01X1526591Y245645D02*
X1527874Y246928D01*
G01X1526591Y239550D02*
Y245645D01*
G01X1528261Y237880D02*
X1526591Y239550D01*
G01X1519983Y224405D02*
X1528261Y232683D01*
G01X1526877Y228177D02*
X1530165Y231465D01*
G01X1482400Y247300D02*
Y248000D01*
G01X1481810Y246710D02*
X1482400Y247300D01*
G01X1481810Y238581D02*
Y246710D01*
G01X1478080Y234851D02*
X1481810Y238581D01*
G01X1474251Y234851D02*
X1478080D01*
G01X1474244Y234844D02*
X1474251Y234851D01*
G01X1472832Y234844D02*
X1474244D01*
G01X1468448Y230460D02*
X1472832Y234844D01*
G01X1468448Y229677D02*
Y230460D01*
G01X1521999Y228051D02*
X1518830Y224882D01*
G01X1521999Y232519D02*
Y228051D01*
G01X1525541Y236061D02*
X1521999Y232519D01*
G01X1525541Y245420D02*
Y236061D01*
G01X1521999Y248962D02*
X1525541Y245420D01*
G01X1521999Y268201D02*
Y248962D01*
G01X1518482Y271718D02*
X1521999Y268201D01*
G01X1518482Y280093D02*
Y271718D01*
G01X1467854Y250000D02*
X1466824D01*
G01X1470700Y252846D02*
X1467854Y250000D01*
G01X1470950Y252846D02*
X1470700D01*
G01X1489398Y224625D02*
X1491265Y226492D01*
G01X1489398Y222921D02*
Y224625D01*
G01X1483372Y219023D02*
X1471993D01*
G01X1487894Y223545D02*
X1483372Y219023D01*
G01X1487894Y230909D02*
Y223545D01*
G01X1490815Y233830D02*
X1487894Y230909D01*
G01X1490815Y237900D02*
Y233830D01*
G01X1493276Y240361D02*
X1490815Y237900D01*
G01X1493276Y246100D02*
Y240361D01*
G01X1488532Y250844D02*
X1493276Y246100D01*
G01X1488532Y260726D02*
Y250844D01*
G01X1491558Y263752D02*
X1488532Y260726D01*
G01X1495260Y263752D02*
X1491558D01*
G01X1498252Y266744D02*
X1495260Y263752D01*
G01X1498252Y271096D02*
Y266744D01*
G01X1496812Y272536D02*
X1498252Y271096D01*
G01X1496812Y273718D02*
Y272536D01*
G01X1469993Y244676D02*
X1471604Y246287D01*
G01X1468247Y244676D02*
X1469993D01*
G01X1467324Y243753D02*
X1468247Y244676D01*
G01X1467324Y243193D02*
Y243753D01*
G01X1468074Y270964D02*
Y315093D01*
G01X1483684Y218271D02*
X1472305D01*
G01X1488646Y223233D02*
X1483684Y218271D01*
G01X1488646Y230069D02*
Y223233D01*
G01X1491621Y233044D02*
X1488646Y230069D01*
G01X1491621Y237642D02*
Y233044D01*
G01X1494028Y240049D02*
X1491621Y237642D01*
G01X1494028Y246412D02*
Y240049D01*
G01X1489284Y251156D02*
X1494028Y246412D01*
G01X1489284Y260089D02*
Y251156D01*
G01X1492195Y263000D02*
X1489284Y260089D01*
G01X1495572Y263000D02*
X1492195D01*
G01X1499004Y266432D02*
X1495572Y263000D01*
G01X1499004Y277004D02*
Y266432D01*
G01X1501257Y279257D02*
X1499004Y277004D01*
G01X1501257Y280563D02*
Y279257D01*
G01X1466404Y245350D02*
Y243419D01*
G01X1468450Y252900D02*
X1468194D01*
G01X1466076Y231348D02*
Y230936D01*
G01X1471883Y237155D02*
X1466076Y231348D01*
G01X1473706Y237155D02*
X1471883D01*
G01X1479236Y242685D02*
X1473706Y237155D01*
G01X1479236Y248726D02*
Y242685D01*
G01X1481728Y251218D02*
X1479236Y248726D01*
G01X1481728Y255631D02*
Y251218D01*
G01X1481000Y256359D02*
X1481728Y255631D01*
G01X1481000Y263000D02*
Y256359D01*
G01X1483834Y265834D02*
X1481000Y263000D01*
G01X1483856Y265834D02*
X1483834D01*
G01X1484717Y266695D02*
X1483856Y265834D01*
G01X1484717Y266717D02*
Y266695D01*
G01X1485104Y267104D02*
X1484717Y266717D01*
G01X1485104Y267736D02*
Y267104D01*
G01X1485965Y268597D02*
X1485104Y267736D01*
G01X1486619Y268597D02*
X1485965D01*
G01X1487867Y269845D02*
X1486619Y268597D01*
G01X1487867Y277361D02*
Y269845D01*
G01X1484927Y280301D02*
X1487867Y277361D01*
G01X1479759Y224801D02*
X1479700D01*
G01X1477458Y222500D02*
X1479759Y224801D01*
G01X1471214Y222500D02*
X1477458D01*
G01X1504219Y219351D02*
X1504220Y219350D01*
G01X1504219Y220139D02*
Y219351D01*
G01X1506120Y222040D02*
X1504219Y220139D01*
G01X1506120Y235947D02*
Y222040D01*
G01X1504048Y238019D02*
X1506120Y235947D01*
G01X1504048Y245472D02*
Y238019D01*
G01X1503842Y245678D02*
X1504048Y245472D01*
G01X1481567Y268774D02*
X1483247Y270454D01*
G01X1479489Y268774D02*
X1481567D01*
G01X1478628Y267913D02*
X1479489Y268774D01*
G01X1478628Y266695D02*
Y267913D01*
G01X1479000Y266323D02*
X1478628Y266695D01*
G01X1479000Y254500D02*
Y266323D01*
G01X1509050Y220126D02*
X1507524Y218600D01*
G01X1509050Y239963D02*
Y220126D01*
G01X1506796Y242217D02*
X1509050Y239963D01*
G01X1506796Y252575D02*
Y242217D01*
G01X1511842Y257621D02*
X1506796Y252575D01*
G01X1511842Y278200D02*
Y257621D01*
G01X1510625Y279417D02*
X1511842Y278200D01*
G01X1510625Y281743D02*
Y279417D01*
G01X1473211Y224822D02*
X1471408D01*
G01X1485785Y237396D02*
X1473211Y224822D01*
G01X1485785Y245533D02*
Y237396D01*
G01X1485062Y246256D02*
X1485785Y245533D01*
G01X1485062Y248498D02*
Y246256D01*
G01X1487028Y250464D02*
X1485062Y248498D01*
G01X1487028Y261350D02*
Y250464D01*
G01X1490943Y265265D02*
X1487028Y261350D01*
G01X1493023Y265265D02*
X1490943D01*
G01X1494534Y266776D02*
X1493023Y265265D01*
G01X1494534Y272712D02*
Y266776D01*
G01X1494491Y272755D02*
X1494534Y272712D01*
G01X1494491Y279291D02*
Y272755D01*
G01X1496600Y281400D02*
X1494491Y279291D01*
G01X1488076Y279293D02*
Y292473D01*
G01X1489600Y277769D02*
X1488076Y279293D01*
G01X1489600Y272530D02*
Y277769D01*
G01X1491016Y271114D02*
X1489600Y272530D01*
G01X1491016Y269845D02*
Y271114D01*
G01X1489945Y268774D02*
X1491016Y269845D01*
G01X1489945Y267669D02*
Y268774D01*
G01X1482424Y260148D02*
X1489945Y267669D01*
G01X1482424Y256565D02*
Y260148D01*
G01X1482880Y256109D02*
X1482424Y256565D01*
G01X1482880Y250740D02*
Y256109D01*
G01X1480388Y248248D02*
X1482880Y250740D01*
G01X1480388Y243163D02*
Y248248D01*
G01X1480389Y243162D02*
X1480388Y243163D01*
G01X1480389Y242208D02*
Y243162D01*
G01X1474184Y236003D02*
X1480389Y242208D01*
G01X1472674Y236003D02*
X1474184D01*
G01X1472667Y235996D02*
X1472674Y236003D01*
G01X1472354Y235996D02*
X1472667D01*
G01X1467229Y230871D02*
X1472354Y235996D01*
G01X1467229Y230459D02*
Y230871D01*
G01X1497138Y229597D02*
X1489596Y222055D01*
G01X1498304Y229597D02*
X1497138D01*
G01X1498311Y229604D02*
X1498304Y229597D01*
G01X1498899Y229604D02*
X1498311D01*
G01X1498906Y229597D02*
X1498899Y229604D01*
G01X1500212Y229597D02*
X1498906D01*
G01X1501449Y230834D02*
X1500212Y229597D01*
G01X1501449Y235230D02*
Y230834D01*
G01X1498862Y237817D02*
X1501449Y235230D01*
G01X1498862Y244272D02*
Y237817D01*
G01X1498863Y244273D02*
X1498862Y244272D01*
G01X1498863Y245309D02*
Y244273D01*
G01X1498836Y245336D02*
X1498863Y245309D01*
G01X1498836Y245387D02*
Y245336D01*
G01X1495830Y248393D02*
X1498836Y245387D01*
G01X1495830Y248685D02*
Y248393D01*
G01X1495835Y250141D02*
X1495830Y248685D01*
G01X1495836Y250142D02*
X1495835Y250141D01*
G01X1495836Y250582D02*
Y250142D01*
G01X1495838Y251176D02*
X1495836Y250582D01*
G01Y251179D02*
X1495838Y251176D01*
G01X1495836Y252015D02*
Y251179D01*
G01X1498179Y254358D02*
X1495836Y252015D01*
G01X1499938Y254358D02*
X1498179D01*
G01X1500944Y255364D02*
X1499938Y254358D01*
G01X1500944Y260348D02*
Y255364D01*
G01X1508726Y268130D02*
X1500944Y260348D01*
G01X1508726Y277558D02*
Y268130D01*
G01X1507969Y278315D02*
X1508726Y277558D01*
G01X1507969Y283163D02*
Y278315D01*
G01X1471661Y319743D02*
X1467323Y315405D01*
G01X1471661Y320901D02*
Y319743D01*
G01X1477200Y326440D02*
X1471661Y320901D01*
G01X1477200Y348999D02*
Y326440D01*
G01X1467323Y281622D02*
X1465603Y279902D01*
G01X1467323Y315405D02*
Y281622D01*
G01X1489838Y339470D02*
Y350011D01*
G01X1489019Y338651D02*
X1489838Y339470D01*
G01X1489019Y338615D02*
Y338651D01*
G01X1487904Y337500D02*
X1489019Y338615D01*
G01X1525226Y286726D02*
Y281914D01*
G01X1529000Y290500D02*
X1525226Y286726D01*
G01X1481568Y297328D02*
X1480098Y298798D01*
G01X1481568Y288742D02*
Y297328D01*
G01X1480498Y287672D02*
X1481568Y288742D01*
G01X1479489Y287672D02*
X1480498D01*
G01X1478628Y286811D02*
X1479489Y287672D01*
G01X1478628Y282442D02*
Y286811D01*
G01X1489800Y330500D02*
X1487000Y333300D01*
G01X1489800Y323360D02*
Y330500D01*
G01X1495092Y318068D02*
X1489800Y323360D01*
G01X1503538Y318068D02*
X1495092D01*
G01X1495810Y341200D02*
Y345269D01*
G01X1465377Y334817D02*
Y346977D01*
G01X1514095Y287341D02*
X1509121Y282367D01*
G01X1514095Y288659D02*
Y287341D01*
G01X1517152Y291716D02*
X1514095Y288659D01*
G01X1517152Y295022D02*
Y291716D01*
G01X1517153Y295023D02*
X1517152Y295022D01*
G01X1517153Y295977D02*
Y295023D01*
G01X1513500Y299630D02*
X1517153Y295977D01*
G01X1513500Y315059D02*
Y299630D01*
G01X1514067Y315626D02*
X1513500Y315059D01*
G01X1524101Y296100D02*
X1528587Y300586D01*
G01X1524101Y283018D02*
Y296100D01*
G01X1472119Y303628D02*
X1470649Y305098D01*
G01X1467803Y342424D02*
Y334204D01*
G01X1507170Y290943D02*
X1506065Y289838D01*
G01X1507170Y301276D02*
Y290943D01*
G01X1508252Y302358D02*
X1507170Y301276D01*
G01X1508252Y309773D02*
Y302358D01*
G01X1506127Y311898D02*
X1508252Y309773D01*
G01X1506127Y314006D02*
Y311898D01*
G01X1510900Y318779D02*
X1506127Y314006D01*
G01X1510900Y324120D02*
Y318779D01*
G01X1512510Y325730D02*
X1510900Y324120D01*
G01X1517090Y325730D02*
X1512510D01*
G01X1518700Y327340D02*
X1517090Y325730D01*
G01X1518700Y338116D02*
Y327340D01*
G01X1514252Y342564D02*
X1518700Y338116D01*
G01X1497509Y301390D02*
Y303120D01*
G01X1496939Y300820D02*
X1497509Y301390D01*
G01X1496939Y296160D02*
Y300820D01*
G01X1495058Y294279D02*
X1496939Y296160D01*
G01X1495058Y285171D02*
Y294279D01*
G01X1498176Y282053D02*
X1495058Y285171D01*
G01X1498176Y280747D02*
Y282053D01*
G01X1497253Y279824D02*
X1498176Y280747D01*
G01X1496698Y279824D02*
X1497253D01*
G01X1519303Y338735D02*
X1515321Y342717D01*
G01X1519303Y338577D02*
Y338735D01*
G01X1519452Y338428D02*
X1519303Y338577D01*
G01X1519452Y326982D02*
Y338428D01*
G01X1517360Y324890D02*
X1519452Y326982D01*
G01X1512790Y324890D02*
X1517360D01*
G01X1511652Y323752D02*
X1512790Y324890D01*
G01X1511652Y319091D02*
Y323752D01*
G01X1511653Y319090D02*
X1511652Y319091D01*
G01X1511653Y318468D02*
Y319090D01*
G01X1506879Y313694D02*
X1511653Y318468D01*
G01X1506879Y312294D02*
Y313694D01*
G01X1509024Y310149D02*
X1506879Y312294D01*
G01X1509024Y302066D02*
Y310149D01*
G01X1507922Y300964D02*
X1509024Y302066D01*
G01X1507922Y290631D02*
Y300964D01*
G01X1506817Y289526D02*
X1507922Y290631D01*
G01X1521245Y284203D02*
X1517530Y280488D01*
G01X1521245Y324337D02*
Y284203D01*
G01X1521356Y324448D02*
X1521245Y324337D01*
G01X1521356Y328247D02*
Y324448D01*
G01X1523917Y330808D02*
X1521356Y328247D01*
G01X1523917Y335817D02*
Y330808D01*
G01X1523918Y335818D02*
X1523917Y335817D01*
G01X1523918Y336772D02*
Y335818D01*
G01X1523917Y336773D02*
X1523918Y336772D01*
G01X1523917Y352349D02*
Y336773D01*
G01X1489546Y286202D02*
X1491082Y284666D01*
G01X1522765Y336295D02*
Y351510D01*
G01X1520204Y333734D02*
X1522765Y336295D01*
G01X1520204Y324926D02*
Y333734D01*
G01X1520093Y324815D02*
X1520204Y324926D01*
G01X1520093Y285800D02*
Y324815D01*
G01X1518821Y284528D02*
X1520093Y285800D01*
G01X1516981Y284528D02*
X1518821D01*
G01X1513906Y281453D02*
X1516981Y284528D01*
G01X1507090Y328250D02*
X1504370Y330970D01*
G01X1507090Y317410D02*
Y328250D01*
G01X1503000Y313320D02*
X1507090Y317410D01*
G01X1503000Y303317D02*
Y313320D01*
G01X1504813Y301504D02*
X1503000Y303317D01*
G01X1508150Y339270D02*
Y345430D01*
G01X1509910Y337510D02*
X1508150Y339270D01*
G01X1509910Y334280D02*
Y337510D01*
G01X1508915Y333285D02*
X1509910Y334280D01*
G01X1503245Y333285D02*
X1508915D01*
G01X1500520Y330560D02*
X1503245Y333285D01*
G01X1500520Y320190D02*
Y330560D01*
G01X1500840Y319870D02*
X1500520Y320190D01*
G01X1503177Y336377D02*
Y342470D01*
G01X1498750Y331950D02*
X1503177Y336377D01*
G01X1496240Y331950D02*
X1498750D01*
G01X1492540Y328250D02*
X1496240Y331950D01*
G01X1478649Y322080D02*
Y342696D01*
G01X1476886Y320317D02*
X1478649Y322080D01*
G01X1476886Y316114D02*
Y320317D01*
G01X1478419Y314581D02*
X1476886Y316114D01*
G01X1478419Y299406D02*
Y314581D01*
G01X1478546Y299279D02*
X1478419Y299406D01*
G01X1478546Y288870D02*
Y299279D01*
G01X1476948Y287272D02*
X1478546Y288870D01*
G01X1476948Y286202D02*
Y287272D01*
G01X1488000Y312943D02*
X1489546Y311397D01*
G01X1488000Y319295D02*
Y312943D01*
G01X1486780Y320515D02*
X1488000Y319295D01*
G01X1483111Y320515D02*
X1486780D01*
G01X1480058Y323568D02*
X1483111Y320515D01*
G01X1480058Y341749D02*
Y323568D01*
G01X1514421Y311364D02*
X1516301Y313244D01*
G01X1514421Y299773D02*
Y311364D01*
G01X1517905Y296289D02*
X1514421Y299773D01*
G01X1517905Y295335D02*
Y296289D01*
G01X1517906Y295334D02*
X1517905Y295335D01*
G01X1517906Y294712D02*
Y295334D01*
G01X1517904Y294710D02*
X1517906Y294712D01*
G01X1517904Y291404D02*
Y294710D01*
G01X1514847Y288347D02*
X1517904Y291404D01*
G01X1514847Y287029D02*
Y288347D01*
G01X1509873Y282055D02*
X1514847Y287029D01*
G01X1523149Y313098D02*
X1528120Y318069D01*
G01X1523149Y283413D02*
Y313098D01*
G01X1519434Y279698D02*
X1523149Y283413D01*
G01X1522197Y283808D02*
X1518482Y280093D01*
G01X1522197Y313493D02*
Y283808D01*
G01X1527010Y318306D02*
X1522197Y313493D01*
G01X1527010Y326800D02*
Y318306D01*
G01X1529430Y329220D02*
X1527010Y326800D01*
G01X1475308Y327048D02*
Y354768D01*
G01X1472012Y323752D02*
X1475308Y327048D01*
G01X1469851Y323752D02*
X1472012D01*
G01X1468681Y322582D02*
X1469851Y323752D01*
G01X1468681Y318807D02*
Y322582D01*
G01X1466100Y316226D02*
X1468681Y318807D01*
G01X1466100Y282722D02*
Y316226D01*
G01X1474556Y332825D02*
Y355419D01*
G01X1470288Y328557D02*
X1474556Y332825D01*
G01X1469797Y328557D02*
X1470288D01*
G01X1465349Y318699D02*
Y324109D01*
G01X1468074Y315093D02*
X1473231Y320250D01*
G01X1498411Y283409D02*
X1501257Y280563D01*
G01X1498411Y289347D02*
Y283409D01*
G01X1498476Y289412D02*
X1498411Y289347D01*
G01X1498476Y298417D02*
Y289412D01*
G01X1498147Y298746D02*
X1498476Y298417D01*
G01X1498147Y300964D02*
Y298746D01*
G01X1498985Y301802D02*
X1498147Y300964D01*
G01X1498985Y308016D02*
Y301802D01*
G01X1495651Y311350D02*
X1498985Y308016D01*
G01X1516578Y330542D02*
X1517115Y330005D01*
G01X1516578Y338772D02*
Y330542D01*
G01X1513030Y342320D02*
X1516578Y338772D01*
G01X1484927Y291375D02*
Y280301D01*
G01X1491350Y297798D02*
X1484927Y291375D01*
G01X1491350Y304329D02*
Y297798D01*
G01X1492971Y305950D02*
X1491350Y304329D01*
G01X1496757Y305950D02*
X1492971D01*
G01X1497179Y306372D02*
X1496757Y305950D01*
G01X1471328Y323000D02*
X1470257Y321929D01*
G01X1472696Y323000D02*
X1471328D01*
G01X1476400Y326704D02*
X1472696Y323000D01*
G01X1476400Y349599D02*
Y326704D01*
G01X1491100Y312976D02*
X1492700Y311376D01*
G01X1491100Y318917D02*
Y312976D01*
G01X1488750Y321267D02*
X1491100Y318917D01*
G01X1483423Y321267D02*
X1488750D01*
G01X1480810Y323880D02*
X1483423Y321267D01*
G01X1480810Y341360D02*
Y323880D01*
G01X1515629Y286747D02*
X1510625Y281743D01*
G01X1515629Y287871D02*
Y286747D01*
G01X1518657Y290899D02*
X1515629Y287871D01*
G01X1518657Y292145D02*
Y290899D01*
G01X1518656Y292146D02*
X1518657Y292145D01*
G01X1518656Y294398D02*
Y292146D01*
G01X1518658Y294400D02*
X1518656Y294398D01*
G01X1518658Y313402D02*
Y294400D01*
G01X1514100Y317960D02*
X1518658Y313402D01*
G01X1514100Y321792D02*
Y317960D01*
G01X1493400Y297797D02*
Y300800D01*
G01X1488076Y292473D02*
X1493400Y297797D01*
G01X1470850Y342259D02*
Y334447D01*
G01X1510324Y285518D02*
X1507969Y283163D01*
G01X1510324Y289264D02*
Y285518D01*
G01X1509074Y290514D02*
X1510324Y289264D01*
G01X1509074Y300486D02*
Y290514D01*
G01X1510268Y301680D02*
X1509074Y300486D01*
G01X1510268Y311228D02*
Y301680D01*
G01X1508455Y313041D02*
X1510268Y311228D01*
G01X1481800Y353599D02*
X1477200Y348999D01*
G01X1481800Y366021D02*
Y353599D01*
G01X1482849Y367070D02*
X1481800Y366021D01*
G01X1484151Y367070D02*
X1482849D01*
G01X1484172Y367049D02*
X1484151Y367070D01*
G01X1488760Y367049D02*
X1484172D01*
G01X1499225Y377514D02*
X1488760Y367049D01*
G01X1500499Y383000D02*
X1499225Y384274D01*
G01X1501500Y383000D02*
X1500499D01*
G01X1503000Y381500D02*
X1501500Y383000D01*
G01X1503000Y380122D02*
Y381500D01*
G01X1501270Y378392D02*
X1503000Y380122D01*
G01X1501270Y372270D02*
Y378392D01*
G01X1493452Y364452D02*
X1501270Y372270D01*
G01X1493452Y347627D02*
Y364452D01*
G01X1495810Y345269D02*
X1493452Y347627D01*
G01X1468100Y362497D02*
X1467597Y363000D01*
G01X1468100Y349700D02*
Y362497D01*
G01X1470576Y345197D02*
X1467803Y342424D01*
G01X1470576Y363797D02*
Y345197D01*
G01X1482368Y375589D02*
X1470576Y363797D01*
G01X1482368Y376008D02*
Y375589D01*
G01X1489475Y383115D02*
X1482368Y376008D01*
G01X1489475Y387654D02*
Y383115D01*
G01X1514252Y352058D02*
Y342564D01*
G01X1510400Y355910D02*
X1514252Y352058D01*
G01X1510400Y366200D02*
Y355910D01*
G01X1521000Y376800D02*
X1510400Y366200D01*
G01X1521000Y378600D02*
Y376800D01*
G01X1522500Y380100D02*
X1521000Y378600D01*
G01X1522500Y381040D02*
Y380100D01*
G01X1524164Y382704D02*
X1522500Y381040D01*
G01X1527176Y382704D02*
X1524164D01*
G01X1526896Y386124D02*
X1528095Y384925D01*
G01X1526896Y388333D02*
Y386124D01*
G01X1470100Y392350D02*
X1465975Y388225D01*
G01X1520158Y357069D02*
X1520313D01*
G01X1515321Y352232D02*
X1520158Y357069D01*
G01X1515321Y342717D02*
Y352232D01*
G01X1481233Y390233D02*
X1483868D01*
G01X1477952Y386952D02*
X1481233Y390233D01*
G01X1477952Y373452D02*
Y386952D01*
G01X1472900Y368400D02*
X1477952Y373452D01*
G01X1468680Y368400D02*
X1472900D01*
G01X1468678Y368398D02*
X1468680Y368400D01*
G01X1468198Y368398D02*
X1468678D01*
G01X1523170Y353096D02*
X1523917Y352349D01*
G01X1523170Y360372D02*
Y353096D01*
G01X1524195Y361397D02*
X1523170Y360372D01*
G01X1524195Y378165D02*
Y361397D01*
G01X1523460Y378900D02*
X1524195Y378165D01*
G01X1523460Y379779D02*
Y378900D01*
G01X1524575Y380894D02*
X1523460Y379779D01*
G01X1522625Y372900D02*
Y377514D01*
G01X1518056Y368331D02*
X1522625Y372900D01*
G01X1518056Y363920D02*
Y368331D01*
G01X1522018Y359958D02*
X1518056Y363920D01*
G01X1522018Y352257D02*
Y359958D01*
G01X1522765Y351510D02*
X1522018Y352257D01*
G01X1508150Y345430D02*
X1502970Y350610D01*
G01X1500330Y355421D02*
X1498246Y357505D01*
G01X1500330Y345317D02*
Y355421D01*
G01X1503177Y342470D02*
X1500330Y345317D01*
G01X1483867Y355621D02*
Y356753D01*
G01X1485593Y353895D02*
X1483867Y355621D01*
G01X1485593Y349640D02*
Y353895D01*
G01X1478649Y342696D02*
X1485593Y349640D01*
G01X1486655Y348346D02*
X1480058Y341749D01*
G01X1486655Y354575D02*
Y348346D01*
G01X1485924Y355306D02*
X1486655Y354575D01*
G01X1485924Y357599D02*
Y355306D01*
G01X1483973Y359550D02*
X1485924Y357599D01*
G01X1483740Y359550D02*
X1483973D01*
G01X1527610Y397500D02*
X1526659D01*
G01X1526226Y360261D02*
X1528779Y357708D01*
G01X1526226Y372896D02*
Y360261D01*
G01X1528095Y374765D02*
X1526226Y372896D01*
G01X1494490Y386539D02*
X1493375Y387654D01*
G01X1494490Y385660D02*
Y386539D01*
G01X1493755Y384925D02*
X1494490Y385660D01*
G01X1493755Y383623D02*
Y384925D01*
G01X1494945Y382433D02*
X1493755Y383623D01*
G01X1494945Y380243D02*
Y382433D01*
G01X1492995Y378293D02*
X1494945Y380243D01*
G01X1492995Y376863D02*
Y378293D01*
G01X1485317Y369185D02*
X1492995Y376863D01*
G01X1482621Y369185D02*
X1485317D01*
G01X1480276Y366840D02*
X1482621Y369185D01*
G01X1480276Y358505D02*
Y366840D01*
G01X1478781Y357010D02*
X1480276Y358505D01*
G01X1477550Y357010D02*
X1478781D01*
G01X1475308Y354768D02*
X1477550Y357010D01*
G01X1472050Y374500D02*
X1468500Y370950D01*
G01X1474163Y374500D02*
X1472050D01*
G01X1475100Y375437D02*
X1474163Y374500D01*
G01X1475100Y391753D02*
Y375437D01*
G01X1473083Y393770D02*
X1475100Y391753D01*
G01X1478495Y359082D02*
X1478607D01*
G01X1478495Y358970D02*
Y359082D01*
G01X1478107Y358970D02*
X1478495D01*
G01X1474556Y355419D02*
X1478107Y358970D01*
G01X1518725Y387719D02*
G02X1520027Y389494I1950J-65D01*
G01X1518725Y387589D02*
Y387719D01*
G01X1517750Y385964D02*
G03X1518725Y387589I-975J1690D01*
G01X1516775Y384339D02*
G02X1517750Y385964I1950J-65D01*
G01X1516775Y384209D02*
Y384339D01*
G01X1515800Y382584D02*
G03X1516775Y384209I-975J1690D01*
G01X1514825Y380959D02*
G02X1515800Y382584I1950J-65D01*
G01X1514825Y380829D02*
Y380959D01*
G01X1513850Y379204D02*
G03X1514825Y380829I-975J1690D01*
G01X1512875Y377579D02*
G02X1513850Y379204I1950J-65D01*
G01X1512875Y375875D02*
Y377579D01*
G01X1511204Y374204D02*
X1512875Y375875D01*
G01X1509562Y374204D02*
X1511204D01*
G01X1502286Y366928D02*
X1509562Y374204D01*
G01X1502286Y363614D02*
Y366928D01*
G01X1507200Y358700D02*
X1502286Y363614D01*
G01X1470800Y393899D02*
Y395200D01*
G01X1471670Y393029D02*
X1470800Y393899D01*
G01X1471670Y390350D02*
Y393029D01*
G01X1466950Y385630D02*
X1471670Y390350D01*
G01X1466950Y382800D02*
Y385630D01*
G01X1513030Y351710D02*
Y342320D01*
G01X1509200Y355540D02*
X1513030Y351710D01*
G01X1509200Y367239D02*
Y355540D01*
G01X1516400Y374439D02*
X1509200Y367239D01*
G01X1516400Y377500D02*
Y374439D01*
G01X1518400Y379500D02*
X1516400Y377500D01*
G01X1518400Y381000D02*
Y379500D01*
G01X1520400Y383000D02*
X1518400Y381000D01*
G01X1520400Y384500D02*
Y383000D01*
G01X1522246Y386346D02*
X1520400Y384500D01*
G01X1523267Y386346D02*
X1522246D01*
G01X1524575Y387654D02*
X1523267Y386346D01*
G01X1499365Y392604D02*
X1501175Y394414D01*
G01X1498574Y392604D02*
X1499365D01*
G01X1498470Y392500D02*
X1498574Y392604D01*
G01X1496080Y392500D02*
X1498470D01*
G01X1495976Y392604D02*
X1496080Y392500D01*
G01X1494674Y392604D02*
X1495976D01*
G01X1494570Y392500D02*
X1494674Y392604D01*
G01X1492180Y392500D02*
X1494570D01*
G01X1492076Y392604D02*
X1492180Y392500D01*
G01X1490774Y392604D02*
X1492076D01*
G01X1490170Y392000D02*
X1490774Y392604D01*
G01X1481400Y392000D02*
X1490170D01*
G01X1477200Y387800D02*
X1481400Y392000D01*
G01X1477200Y373800D02*
Y387800D01*
G01X1472950Y369550D02*
X1477200Y373800D01*
G01X1481028Y354227D02*
X1476400Y349599D01*
G01X1481028Y366528D02*
Y354227D01*
G01X1482616Y368116D02*
X1481028Y366528D01*
G01X1488148Y368116D02*
X1482616D01*
G01X1496895Y376863D02*
X1488148Y368116D01*
G01X1496895Y379053D02*
Y376863D01*
G01X1495705Y380243D02*
X1496895Y379053D01*
G01X1495705Y381573D02*
Y380243D01*
G01X1496895Y382763D02*
X1495705Y381573D01*
G01X1496895Y385648D02*
Y382763D01*
G01X1497247Y386000D02*
X1496895Y385648D01*
G01X1502000Y386000D02*
X1497247D01*
G01X1503505Y387505D02*
X1502000Y386000D01*
G01X1503505Y388305D02*
Y387505D01*
G01X1503776Y388576D02*
X1503505Y388305D01*
G01X1503776Y389464D02*
Y388576D01*
G01X1504695Y390383D02*
X1503776Y389464D01*
G01X1504695Y392573D02*
Y390383D01*
G01X1503505Y393763D02*
X1504695Y392573D01*
G01X1503505Y395905D02*
Y393763D01*
G01X1504695Y397095D02*
X1503505Y395905D01*
G01X1504695Y399333D02*
Y397095D01*
G01X1504014Y400014D02*
X1504695Y399333D01*
G01X1502514Y400014D02*
X1504014D01*
G01X1502000Y399500D02*
X1502514Y400014D01*
G01X1496500Y399500D02*
X1502000D01*
G01X1495000Y401000D02*
X1496500Y399500D01*
G01X1495000Y402801D02*
Y401000D01*
G01X1498948Y406749D02*
X1495000Y402801D01*
G01X1487786Y348336D02*
X1480810Y341360D01*
G01X1487786Y355105D02*
Y348336D01*
G01X1486676Y356215D02*
X1487786Y355105D01*
G01X1486676Y359447D02*
Y356215D01*
G01X1483659Y362464D02*
X1486676Y359447D01*
G01X1483659Y362914D02*
Y362464D01*
G01X1483664Y362914D02*
X1483659D01*
G01X1472704Y344113D02*
X1470850Y342259D01*
G01X1472704Y358203D02*
Y344113D01*
G01X1476800Y362299D02*
X1472704Y358203D01*
G01X1476800Y366021D02*
Y362299D01*
G01X1483169Y372390D02*
X1476800Y366021D01*
G01X1484622Y372390D02*
X1483169D01*
G01X1489855Y377623D02*
X1484622Y372390D01*
G01X1489855Y379053D02*
Y377623D01*
G01X1491805Y381003D02*
X1489855Y379053D01*
G01X1491805Y381545D02*
Y381003D01*
G01X1492995Y382735D02*
X1491805Y381545D01*
G01X1492995Y385605D02*
Y382735D01*
G01X1491805Y386795D02*
X1492995Y385605D01*
G01X1491805Y388305D02*
Y386795D01*
G01X1492964Y389464D02*
X1491805Y388305D01*
G01X1499876Y389464D02*
X1492964D01*
G01X1500795Y390383D02*
X1499876Y389464D01*
G01X1500795Y391813D02*
Y390383D01*
G01X1502745Y393763D02*
X1500795Y391813D01*
G01X1502745Y395065D02*
Y393763D01*
G01X1501826Y395984D02*
X1502745Y395065D01*
G01X1494914Y395984D02*
X1501826D01*
G01X1493500Y397398D02*
X1494914Y395984D01*
G01X1493500Y398500D02*
Y397398D01*
G01X1491805Y400195D02*
X1493500Y398500D01*
G01X1491805Y402305D02*
Y400195D01*
G01X1494945Y405445D02*
X1491805Y402305D01*
G01X1466353Y360400D02*
Y349583D01*
G01X1466021Y360732D02*
X1466353Y360400D01*
G01X1466021Y364591D02*
Y360732D01*
G01X1468676Y367246D02*
X1466021Y364591D01*
G01X1468678Y367246D02*
X1468676D01*
G01X1469081Y367649D02*
X1468678Y367246D01*
G01X1473212Y367649D02*
X1469081D01*
G01X1478969Y373406D02*
X1473212Y367649D01*
G01X1478969Y376346D02*
Y373406D01*
G01X1486897Y384274D02*
X1478969Y376346D01*
G01X1487525Y384274D02*
X1486897D01*
G01X1472703Y459127D02*
Y473934D01*
G01X1474151Y457679D02*
X1472703Y459127D01*
G01X1474151Y431734D02*
Y457679D01*
G01X1472980Y430563D02*
X1474151Y431734D01*
G01X1475653Y430655D02*
Y481697D01*
G01X1475093Y430095D02*
X1475653Y430655D01*
G01X1475093Y428294D02*
Y430095D01*
G01X1471922Y425123D02*
X1475093Y428294D01*
G01X1469019Y425123D02*
X1471922D01*
G01X1465486Y421590D02*
X1469019Y425123D01*
G01X1469067Y462537D02*
X1471530Y465000D01*
G01X1498948Y408752D02*
Y406749D01*
G01X1497400Y410300D02*
X1498948Y408752D01*
G01X1497400Y412000D02*
Y410300D01*
G01X1499000Y413600D02*
X1497400Y412000D01*
G01X1499000Y416620D02*
Y413600D01*
G01X1494945Y420675D02*
X1499000Y416620D01*
G01X1494945Y422105D02*
Y420675D01*
G01X1494026Y423024D02*
X1494945Y422105D01*
G01X1489703Y423024D02*
X1494026D01*
G01X1489070Y423657D02*
X1489703Y423024D01*
G01X1489070Y425251D02*
Y423657D01*
G01X1488151Y426170D02*
X1489070Y425251D01*
G01X1487609Y426170D02*
X1488151D01*
G01X1486943Y426836D02*
X1487609Y426170D01*
G01X1486943Y437363D02*
Y426836D01*
G01X1489095Y439515D02*
X1486943Y437363D01*
G01X1489095Y440945D02*
Y439515D01*
G01X1491045Y442895D02*
X1489095Y440945D01*
G01X1491045Y444197D02*
Y442895D01*
G01X1490126Y445116D02*
X1491045Y444197D01*
G01X1489496Y445116D02*
X1490126D01*
G01X1487571Y447041D02*
X1489496Y445116D01*
G01X1487571Y450928D02*
Y447041D01*
G01X1489095Y452452D02*
X1487571Y450928D01*
G01X1489095Y454596D02*
Y452452D01*
G01X1487307Y456384D02*
X1489095Y454596D01*
G01X1487307Y457640D02*
Y456384D01*
G01X1489528Y459861D02*
X1487307Y457640D01*
G01X1489528Y460922D02*
Y459861D01*
G01X1491194Y462588D02*
X1489528Y460922D01*
G01X1491194Y464767D02*
Y462588D01*
G01X1494945Y408955D02*
Y405445D01*
G01X1493755Y410145D02*
X1494945Y408955D01*
G01X1493755Y412155D02*
Y410145D01*
G01X1494945Y413345D02*
X1493755Y412155D01*
G01X1494945Y415755D02*
Y413345D01*
G01X1493400Y417300D02*
X1494945Y415755D01*
G01X1493400Y418320D02*
Y417300D01*
G01X1491920Y419800D02*
X1493400Y418320D01*
G01X1486043Y419800D02*
X1491920D01*
G01X1483930Y421913D02*
X1486043Y419800D01*
G01X1483930Y423751D02*
Y421913D01*
G01X1486192Y426013D02*
X1483930Y423751D01*
G01X1486192Y438936D02*
Y426013D01*
G01X1485955Y439173D02*
X1486192Y438936D01*
G01X1485955Y440817D02*
Y439173D01*
G01X1487905Y442767D02*
X1485955Y440817D01*
G01X1487905Y444417D02*
Y442767D01*
G01X1485884Y446438D02*
X1487905Y444417D01*
G01X1485884Y461479D02*
Y446438D01*
G01X1487887Y463482D02*
X1485884Y461479D01*
G01X1487887Y471383D02*
Y463482D01*
G01X1517223Y522002D02*
X1531601Y536380D01*
G01X1508466Y522002D02*
X1517223D01*
G01X1505326Y518862D02*
X1508466Y522002D01*
G01X1496874Y518862D02*
X1505326D01*
G01X1489608Y511596D02*
X1496874Y518862D01*
G01X1478624Y511596D02*
X1489608D01*
G01X1473717Y506689D02*
X1478624Y511596D01*
G01X1472338Y506689D02*
X1473717D01*
G01X1470974Y505325D02*
X1472338Y506689D01*
G01X1514794Y525907D02*
X1529499Y540612D01*
G01X1508137Y525907D02*
X1514794D01*
G01X1504265Y522035D02*
X1508137Y525907D01*
G01X1501038Y522035D02*
X1504265D01*
G01X1498373Y524700D02*
X1501038Y522035D01*
G01X1491913Y524700D02*
X1498373D01*
G01X1485191Y517978D02*
X1491913Y524700D01*
G01X1481185Y517978D02*
X1485191D01*
G01X1477879Y514672D02*
X1481185Y517978D01*
G01X1472955Y514672D02*
X1477879D01*
G01X1468753Y510470D02*
X1472955Y514672D01*
G01X1518828Y508226D02*
X1538166Y527564D01*
G01X1518828Y505916D02*
Y508226D01*
G01X1517848Y504936D02*
X1518828Y505916D01*
G01X1517848Y499153D02*
Y504936D01*
G01X1513112Y494417D02*
X1517848Y499153D01*
G01X1498546Y494417D02*
X1513112D01*
G01X1497524Y495439D02*
X1498546Y494417D01*
G01X1497523Y495439D02*
X1497524D01*
G01X1497136Y495826D02*
X1497523Y495439D01*
G01X1479128Y495826D02*
X1497136D01*
G01X1476958Y493656D02*
X1479128Y495826D01*
G01X1470829Y493656D02*
X1476958D01*
G01X1469372Y492199D02*
X1470829Y493656D01*
G01X1469372Y477265D02*
Y492199D01*
G01X1472703Y473934D02*
X1469372Y477265D01*
G01X1515068Y509786D02*
X1536606Y531324D01*
G01X1515068Y507554D02*
Y509786D01*
G01X1513148Y505634D02*
X1515068Y507554D01*
G01X1513148Y502689D02*
Y505634D01*
G01X1511821Y501362D02*
X1513148Y502689D01*
G01X1493085Y501362D02*
X1511821D01*
G01X1492413Y502034D02*
X1493085Y501362D01*
G01X1475089Y502034D02*
X1492413D01*
G01X1473664Y500609D02*
X1475089Y502034D01*
G01X1469478Y500609D02*
X1473664D01*
G01X1504028Y522987D02*
X1508001Y526960D01*
G01X1501433Y522987D02*
X1504028D01*
G01X1498768Y525652D02*
X1501433Y522987D01*
G01X1491518Y525652D02*
X1498768D01*
G01X1484796Y518930D02*
X1491518Y525652D01*
G01X1480790Y518930D02*
X1484796D01*
G01X1477484Y515624D02*
X1480790Y518930D01*
G01X1472560Y515624D02*
X1477484D01*
G01X1468358Y511422D02*
X1472560Y515624D01*
G01X1475653Y481697D02*
X1472250Y485100D01*
G01X1511109Y514541D02*
X1531996Y535428D01*
G01X1504748Y514541D02*
X1511109D01*
G01X1501391Y517898D02*
X1504748Y514541D01*
G01X1497319Y517898D02*
X1501391D01*
G01X1492505Y513084D02*
X1497319Y517898D01*
G01X1492505Y506451D02*
Y513084D01*
G01X1491582Y505528D02*
X1492505Y506451D01*
G01X1473257Y505528D02*
X1491582D01*
G01X1472102Y504373D02*
X1473257Y505528D01*
G01X1515820Y509474D02*
X1536918Y530572D01*
G01X1515820Y507242D02*
Y509474D01*
G01X1513948Y505370D02*
X1515820Y507242D01*
G01X1513948Y502426D02*
Y505370D01*
G01X1512133Y500611D02*
X1513948Y502426D01*
G01X1491255Y500611D02*
X1512133D01*
G01X1490583Y501283D02*
X1491255Y500611D01*
G01X1475402Y501283D02*
X1490583D01*
G01X1473976Y499857D02*
X1475402Y501283D01*
G01X1469790Y499857D02*
X1473976D01*
G01X1465313Y482771D02*
Y495380D01*
G01X1516828Y522954D02*
X1531206Y537332D01*
G01X1508071Y522954D02*
X1516828D01*
G01X1504931Y519814D02*
X1508071Y522954D01*
G01X1496479Y519814D02*
X1504931D01*
G01X1489213Y512548D02*
X1496479Y519814D01*
G01X1478221Y512548D02*
X1489213D01*
G01X1473394Y507721D02*
X1478221Y512548D01*
G01X1471182Y507721D02*
X1473394D01*
G01X1469738Y506277D02*
X1471182Y507721D01*
G01X1468599Y493255D02*
X1470643Y495299D01*
G01X1468599Y476975D02*
Y493255D01*
G01X1471530Y474044D02*
X1468599Y476975D01*
G01X1471530Y465000D02*
Y474044D01*
G01X1486676Y482400D02*
X1535300D01*
G01X1482958Y486118D02*
X1486676Y482400D01*
G01X1516433Y523906D02*
X1531987Y539460D01*
G01X1507656Y523906D02*
X1516433D01*
G01X1504516Y520766D02*
X1507656Y523906D01*
G01X1496084Y520766D02*
X1504516D01*
G01X1488818Y513500D02*
X1496084Y520766D01*
G01X1473544Y513500D02*
X1488818D01*
G01X1467273Y507229D02*
X1473544Y513500D01*
G01X1518076Y508538D02*
X1537854Y528316D01*
G01X1518076Y506260D02*
Y508538D01*
G01X1516848Y505032D02*
X1518076Y506260D01*
G01X1516848Y499529D02*
Y505032D01*
G01X1512997Y495678D02*
X1516848Y499529D01*
G01X1499886Y495678D02*
X1512997D01*
G01X1498986Y496578D02*
X1499886Y495678D01*
G01X1475243Y496578D02*
X1498986D01*
G01X1474451Y497370D02*
X1475243Y496578D01*
G01X1470493Y497370D02*
X1474451D01*
G01X1469073Y495950D02*
X1470493Y497370D01*
G01X1469073Y495949D02*
Y495950D01*
G01X1468953Y495829D02*
X1469073Y495949D01*
G01X1468953Y495828D02*
Y495829D01*
G01X1467657Y494532D02*
X1468953Y495828D01*
G01X1467657Y481923D02*
Y494532D01*
G01X1517324Y508850D02*
X1537542Y529068D01*
G01X1517324Y506572D02*
Y508850D01*
G01X1515948Y505196D02*
X1517324Y506572D01*
G01X1515948Y499692D02*
Y505196D01*
G01X1512685Y496429D02*
X1515948Y499692D01*
G01X1500199Y496429D02*
X1512685D01*
G01X1499298Y497330D02*
X1500199Y496429D01*
G01X1475555Y497330D02*
X1499298D01*
G01X1474764Y498121D02*
X1475555Y497330D01*
G01X1470805Y498121D02*
X1474764D01*
G01X1470804Y498122D02*
X1470805Y498121D01*
G01X1470182Y498122D02*
X1470804D01*
G01X1468322Y496262D02*
X1470182Y498122D01*
G01X1468322Y496261D02*
Y496262D01*
G01X1466817Y494756D02*
X1468322Y496261D01*
G01X1466817Y482147D02*
Y494756D01*
G01X1513714Y510062D02*
X1536128Y532476D01*
G01X1513714Y508051D02*
Y510062D01*
G01X1511868Y506205D02*
X1513714Y508051D01*
G01X1507745Y506205D02*
X1511868D01*
G01X1504460Y502920D02*
X1507745Y506205D01*
G01X1474911Y502920D02*
X1504460D01*
G01X1473426Y501435D02*
X1474911Y502920D01*
G01X1468674Y501435D02*
X1473426D01*
G01X1466065Y495068D02*
Y482459D01*
G01X1470102Y499105D02*
X1466065Y495068D01*
G01X1474430Y499105D02*
X1470102D01*
G01X1475857Y500532D02*
X1474430Y499105D01*
G01X1489682Y500532D02*
X1475857D01*
G01X1491152Y499062D02*
X1489682Y500532D01*
G01X1502138Y499062D02*
X1491152D01*
G01X1504020Y497180D02*
X1502138Y499062D01*
G01X1512373Y497180D02*
X1504020D01*
G01X1515089Y499896D02*
X1512373Y497180D01*
G01X1515089Y505401D02*
Y499896D01*
G01X1516572Y506884D02*
X1515089Y505401D01*
G01X1516572Y509162D02*
Y506884D01*
G01X1537230Y529820D02*
X1516572Y509162D01*
G01X1489601Y466360D02*
X1491194Y464767D01*
G01X1489601Y467983D02*
Y466360D01*
G01X1489866Y468248D02*
X1489601Y467983D01*
G01X1489866Y468249D02*
Y468248D01*
G01X1491243Y469626D02*
X1489866Y468249D01*
G01X1491243Y471508D02*
Y469626D01*
G01X1489095Y473656D02*
X1491243Y471508D01*
G01X1489095Y474617D02*
Y473656D01*
G01X1487525Y476187D02*
X1489095Y474617D01*
G01X1487525Y480726D02*
Y476187D01*
G01X1484400Y474870D02*
X1487887Y471383D01*
G01X1484400Y475600D02*
Y474870D01*
G01X1482200Y477800D02*
X1484400Y475600D01*
G01X1489705Y577325D02*
X1465755D01*
G01X1492730Y580350D02*
X1489705Y577325D01*
G01X1517302Y580350D02*
X1492730D01*
G01X1523938Y586986D02*
X1517302Y580350D01*
G01X1530893Y586986D02*
X1523938D01*
G01X1514500Y526960D02*
X1529104Y541564D01*
G01X1508001Y526960D02*
X1514500D01*
G01X1516226Y582550D02*
X1522344Y588668D01*
G01X1491650Y582550D02*
X1516226D01*
G01X1488958Y579858D02*
X1491650Y582550D01*
G01X1523208Y587828D02*
X1529318D01*
G01X1516940Y581560D02*
X1523208Y587828D01*
G01X1492200Y581560D02*
X1516940D01*
G01X1489160Y578520D02*
X1492200Y581560D01*
G01X1522344Y588668D02*
X1528538D01*
G01X1545456Y32834D02*
X1554434Y23856D01*
G01X1541504Y1404D02*
X1543500Y3400D01*
G01X1558184Y28682D02*
X1551670Y35196D01*
G01X1589401Y28682D02*
X1558184D01*
G01X1569242Y-1842D02*
X1569200Y-1800D01*
G01X1569334Y-1842D02*
X1569242D01*
G01X1578492Y-11000D02*
X1569334Y-1842D01*
G01X1616700Y-11000D02*
X1578492D01*
G01X1571948Y3400D02*
X1569000D01*
G01X1578148Y-2800D02*
X1571948Y3400D01*
G01X1602400Y-2800D02*
X1578148D01*
G01X1577884Y-3600D02*
X1605500D01*
G01X1573832Y452D02*
X1577884Y-3600D01*
G01X1564462Y32538D02*
X1591633D01*
G01X1552951Y44049D02*
X1564462Y32538D01*
G01X1564032Y31338D02*
X1552473Y42897D01*
G01X1589060Y31338D02*
X1564032D01*
G01X1536926Y8044D02*
X1531522Y13448D01*
G01X1586760Y8044D02*
X1536926D01*
G01X1589752Y5052D02*
X1586760Y8044D01*
G01X1570394Y-300D02*
X1571500Y-1406D01*
G01X1558662Y29834D02*
X1589684D01*
G01X1547225Y41271D02*
X1558662Y29834D01*
G01X1587238Y9196D02*
X1590230Y6204D01*
G01X1537404Y9196D02*
X1587238D01*
G01X1532000Y14600D02*
X1537404Y9196D01*
G01X1545111Y24172D02*
X1539163Y18224D01*
G01X1549400Y19100D02*
X1634959D01*
G01X1547600Y20900D02*
X1549400Y19100D01*
G01X1547600Y24248D02*
Y20900D01*
G01X1546100Y25748D02*
X1547600Y24248D01*
G01X1543739Y25748D02*
X1546100D01*
G01X1537617Y19626D02*
X1543739Y25748D01*
G01X1558974Y30586D02*
X1547537Y42023D01*
G01X1589372Y30586D02*
X1558974D01*
G01X1543608Y32082D02*
X1551834Y23856D01*
G01X1538713Y32082D02*
X1543608D01*
G01X1537037Y33758D02*
X1538713Y32082D01*
G01X1579600Y1600D02*
X1602300D01*
G01X1574308Y6892D02*
X1579600Y1600D01*
G01X1536448Y6892D02*
X1574308D01*
G01X1531044Y12296D02*
X1536448Y6892D01*
G01X1557872Y27930D02*
X1589089D01*
G01X1551558Y34244D02*
X1557872Y27930D01*
G01X1577908Y-12408D02*
X1611708D01*
G01X1568750Y-3250D02*
X1577908Y-12408D01*
G01X1544872Y-3250D02*
X1568750D01*
G01X1544862Y-3260D02*
X1544872Y-3250D01*
G01X1549840Y67370D02*
X1544140Y61670D01*
G01X1558970Y67370D02*
X1549840D01*
G01X1560210Y68610D02*
X1558970Y67370D01*
G01X1560210Y76360D02*
Y68610D01*
G01X1561640Y77790D02*
X1560210Y76360D01*
G01X1561640Y77807D02*
Y77790D01*
G01X1573877Y77807D02*
X1561640D01*
G01X1575292Y76392D02*
X1573877Y77807D01*
G01X1575292Y74392D02*
Y76392D01*
G01X1573432Y72532D02*
X1575292Y74392D01*
G01X1573432Y69380D02*
Y72532D01*
G01X1586244Y56568D02*
X1573432Y69380D01*
G01X1617456Y56568D02*
X1586244D01*
G01X1585454Y54664D02*
X1642830D01*
G01X1571328Y68790D02*
X1585454Y54664D01*
G01X1571328Y74579D02*
Y68790D01*
G01X1570511Y75396D02*
X1571328Y74579D01*
G01X1539308Y32834D02*
X1545456D01*
G01X1537632Y34510D02*
X1539308Y32834D01*
G01X1574712Y59271D02*
X1574711Y59270D01*
G01X1577870Y59271D02*
X1574712D01*
G01X1584581Y52560D02*
X1577870Y59271D01*
G01X1644482Y52560D02*
X1584581D01*
G01X1579402Y40288D02*
X1594260D01*
G01X1572892Y46798D02*
X1579402Y40288D01*
G01X1578566Y79682D02*
X1582407Y75841D01*
G01X1578566Y91672D02*
Y79682D01*
G01X1575119Y95119D02*
X1578566Y91672D01*
G01X1541326Y35196D02*
X1539767Y36755D01*
G01X1551670Y35196D02*
X1541326D01*
G01X1583396Y49704D02*
X1645667D01*
G01X1576685Y56415D02*
X1583396Y49704D01*
G01X1575897Y56415D02*
X1576685D01*
G01X1575896Y56414D02*
X1575897Y56415D01*
G01X1583001Y48752D02*
X1576291Y55462D01*
G01X1646062Y48752D02*
X1583001D01*
G01X1588138Y76750D02*
X1588962Y75926D01*
G01X1588138Y78058D02*
Y76750D01*
G01X1589109Y79029D02*
X1588138Y78058D01*
G01X1587386Y73859D02*
X1592004Y69241D01*
G01X1587386Y78370D02*
Y73859D01*
G01X1588258Y79242D02*
X1587386Y78370D01*
G01X1588258Y80182D02*
Y79242D01*
G01X1591476Y83400D02*
X1588258Y80182D01*
G01X1581816Y45896D02*
X1647247D01*
G01X1575106Y52606D02*
X1581816Y45896D01*
G01X1580192Y42192D02*
X1595050D01*
G01X1573682Y48702D02*
X1580192Y42192D01*
G01X1581250Y44744D02*
X1574540Y51454D01*
G01X1647725Y44744D02*
X1581250D01*
G01X1572609Y34340D02*
X1596559D01*
G01X1561499Y45450D02*
X1572609Y34340D01*
G01X1582606Y47800D02*
X1575896Y54510D01*
G01X1646457Y47800D02*
X1582606D01*
G01X1540850Y36932D02*
X1540275Y37507D01*
G01X1544316Y36932D02*
X1540850D01*
G01X1545572Y38188D02*
X1544316Y36932D01*
G01X1582211Y46848D02*
X1646852D01*
G01X1575501Y53558D02*
X1582211Y46848D01*
G01X1575107Y58319D02*
X1575106Y58318D01*
G01X1577475Y58319D02*
X1575107D01*
G01X1584186Y51608D02*
X1577475Y58319D01*
G01X1644877Y51608D02*
X1584186D01*
G01X1585766Y55416D02*
X1642518D01*
G01X1572280Y68902D02*
X1585766Y55416D01*
G01X1572280Y74532D02*
Y68902D01*
G01X1573076Y75328D02*
X1572280Y74532D01*
G01X1574317Y60223D02*
X1574316Y60222D01*
G01X1578265Y60223D02*
X1574317D01*
G01X1584976Y53512D02*
X1578265Y60223D01*
G01X1644087Y53512D02*
X1584976D01*
G01X1583791Y50656D02*
X1645272D01*
G01X1577080Y57367D02*
X1583791Y50656D01*
G01X1575502Y57367D02*
X1577080D01*
G01X1575501Y57366D02*
X1575502Y57367D01*
G01X1579807Y77377D02*
Y75841D01*
G01X1577814Y79370D02*
X1579807Y77377D01*
G01X1577814Y91360D02*
Y79370D01*
G01X1574315Y94859D02*
X1577814Y91360D01*
G01X1540931Y34244D02*
X1551558D01*
G01X1539172Y36003D02*
X1540931Y34244D01*
G01X1579797Y41240D02*
X1594655D01*
G01X1573287Y47750D02*
X1579797Y41240D01*
G01X1588052Y138012D02*
X1589355Y136709D01*
G01X1588052Y155388D02*
Y138012D01*
G01X1589652Y156988D02*
X1588052Y155388D01*
G01X1575119Y99426D02*
Y95119D01*
G01X1579550Y103857D02*
X1575119Y99426D01*
G01X1579550Y105316D02*
Y103857D01*
G01X1576300Y108566D02*
X1579550Y105316D01*
G01X1576300Y113902D02*
Y108566D01*
G01X1581055Y118657D02*
X1576300Y113902D01*
G01X1581055Y129339D02*
Y118657D01*
G01X1579290Y131104D02*
X1581055Y129339D01*
G01X1586500Y113900D02*
X1582500Y109900D01*
G01X1586500Y116725D02*
Y113900D01*
G01X1590775Y121000D02*
X1586500Y116725D01*
G01X1587868Y109852D02*
X1592845Y104875D01*
G01X1587868Y117030D02*
Y109852D01*
G01X1591527Y120689D02*
X1587868Y117030D01*
G01X1586436Y153883D02*
Y158635D01*
G01X1587251Y153068D02*
X1586436Y153883D01*
G01X1587251Y136290D02*
Y153068D01*
G01X1587620Y135921D02*
X1587251Y136290D01*
G01X1574315Y99686D02*
Y94859D01*
G01X1578798Y104169D02*
X1574315Y99686D01*
G01X1578798Y104721D02*
Y104169D01*
G01X1575502Y108017D02*
X1578798Y104721D01*
G01X1575502Y114451D02*
Y108017D01*
G01X1580000Y118949D02*
X1575502Y114451D01*
G01X1580000Y127914D02*
Y118949D01*
G01X1579310Y128604D02*
X1580000Y127914D01*
G01X1531069Y205970D02*
X1554061Y228962D01*
G01X1531069Y199225D02*
Y205970D01*
G01X1586436Y158635D02*
X1590451Y162650D01*
G01X1532021Y201841D02*
X1555013Y224833D01*
G01X1532021Y198830D02*
Y201841D01*
G01X1533925Y201051D02*
X1556917Y224043D01*
G01X1533925Y198040D02*
Y201051D01*
G01X1529004Y193119D02*
X1533925Y198040D01*
G01X1529004Y189074D02*
Y193119D01*
G01X1527467Y205628D02*
X1551757Y229918D01*
G01X1527467Y198883D02*
Y205628D01*
G01X1532973Y201446D02*
X1555965Y224438D01*
G01X1532973Y198435D02*
Y201446D01*
G01X1527834Y193296D02*
X1532973Y198435D01*
G01X1527834Y189341D02*
Y193296D01*
G01X1528619Y205150D02*
X1552909Y229440D01*
G01X1528619Y198405D02*
Y205150D01*
G01X1567198Y259758D02*
X1567000Y259560D01*
G01X1567198Y275629D02*
Y259758D01*
G01X1575476Y283907D02*
X1567198Y275629D01*
G01X1562500Y276685D02*
X1568213Y282398D01*
G01X1562500Y258821D02*
Y276685D01*
G01X1563157Y258164D02*
X1562500Y258821D01*
G01X1559975Y277002D02*
X1566493Y283520D01*
G01X1559975Y258272D02*
Y277002D01*
G01X1554061Y252358D02*
X1559975Y258272D01*
G01X1554061Y228962D02*
Y252358D01*
G01X1541002Y241629D02*
Y223204D01*
G01X1544476Y245103D02*
X1541002Y241629D01*
G01X1544476Y250074D02*
Y245103D01*
G01X1554777Y260375D02*
X1544476Y250074D01*
G01X1554777Y279105D02*
Y260375D01*
G01X1557172Y281500D02*
X1554777Y279105D01*
G01X1549626Y253877D02*
Y230481D01*
G01X1555767Y260018D02*
X1549626Y253877D01*
G01X1555767Y278748D02*
Y260018D01*
G01X1561520Y284501D02*
X1555767Y278748D01*
G01X1549850Y279410D02*
Y287681D01*
G01X1552873Y276387D02*
X1549850Y279410D01*
G01X1552873Y261455D02*
Y276387D01*
G01X1537772Y246354D02*
X1552873Y261455D01*
G01X1537772Y240465D02*
Y246354D01*
G01X1535817Y238510D02*
X1537772Y240465D01*
G01X1535817Y222076D02*
Y238510D01*
G01X1529626Y247934D02*
Y250510D01*
G01X1531428Y246132D02*
X1529626Y247934D01*
G01X1531428Y243341D02*
Y246132D01*
G01X1529213Y241126D02*
X1531428Y243341D01*
G01X1529213Y232288D02*
Y241126D01*
G01X1540875Y277373D02*
Y313565D01*
G01X1535468Y271966D02*
X1540875Y277373D01*
G01X1535468Y240855D02*
Y271966D01*
G01X1533913Y239300D02*
X1535468Y240855D01*
G01X1533913Y223432D02*
Y239300D01*
G01X1554025Y276865D02*
X1551002Y279888D01*
G01X1554025Y260977D02*
Y276865D01*
G01X1538924Y245876D02*
X1554025Y260977D01*
G01X1538924Y240974D02*
Y245876D01*
G01X1540010Y239888D02*
X1538924Y240974D01*
G01X1540010Y224639D02*
Y239888D01*
G01X1561396Y234255D02*
X1561104D01*
G01X1563000Y235859D02*
X1561396Y234255D01*
G01X1563000Y240171D02*
Y235859D01*
G01X1564612Y241783D02*
X1563000Y240171D01*
G01X1568455Y241783D02*
X1564612D01*
G01X1578172Y251500D02*
X1568455Y241783D01*
G01X1581553Y251500D02*
X1578172D01*
G01X1582699Y252646D02*
X1581553Y251500D01*
G01X1560927Y276176D02*
X1567445Y282694D01*
G01X1560927Y257877D02*
Y276176D01*
G01X1555013Y251963D02*
X1560927Y257877D01*
G01X1555013Y224833D02*
Y251963D01*
G01X1576242Y276422D02*
X1583990Y284170D01*
G01X1576242Y250634D02*
Y276422D01*
G01X1568475Y242867D02*
X1576242Y250634D01*
G01X1560669Y242867D02*
X1568475D01*
G01X1556917Y239115D02*
X1560669Y242867D01*
G01X1556917Y224043D02*
Y239115D01*
G01X1527874Y246928D02*
Y250705D01*
G01X1528261Y232683D02*
Y237880D01*
G01X1540123Y277685D02*
Y313877D01*
G01X1534716Y272278D02*
X1540123Y277685D01*
G01X1534716Y245254D02*
Y272278D01*
G01X1530165Y240703D02*
X1534716Y245254D01*
G01X1530165Y231465D02*
Y240703D01*
G01X1557671Y277958D02*
X1563425Y283712D01*
G01X1557671Y259228D02*
Y277958D01*
G01X1551757Y253314D02*
X1557671Y259228D01*
G01X1551757Y229918D02*
Y253314D01*
G01X1563500Y276621D02*
X1568965Y282086D01*
G01X1563500Y262300D02*
Y276621D01*
G01X1565400Y260400D02*
X1563500Y262300D01*
G01X1565400Y254728D02*
Y260400D01*
G01X1568120Y252008D02*
X1565400Y254728D01*
G01X1568120Y251710D02*
Y252008D01*
G01X1573452Y279232D02*
X1576983Y282763D01*
G01X1573452Y249544D02*
Y279232D01*
G01X1567878Y243970D02*
X1573452Y249544D01*
G01X1560425Y243970D02*
X1567878D01*
G01X1555965Y239510D02*
X1560425Y243970D01*
G01X1555965Y224438D02*
Y239510D01*
G01X1550805Y253709D02*
Y230313D01*
G01X1556719Y259623D02*
X1550805Y253709D01*
G01X1556719Y278353D02*
Y259623D01*
G01X1562472Y284106D02*
X1556719Y278353D01*
G01X1558823Y277480D02*
X1565340Y283997D01*
G01X1558823Y258750D02*
Y277480D01*
G01X1552909Y252836D02*
X1558823Y258750D01*
G01X1552909Y229440D02*
Y252836D01*
G01X1534665Y238988D02*
Y222554D01*
G01X1536220Y240543D02*
X1534665Y238988D01*
G01X1536220Y271654D02*
Y240543D01*
G01X1542027Y277461D02*
X1536220Y271654D01*
G01X1542027Y313087D02*
Y277461D01*
G01X1554918Y307386D02*
X1550619Y303087D01*
G01X1554918Y325382D02*
Y307386D01*
G01X1550951Y329349D02*
X1554918Y325382D01*
G01X1550951Y342821D02*
Y329349D01*
G01X1575476Y296365D02*
Y283907D01*
G01X1577904Y298793D02*
X1575476Y296365D01*
G01X1577904Y300984D02*
Y298793D01*
G01X1577903Y300985D02*
X1577904Y300984D01*
G01X1577903Y304444D02*
Y300985D01*
G01X1579844Y306385D02*
X1577903Y304444D01*
G01X1579844Y309850D02*
Y306385D01*
G01X1579105Y310589D02*
X1579844Y309850D01*
G01X1579105Y311543D02*
Y310589D01*
G01X1579106Y311544D02*
X1579105Y311543D01*
G01X1579106Y324406D02*
Y311544D01*
G01X1584444Y329744D02*
X1579106Y324406D01*
G01X1584444Y334042D02*
Y329744D01*
G01X1591794Y341392D02*
X1584444Y334042D01*
G01X1532700Y290500D02*
X1529000D01*
G01X1536500Y294300D02*
X1532700Y290500D01*
G01X1536500Y297400D02*
Y294300D01*
G01X1531243Y302657D02*
X1536500Y297400D01*
G01X1531243Y309086D02*
Y302657D01*
G01X1534840Y312683D02*
X1531243Y309086D01*
G01X1534840Y321372D02*
Y312683D01*
G01X1535900Y322432D02*
X1534840Y321372D01*
G01X1535900Y345400D02*
Y322432D01*
G01X1581760Y342688D02*
X1580365Y341293D01*
G01X1585370Y340830D02*
X1583512Y342688D01*
G01X1585370Y338114D02*
Y340830D01*
G01X1577601Y330345D02*
X1585370Y338114D01*
G01X1577601Y310800D02*
Y330345D01*
G01X1575900Y309099D02*
X1577601Y310800D01*
G01X1575900Y304569D02*
Y309099D01*
G01X1575450Y304119D02*
X1575900Y304569D01*
G01X1575450Y299210D02*
Y304119D01*
G01X1573448Y297208D02*
X1575450Y299210D01*
G01X1573448Y291747D02*
Y297208D01*
G01X1568213Y286512D02*
X1573448Y291747D01*
G01X1568213Y282398D02*
Y286512D01*
G01X1578362Y335778D02*
Y350139D01*
G01X1575318Y332734D02*
X1578362Y335778D01*
G01X1575318Y329183D02*
Y332734D01*
G01X1573117Y326982D02*
X1575318Y329183D01*
G01X1573117Y316508D02*
Y326982D01*
G01X1574338Y315287D02*
X1573117Y316508D01*
G01X1574338Y310249D02*
Y315287D01*
G01X1574196Y310107D02*
X1574338Y310249D01*
G01X1574196Y305276D02*
Y310107D01*
G01X1572621Y303701D02*
X1574196Y305276D01*
G01X1572621Y299822D02*
Y303701D01*
G01X1571744Y298945D02*
X1572621Y299822D01*
G01X1571744Y292454D02*
Y298945D01*
G01X1566493Y287203D02*
X1571744Y292454D01*
G01X1566493Y283520D02*
Y287203D01*
G01X1559267Y339672D02*
Y343026D01*
G01X1558448Y338853D02*
X1559267Y339672D01*
G01X1558448Y328180D02*
Y338853D01*
G01X1559997Y326631D02*
X1558448Y328180D01*
G01X1559997Y310317D02*
Y326631D01*
G01X1557172Y312442D02*
Y281500D01*
G01X1558826Y314096D02*
X1557172Y312442D01*
G01X1558826Y323602D02*
Y314096D01*
G01X1553224Y329204D02*
X1558826Y323602D01*
G01X1553224Y341753D02*
Y329204D01*
G01X1561520Y294707D02*
Y284501D01*
G01X1561770Y294957D02*
X1561520Y294707D01*
G01X1561770Y294963D02*
Y294957D01*
G01X1567963Y301156D02*
X1561770Y294963D01*
G01X1567963Y304865D02*
Y301156D01*
G01X1567198Y305630D02*
X1567963Y304865D01*
G01X1567198Y309195D02*
Y305630D01*
G01X1570100Y312097D02*
X1567198Y309195D01*
G01X1570100Y313571D02*
Y312097D01*
G01X1568909Y314762D02*
X1570100Y313571D01*
G01X1568909Y328728D02*
Y314762D01*
G01X1570987Y330806D02*
X1568909Y328728D01*
G01X1570987Y338887D02*
Y330806D01*
G01X1572150Y340050D02*
X1570987Y338887D01*
G01X1572150Y355756D02*
Y340050D01*
G01X1549603Y325497D02*
X1548334D01*
G01X1553014Y322086D02*
X1549603Y325497D01*
G01X1553014Y315570D02*
Y322086D01*
G01X1547729Y310285D02*
X1553014Y315570D01*
G01X1547729Y289802D02*
Y310285D01*
G01X1549850Y287681D02*
X1547729Y289802D01*
G01X1532890Y329520D02*
Y353564D01*
G01X1530348Y326978D02*
X1532890Y329520D01*
G01X1530348Y323182D02*
Y326978D01*
G01X1532128Y321402D02*
X1530348Y323182D01*
G01X1532128Y313231D02*
Y321402D01*
G01X1528587Y309690D02*
X1532128Y313231D01*
G01X1528587Y300586D02*
Y309690D01*
G01X1543900Y311363D02*
X1543864Y311399D01*
G01X1543900Y290523D02*
Y311363D01*
G01X1546550Y287873D02*
X1543900Y290523D01*
G01X1546550Y287812D02*
Y287873D01*
G01X1546612Y287812D02*
X1546550D01*
G01X1565235Y304705D02*
Y303734D01*
G01X1562790Y307150D02*
X1565235Y304705D01*
G01X1562790Y313436D02*
Y307150D01*
G01X1562083Y314143D02*
X1562790Y313436D01*
G01X1562083Y319449D02*
Y314143D01*
G01X1566000Y323366D02*
X1562083Y319449D01*
G01X1566000Y338050D02*
Y323366D01*
G01X1567750Y339800D02*
X1566000Y338050D01*
G01X1567750Y354403D02*
Y339800D01*
G01X1578572Y284804D02*
X1578577Y284799D01*
G01X1578572Y286572D02*
Y284804D01*
G01X1581266Y289266D02*
X1578572Y286572D01*
G01X1581266Y293759D02*
Y289266D01*
G01X1580008Y295017D02*
X1581266Y293759D01*
G01X1580008Y303572D02*
Y295017D01*
G01X1581948Y305512D02*
X1580008Y303572D01*
G01X1581948Y310723D02*
Y305512D01*
G01X1581224Y311447D02*
X1581948Y310723D01*
G01X1581224Y313278D02*
Y311447D01*
G01X1583903Y315957D02*
X1581224Y313278D01*
G01X1583903Y317263D02*
Y315957D01*
G01X1586548Y319908D02*
X1583903Y317263D01*
G01X1586548Y333169D02*
Y319908D01*
G01X1594167Y340788D02*
X1586548Y333169D01*
G01X1546300Y320421D02*
X1548024Y322145D01*
G01X1546300Y318990D02*
Y320421D01*
G01X1540875Y313565D02*
X1546300Y318990D01*
G01X1588357Y321834D02*
X1589476Y322953D01*
G01X1588357Y313935D02*
Y321834D01*
G01X1585200Y310778D02*
X1588357Y313935D01*
G01X1585200Y298189D02*
Y310778D01*
G01X1585585Y297804D02*
X1585200Y298189D01*
G01X1585585Y282356D02*
Y297804D01*
G01X1584568Y281339D02*
X1585585Y282356D01*
G01X1555670Y296223D02*
X1554775Y295328D01*
G01X1555670Y325694D02*
Y296223D01*
G01X1552472Y328892D02*
X1555670Y325694D01*
G01X1552472Y342065D02*
Y328892D01*
G01X1548000Y328749D02*
Y331361D01*
G01X1554166Y322583D02*
X1548000Y328749D01*
G01X1554166Y315092D02*
Y322583D01*
G01X1548906Y309832D02*
X1554166Y315092D01*
G01X1548906Y290255D02*
Y309832D01*
G01X1551002Y288159D02*
X1548906Y290255D01*
G01X1551002Y279888D02*
Y288159D01*
G01X1576270Y331243D02*
X1583794Y338767D01*
G01X1576270Y328788D02*
Y331243D01*
G01X1574069Y326587D02*
X1576270Y328788D01*
G01X1574069Y316903D02*
Y326587D01*
G01X1575290Y315682D02*
X1574069Y316903D01*
G01X1575290Y309854D02*
Y315682D01*
G01X1575148Y309712D02*
X1575290Y309854D01*
G01X1575148Y304881D02*
Y309712D01*
G01X1574020Y303753D02*
X1575148Y304881D01*
G01X1574020Y299720D02*
Y303753D01*
G01X1572696Y298396D02*
X1574020Y299720D01*
G01X1572696Y292059D02*
Y298396D01*
G01X1567445Y286808D02*
X1572696Y292059D01*
G01X1567445Y283915D02*
Y286808D01*
G01X1567446Y283914D02*
X1567445Y283915D01*
G01X1567446Y283126D02*
Y283914D01*
G01X1567445Y283125D02*
X1567446Y283126D01*
G01X1567445Y282694D02*
Y283125D01*
G01X1587405Y332962D02*
X1594919Y340476D01*
G01X1587405Y314330D02*
Y332962D01*
G01X1582700Y309625D02*
X1587405Y314330D01*
G01X1582700Y305200D02*
Y309625D01*
G01X1581700Y304200D02*
X1582700Y305200D01*
G01X1581700Y299790D02*
Y304200D01*
G01X1583990Y297500D02*
X1581700Y299790D01*
G01X1583990Y284170D02*
Y297500D01*
G01X1531938Y329915D02*
Y353169D01*
G01X1528120Y326097D02*
X1531938Y329915D01*
G01X1528120Y318069D02*
Y326097D01*
G01X1537100Y340200D02*
X1540100Y343200D01*
G01X1537100Y333860D02*
Y340200D01*
G01X1545438Y325522D02*
X1537100Y333860D01*
G01X1545438Y319192D02*
Y325522D01*
G01X1540123Y313877D02*
X1545438Y319192D01*
G01X1529430Y334752D02*
Y329220D01*
G01X1528210Y335972D02*
X1529430Y334752D01*
G01X1528210Y345439D02*
Y335972D01*
G01X1568702Y339405D02*
Y354798D01*
G01X1566948Y337651D02*
X1568702Y339405D01*
G01X1566948Y323250D02*
Y337651D01*
G01X1562835Y319137D02*
X1566948Y323250D01*
G01X1562835Y314455D02*
Y319137D01*
G01X1564010Y313280D02*
X1562835Y314455D01*
G01X1564590Y313280D02*
X1564010D01*
G01X1566046Y311824D02*
X1564590Y313280D01*
G01X1566046Y305152D02*
Y311824D01*
G01X1566811Y304387D02*
X1566046Y305152D01*
G01X1566811Y302501D02*
Y304387D01*
G01X1565244Y300934D02*
X1566811Y302501D01*
G01X1550700Y315654D02*
X1548273Y313227D01*
G01X1550700Y318464D02*
Y315654D01*
G01X1549664Y319500D02*
X1550700Y318464D01*
G01X1549664Y323108D02*
Y319500D01*
G01X1548851Y323921D02*
X1549664Y323108D01*
G01X1547681Y323921D02*
X1548851D01*
G01X1546758Y324844D02*
X1547681Y323921D01*
G01X1546758Y326014D02*
Y324844D01*
G01X1540900Y331872D02*
X1546758Y326014D01*
G01X1540900Y353276D02*
Y331872D01*
G01X1575526Y337305D02*
Y355842D01*
G01X1572891Y334670D02*
X1575526Y337305D01*
G01X1572891Y330016D02*
Y334670D01*
G01X1570813Y327938D02*
X1572891Y330016D01*
G01X1570813Y315552D02*
Y327938D01*
G01X1572034Y314331D02*
X1570813Y315552D01*
G01X1572034Y311205D02*
Y314331D01*
G01X1571800Y310971D02*
X1572034Y311205D01*
G01X1571800Y306140D02*
Y310971D01*
G01X1570317Y304657D02*
X1571800Y306140D01*
G01X1570317Y300810D02*
Y304657D01*
G01X1563424Y293917D02*
X1570317Y300810D01*
G01X1563424Y284501D02*
Y293917D01*
G01X1563425Y284500D02*
X1563424Y284501D01*
G01X1563425Y283712D02*
Y284500D01*
G01X1529739Y300690D02*
X1534400Y296029D01*
G01X1529739Y309212D02*
Y300690D01*
G01X1533280Y312753D02*
X1529739Y309212D01*
G01X1533280Y321880D02*
Y312753D01*
G01X1531500Y323660D02*
X1533280Y321880D01*
G01X1531500Y326500D02*
Y323660D01*
G01X1534100Y329100D02*
X1531500Y326500D01*
G01X1534100Y348545D02*
Y329100D01*
G01X1586122Y337106D02*
Y345508D01*
G01X1582908Y333892D02*
X1586122Y337106D01*
G01X1582908Y329634D02*
Y333892D01*
G01X1578353Y325079D02*
X1582908Y329634D01*
G01X1578353Y310277D02*
Y325079D01*
G01X1579092Y309538D02*
X1578353Y310277D01*
G01X1579092Y306697D02*
Y309538D01*
G01X1576430Y304035D02*
X1579092Y306697D01*
G01X1576430Y298619D02*
Y304035D01*
G01X1574200Y296389D02*
X1576430Y298619D01*
G01X1574200Y291435D02*
Y296389D01*
G01X1568965Y286200D02*
X1574200Y291435D01*
G01X1568965Y282086D02*
Y286200D01*
G01X1561424Y334123D02*
Y342489D01*
G01X1561976Y333571D02*
X1561424Y334123D01*
G01X1561976Y320406D02*
Y333571D01*
G01X1561331Y319761D02*
X1561976Y320406D01*
G01X1561331Y313831D02*
Y319761D01*
G01X1561976Y313186D02*
X1561331Y313831D01*
G01X1561976Y307030D02*
Y313186D01*
G01X1557924Y302978D02*
X1561976Y307030D01*
G01X1557924Y287176D02*
Y302978D01*
G01X1559800Y285300D02*
X1557924Y287176D01*
G01X1585596Y333564D02*
X1592946Y340914D01*
G01X1585596Y328673D02*
Y333564D01*
G01X1580258Y323335D02*
X1585596Y328673D01*
G01X1580258Y311066D02*
Y323335D01*
G01X1580996Y310328D02*
X1580258Y311066D01*
G01X1580996Y305907D02*
Y310328D01*
G01X1579056Y303967D02*
X1580996Y305907D01*
G01X1579056Y298156D02*
Y303967D01*
G01X1576983Y296083D02*
X1579056Y298156D01*
G01X1576983Y282763D02*
Y296083D01*
G01X1562472Y294312D02*
Y284106D01*
G01X1568915Y300755D02*
X1562472Y294312D01*
G01X1568915Y306563D02*
Y300755D01*
G01X1568150Y307328D02*
X1568915Y306563D01*
G01X1568150Y308800D02*
Y307328D01*
G01X1571082Y311732D02*
X1568150Y308800D01*
G01X1571082Y313936D02*
Y311732D01*
G01X1569861Y315157D02*
X1571082Y313936D01*
G01X1569861Y328333D02*
Y315157D01*
G01X1571939Y330411D02*
X1569861Y328333D01*
G01X1571939Y338268D02*
Y330411D01*
G01X1573102Y339431D02*
X1571939Y338268D01*
G01X1573102Y362259D02*
Y339431D01*
G01X1576765Y335811D02*
Y350395D01*
G01X1574043Y333089D02*
X1576765Y335811D01*
G01X1574043Y329538D02*
Y333089D01*
G01X1571965Y327460D02*
X1574043Y329538D01*
G01X1571965Y316030D02*
Y327460D01*
G01X1573186Y314809D02*
X1571965Y316030D01*
G01X1573186Y310727D02*
Y314809D01*
G01X1573044Y310585D02*
X1573186Y310727D01*
G01X1573044Y305754D02*
Y310585D01*
G01X1571469Y304179D02*
X1573044Y305754D01*
G01X1571469Y300332D02*
Y304179D01*
G01X1567170Y296033D02*
X1571469Y300332D01*
G01X1567170Y289510D02*
Y296033D01*
G01X1565340Y287680D02*
X1567170Y289510D01*
G01X1565340Y283997D02*
Y287680D01*
G01X1532850Y305307D02*
Y303950D01*
G01X1536760Y309223D02*
X1532850Y305307D01*
G01X1536760Y320280D02*
Y309223D01*
G01X1541080Y324600D02*
X1536760Y320280D01*
G01X1542200Y324600D02*
X1541080D01*
G01X1547882Y318942D02*
X1542027Y313087D01*
G01X1553825Y374200D02*
Y377514D01*
G01X1548700Y369075D02*
X1553825Y374200D01*
G01X1548700Y358923D02*
Y369075D01*
G01X1554297Y353326D02*
X1548700Y358923D01*
G01X1557460Y353326D02*
X1554297D01*
G01X1557534Y353400D02*
X1557460Y353326D01*
G01X1574570Y379704D02*
Y436875D01*
G01X1566617Y371751D02*
X1574570Y379704D01*
G01X1562709Y371751D02*
X1566617D01*
G01X1557174Y366216D02*
X1562709Y371751D01*
G01X1557174Y361936D02*
Y366216D01*
G01X1558980Y360130D02*
X1557174Y361936D01*
G01X1555880Y347750D02*
X1550951Y342821D01*
G01X1560799Y347750D02*
X1555880D01*
G01X1562123Y349074D02*
X1560799Y347750D01*
G01X1562123Y351283D02*
Y349074D01*
G01X1553356Y360050D02*
X1562123Y351283D01*
G01X1553356Y367026D02*
Y360050D01*
G01X1561719Y375389D02*
X1553356Y367026D01*
G01X1586568Y366697D02*
X1591794Y361471D01*
G01X1586568Y390332D02*
Y366697D01*
G01X1584300Y392600D02*
X1586568Y390332D01*
G01X1584300Y393700D02*
Y392600D01*
G01X1587683Y397083D02*
X1584300Y393700D01*
G01X1587683Y397414D02*
Y397083D01*
G01X1536700Y346200D02*
X1535900Y345400D01*
G01X1536700Y363200D02*
Y346200D01*
G01X1538200Y364700D02*
X1536700Y363200D01*
G01X1583512Y342688D02*
X1581760D01*
G01X1575321Y379392D02*
Y437187D01*
G01X1566929Y371000D02*
X1575321Y379392D01*
G01X1566437Y371000D02*
X1566929D01*
G01X1560810Y365373D02*
X1566437Y371000D01*
G01X1560810Y364910D02*
Y365373D01*
G01X1558950Y363050D02*
X1560810Y364910D01*
G01X1583470Y396818D02*
Y404679D01*
G01X1583700Y396588D02*
X1583470Y396818D01*
G01X1583700Y395500D02*
Y396588D01*
G01X1582700Y394500D02*
X1583700Y395500D01*
G01X1582700Y391800D02*
Y394500D01*
G01X1584170Y390330D02*
X1582700Y391800D01*
G01X1584170Y365713D02*
Y390330D01*
G01X1580034Y361577D02*
X1584170Y365713D01*
G01X1580034Y351811D02*
Y361577D01*
G01X1578362Y350139D02*
X1580034Y351811D01*
G01X1573784Y394602D02*
Y436598D01*
G01X1571430Y392248D02*
X1573784Y394602D01*
G01X1571430Y390420D02*
Y392248D01*
G01X1573155Y388695D02*
X1571430Y390420D01*
G01X1573155Y379352D02*
Y388695D01*
G01X1566305Y372502D02*
X1573155Y379352D01*
G01X1562397Y372502D02*
X1566305D01*
G01X1555766Y365871D02*
X1562397Y372502D01*
G01X1555766Y360832D02*
Y365871D01*
G01X1564379Y352219D02*
X1555766Y360832D01*
G01X1564379Y348138D02*
Y352219D01*
G01X1559267Y343026D02*
X1564379Y348138D01*
G01X1557717Y346246D02*
X1553224Y341753D01*
G01X1561423Y346246D02*
X1557717D01*
G01X1563627Y348450D02*
X1561423Y346246D01*
G01X1563627Y351907D02*
Y348450D01*
G01X1555014Y360520D02*
X1563627Y351907D01*
G01X1555014Y366182D02*
Y360520D01*
G01X1562375Y373543D02*
X1555014Y366182D01*
G01X1564838Y373543D02*
X1562375D01*
G01X1568014Y376719D02*
X1564838Y373543D01*
G01X1568014Y378653D02*
Y376719D01*
G01X1569045Y379684D02*
X1568014Y378653D01*
G01X1569045Y382433D02*
Y379684D01*
G01X1568719Y382759D02*
X1569045Y382433D01*
G01X1568719Y386677D02*
Y382759D01*
G01X1569045Y387003D02*
X1568719Y386677D01*
G01X1569045Y389193D02*
Y387003D01*
G01X1567855Y390383D02*
X1569045Y389193D01*
G01X1567855Y392573D02*
Y390383D01*
G01X1569045Y393763D02*
X1567855Y392573D01*
G01X1569045Y395953D02*
Y393763D01*
G01X1567855Y397143D02*
X1569045Y395953D01*
G01X1567855Y399333D02*
Y397143D01*
G01X1569045Y400523D02*
X1567855Y399333D01*
G01X1569045Y401398D02*
Y400523D01*
G01X1573032Y405385D02*
X1569045Y401398D01*
G01X1569096Y358810D02*
X1572150Y355756D01*
G01X1569096Y367236D02*
Y358810D01*
G01X1578598Y376738D02*
X1569096Y367236D01*
G01X1578598Y410426D02*
Y376738D01*
G01X1536275Y397395D02*
Y401174D01*
G01X1533945Y395065D02*
X1536275Y397395D01*
G01X1533945Y393755D02*
Y395065D01*
G01X1535900Y391800D02*
X1533945Y393755D01*
G01X1535900Y390300D02*
Y391800D01*
G01X1537845Y388355D02*
X1535900Y390300D01*
G01X1537845Y386945D02*
Y388355D01*
G01X1535900Y385000D02*
X1537845Y386945D01*
G01X1535900Y383600D02*
Y385000D01*
G01X1534000Y381700D02*
X1535900Y383600D01*
G01X1534000Y380200D02*
Y381700D01*
G01X1532746Y378946D02*
X1534000Y380200D01*
G01X1532746Y371999D02*
Y378946D01*
G01X1528253Y367506D02*
X1532746Y371999D01*
G01X1528253Y361152D02*
Y367506D01*
G01X1530683Y358722D02*
X1528253Y361152D01*
G01X1530683Y355771D02*
Y358722D01*
G01X1532890Y353564D02*
X1530683Y355771D01*
G01X1563803Y358350D02*
X1567750Y354403D01*
G01X1563803Y366240D02*
Y358350D01*
G01X1567061Y369498D02*
X1563803Y366240D01*
G01X1568295Y369498D02*
X1567061D01*
G01X1576823Y378026D02*
X1568295Y369498D01*
G01X1576823Y415923D02*
Y378026D01*
G01X1588788Y367454D02*
X1594167Y362075D01*
G01X1590997Y393497D02*
X1588788Y391288D01*
G01X1553825Y387383D02*
Y391034D01*
G01X1551495Y385053D02*
X1553825Y387383D01*
G01X1551495Y383623D02*
Y385053D01*
G01X1549554Y381682D02*
X1551495Y383623D01*
G01X1549554Y379492D02*
Y381682D01*
G01X1548346Y378284D02*
X1549554Y379492D01*
G01X1548346Y372799D02*
Y378284D01*
G01X1545506Y369959D02*
X1548346Y372799D01*
G01X1545506Y363106D02*
Y369959D01*
G01X1543300Y360900D02*
X1545506Y363106D01*
G01X1546000Y391009D02*
X1546025Y391034D01*
G01X1546000Y387000D02*
Y391009D01*
G01X1544100Y385100D02*
X1546000Y387000D01*
G01X1544100Y383300D02*
Y385100D01*
G01X1541900Y381100D02*
X1544100Y383300D01*
G01X1541900Y379100D02*
Y381100D01*
G01X1540500Y377700D02*
X1541900Y379100D01*
G01X1540500Y375800D02*
Y377700D01*
G01X1531635Y366935D02*
X1540500Y375800D01*
G01X1531635Y357262D02*
Y366935D01*
G01X1532367Y356530D02*
X1531635Y357262D01*
G01X1528095Y383623D02*
X1527176Y382704D01*
G01X1528095Y384925D02*
Y383623D01*
G01X1534380Y400958D02*
X1532785Y399363D01*
G01X1534380Y401500D02*
Y400958D01*
G01X1535940Y403060D02*
X1534380Y401500D01*
G01X1537574Y402984D02*
X1537498Y403060D01*
G01X1544455Y404663D02*
X1542776Y402984D01*
G01X1557405Y346998D02*
X1552472Y342065D01*
G01X1561111Y346998D02*
X1557405D01*
G01X1562875Y348762D02*
X1561111Y346998D01*
G01X1562875Y351595D02*
Y348762D01*
G01X1554261Y360209D02*
X1562875Y351595D01*
G01X1554261Y361102D02*
Y360209D01*
G01X1554262Y361103D02*
X1554261Y361102D01*
G01X1554262Y366493D02*
Y361103D01*
G01X1562169Y374400D02*
X1554262Y366493D01*
G01X1564632Y374400D02*
X1562169D01*
G01X1567095Y376863D02*
X1564632Y374400D01*
G01X1567095Y378657D02*
Y376863D01*
G01X1565905Y379847D02*
X1567095Y378657D01*
G01X1565905Y382433D02*
Y379847D01*
G01X1567095Y383623D02*
X1565905Y382433D01*
G01X1567095Y384925D02*
Y383623D01*
G01X1565905Y386115D02*
X1567095Y384925D01*
G01X1565905Y389193D02*
Y386115D01*
G01X1567095Y390383D02*
X1565905Y389193D01*
G01X1567095Y391685D02*
Y390383D01*
G01X1565905Y392875D02*
X1567095Y391685D01*
G01X1565905Y395953D02*
Y392875D01*
G01X1567095Y397143D02*
X1565905Y395953D01*
G01X1567095Y398445D02*
Y397143D01*
G01X1565360Y400180D02*
X1567095Y398445D01*
G01X1565360Y408893D02*
Y400180D01*
G01X1530045Y395065D02*
X1527610Y397500D01*
G01X1530045Y393955D02*
Y395065D01*
G01X1532000Y392000D02*
X1530045Y393955D01*
G01X1532000Y390300D02*
Y392000D01*
G01X1533945Y388355D02*
X1532000Y390300D01*
G01X1533945Y386945D02*
Y388355D01*
G01X1532000Y385000D02*
X1533945Y386945D01*
G01X1532000Y383500D02*
Y385000D01*
G01X1530796Y382296D02*
X1532000Y383500D01*
G01X1530796Y379364D02*
Y382296D01*
G01X1531995Y378165D02*
X1530796Y379364D01*
G01X1531995Y373282D02*
Y378165D01*
G01X1527199Y368486D02*
X1531995Y373282D01*
G01X1527199Y360725D02*
Y368486D01*
G01X1529731Y358193D02*
X1527199Y360725D01*
G01X1529731Y355376D02*
Y358193D01*
G01X1531938Y353169D02*
X1529731Y355376D01*
G01X1551800Y394339D02*
X1551875Y394414D01*
G01X1551800Y390300D02*
Y394339D01*
G01X1550100Y388600D02*
X1551800Y390300D01*
G01X1550100Y387100D02*
Y388600D01*
G01X1547595Y384595D02*
X1550100Y387100D01*
G01X1547595Y383195D02*
Y384595D01*
G01X1546405Y382005D02*
X1547595Y383195D01*
G01X1546405Y381003D02*
Y382005D01*
G01X1544400Y378998D02*
X1546405Y381003D01*
G01X1544400Y373900D02*
Y378998D01*
G01X1540100Y369600D02*
X1544400Y373900D01*
G01X1540100Y343200D02*
Y369600D01*
G01X1530333Y347562D02*
X1528210Y345439D01*
G01X1530333Y353427D02*
Y347562D01*
G01X1528779Y354981D02*
X1530333Y353427D01*
G01X1528779Y357708D02*
Y354981D01*
G01X1528095Y378205D02*
Y374765D01*
G01X1530045Y380155D02*
X1528095Y378205D01*
G01X1530045Y381545D02*
Y380155D01*
G01X1528846Y382744D02*
X1530045Y381545D01*
G01X1528846Y385746D02*
Y382744D01*
G01X1530045Y386945D02*
X1528846Y385746D01*
G01X1530045Y388355D02*
Y386945D01*
G01X1528844Y389556D02*
X1530045Y388355D01*
G01X1528844Y394045D02*
Y389556D01*
G01X1528475Y394414D02*
X1528844Y394045D01*
G01X1577775Y377631D02*
Y415528D01*
G01X1568690Y368546D02*
X1577775Y377631D01*
G01X1567456Y368546D02*
X1568690D01*
G01X1564755Y365845D02*
X1567456Y368546D01*
G01X1564755Y358745D02*
Y365845D01*
G01X1568702Y354798D02*
X1564755Y358745D01*
G01X1542834Y355210D02*
X1540900Y353276D01*
G01X1542834Y355740D02*
Y355210D01*
G01X1542932Y355740D02*
X1542834D01*
G01X1580430Y369869D02*
Y404384D01*
G01X1574298Y363737D02*
X1580430Y369869D01*
G01X1574298Y357070D02*
Y363737D01*
G01X1575526Y355842D02*
X1574298Y357070D01*
G01X1535548Y349993D02*
X1534100Y348545D01*
G01X1535548Y363678D02*
Y349993D01*
G01X1535566Y363696D02*
X1535548Y363678D01*
G01X1535566Y364384D02*
Y363696D01*
G01X1533589Y366361D02*
X1535566Y364384D01*
G01X1585150Y395850D02*
Y397400D01*
G01X1583500Y394200D02*
X1585150Y395850D01*
G01X1583500Y392100D02*
Y394200D01*
G01X1585150Y390450D02*
X1583500Y392100D01*
G01X1585150Y364249D02*
Y390450D01*
G01X1584924Y364023D02*
X1585150Y364249D01*
G01X1584924Y346706D02*
Y364023D01*
G01X1586122Y345508D02*
X1584924Y346706D01*
G01X1576072Y379080D02*
Y439156D01*
G01X1567241Y370249D02*
X1576072Y379080D01*
G01X1566749Y370249D02*
X1567241D01*
G01X1563051Y366551D02*
X1566749Y370249D01*
G01X1563051Y357019D02*
Y366551D01*
G01X1565131Y354939D02*
X1563051Y357019D01*
G01X1565131Y346196D02*
Y354939D01*
G01X1561424Y342489D02*
X1565131Y346196D01*
G01X1587836Y391835D02*
X1590000Y393999D01*
G01X1587836Y367059D02*
Y391835D01*
G01X1592946Y361949D02*
X1587836Y367059D01*
G01X1571951Y363410D02*
X1573102Y362259D01*
G01X1571951Y368802D02*
Y363410D01*
G01X1579579Y376430D02*
X1571951Y368802D01*
G01X1579579Y406784D02*
Y376430D01*
G01X1578065Y362013D02*
X1581822Y365770D01*
G01X1578065Y351695D02*
Y362013D01*
G01X1576765Y350395D02*
X1578065Y351695D01*
G01X1571279Y440166D02*
X1569425D01*
G01X1574570Y436875D02*
X1571279Y440166D01*
G01X1565525Y450035D02*
Y453686D01*
G01X1567095Y448465D02*
X1565525Y450035D01*
G01X1567095Y445387D02*
Y448465D01*
G01X1565905Y444197D02*
X1567095Y445387D01*
G01X1565905Y442895D02*
Y444197D01*
G01X1566824Y441976D02*
X1565905Y442895D01*
G01X1570532Y441976D02*
X1566824D01*
G01X1575321Y437187D02*
X1570532Y441976D01*
G01X1583470Y404679D02*
X1583208Y404941D01*
G01X1563955Y439515D02*
Y443499D01*
G01X1564874Y438596D02*
X1563955Y439515D01*
G01X1571786Y438596D02*
X1564874D01*
G01X1573784Y436598D02*
X1571786Y438596D01*
G01X1573032Y409928D02*
Y405385D01*
G01X1569579Y413381D02*
X1573032Y409928D01*
G01X1569579Y415699D02*
Y413381D01*
G01X1567855Y417423D02*
X1569579Y415699D01*
G01X1567855Y419613D02*
Y417423D01*
G01X1569045Y420803D02*
X1567855Y419613D01*
G01X1569045Y422993D02*
Y420803D01*
G01X1567855Y424183D02*
X1569045Y422993D01*
G01X1567855Y426373D02*
Y424183D01*
G01X1569045Y427563D02*
X1567855Y426373D01*
G01X1569045Y429753D02*
Y427563D01*
G01X1567855Y430943D02*
X1569045Y429753D01*
G01X1567855Y433266D02*
Y430943D01*
G01X1571375Y436786D02*
X1567855Y433266D01*
G01X1582735Y414563D02*
X1578598Y410426D01*
G01X1590548Y414563D02*
X1582735D01*
G01X1587238Y426338D02*
X1576823Y415923D01*
G01X1587238Y432593D02*
Y426338D01*
G01X1585741Y434169D02*
X1590612D01*
G01X1583773Y436137D02*
X1585741Y434169D01*
G01X1537498Y403060D02*
X1535940D01*
G01X1542776Y402984D02*
X1537574D01*
G01X1544455Y405205D02*
Y404663D01*
G01X1545374Y406124D02*
X1544455Y405205D01*
G01X1545916Y406124D02*
X1545374D01*
G01X1546879Y407087D02*
X1545916Y406124D01*
G01X1546879Y409120D02*
Y407087D01*
G01X1547200Y409441D02*
X1546879Y409120D01*
G01X1547200Y412000D02*
Y409441D01*
G01X1550200Y415000D02*
X1547200Y412000D01*
G01X1550200Y416726D02*
Y415000D01*
G01X1553610Y420136D02*
X1550200Y416726D01*
G01X1553610Y422410D02*
Y420136D01*
G01X1552100Y423920D02*
X1553610Y422410D01*
G01X1552100Y425750D02*
Y423920D01*
G01X1553690Y427340D02*
X1552100Y425750D01*
G01X1553690Y428440D02*
Y427340D01*
G01X1555710Y430460D02*
X1553690Y428440D01*
G01X1555710Y431748D02*
Y430460D01*
G01X1558100Y434138D02*
X1555710Y431748D01*
G01X1558100Y438000D02*
Y434138D01*
G01X1559295Y439195D02*
X1558100Y438000D01*
G01X1559295Y441405D02*
Y439195D01*
G01X1558105Y442595D02*
X1559295Y441405D01*
G01X1558105Y444805D02*
Y442595D01*
G01X1559295Y445995D02*
X1558105Y444805D01*
G01X1559295Y450331D02*
Y445995D01*
G01X1559595Y450631D02*
X1559295Y450331D01*
G01X1563332Y410921D02*
X1565360Y408893D01*
G01X1563332Y411828D02*
Y410921D01*
G01X1561680Y413480D02*
X1563332Y411828D01*
G01X1561680Y415588D02*
Y413480D01*
G01X1563620Y417528D02*
X1561680Y415588D01*
G01X1563620Y418653D02*
Y417528D01*
G01X1565905Y420938D02*
X1563620Y418653D01*
G01X1565905Y422993D02*
Y420938D01*
G01X1567095Y424183D02*
X1565905Y422993D01*
G01X1567095Y425485D02*
Y424183D01*
G01X1565527Y427053D02*
X1567095Y425485D01*
G01X1565527Y428819D02*
Y427053D01*
G01X1563955Y430391D02*
X1565527Y428819D01*
G01X1563955Y433266D02*
Y430391D01*
G01X1567475Y436786D02*
X1563955Y433266D01*
G01X1578999Y416752D02*
X1583208D01*
G01X1577775Y415528D02*
X1578999Y416752D01*
G01X1585265Y407800D02*
X1589500Y412035D01*
G01X1583846Y407800D02*
X1585265D01*
G01X1580430Y404384D02*
X1583846Y407800D01*
G01X1570610Y445741D02*
X1569425Y446926D01*
G01X1571401Y445741D02*
X1570610D01*
G01X1573900Y443242D02*
X1571401Y445741D01*
G01X1573900Y441328D02*
Y443242D01*
G01X1576072Y439156D02*
X1573900Y441328D01*
G01X1588234Y403368D02*
X1587968D01*
G01X1590000Y401602D02*
X1588234Y403368D01*
G01X1586406Y413611D02*
X1579579Y406784D01*
G01X1590153Y413611D02*
X1586406D01*
G01X1577977Y524641D02*
X1593369Y509251D01*
G01X1572138Y524641D02*
X1577977D01*
G01X1569215Y527564D02*
X1572138Y524641D01*
G01X1579537Y528401D02*
X1593323Y514624D01*
G01X1581238Y532505D02*
X1595027Y518728D01*
G01X1579225Y527649D02*
X1593008Y513872D01*
G01X1540175Y474825D02*
Y470586D01*
G01X1538500Y476500D02*
X1540175Y474825D01*
G01X1538500Y477600D02*
Y476500D01*
G01X1537000Y479100D02*
X1538500Y477600D01*
G01X1537000Y479730D02*
Y479100D01*
G01X1536655Y480075D02*
X1537000Y479730D01*
G01X1536655Y481045D02*
Y480075D01*
G01X1535300Y482400D02*
X1536655Y481045D01*
G01X1578289Y525393D02*
X1592068Y511616D01*
G01X1572450Y525393D02*
X1578289D01*
G01X1569527Y528316D02*
X1572450Y525393D01*
G01X1578601Y526145D02*
X1592381Y512368D01*
G01X1572762Y526145D02*
X1578601D01*
G01X1569839Y529068D02*
X1572762Y526145D01*
G01X1580014Y529553D02*
X1593803Y515776D01*
G01X1592694Y513120D02*
X1578913Y526897D01*
G01X1577290Y533457D02*
X1591780D01*
G01X1574367Y536380D02*
X1577290Y533457D01*
G01X1531601Y536380D02*
X1574367D01*
G01X1541557Y540750D02*
X1588813D01*
G01X1541419Y540612D02*
X1541557Y540750D01*
G01X1529499Y540612D02*
X1541419D01*
G01X1538166Y527564D02*
X1569215D01*
G01X1535565Y591658D02*
X1530893Y586986D01*
G01X1573698Y528401D02*
X1579537D01*
G01X1570775Y531324D02*
X1573698Y528401D01*
G01X1536606Y531324D02*
X1570775D01*
G01X1541186Y541702D02*
X1589208D01*
G01X1541048Y541564D02*
X1541186Y541702D01*
G01X1529104Y541564D02*
X1541048D01*
G01X1576895Y532505D02*
X1581238D01*
G01X1573972Y535428D02*
X1576895Y532505D01*
G01X1531996Y535428D02*
X1573972D01*
G01X1573386Y527649D02*
X1579225D01*
G01X1570463Y530572D02*
X1573386Y527649D01*
G01X1536918Y530572D02*
X1570463D01*
G01X1578198Y534409D02*
X1591385D01*
G01X1575275Y537332D02*
X1578198Y534409D01*
G01X1531206Y537332D02*
X1575275D01*
G01X1578593Y535361D02*
X1590990D01*
G01X1574494Y539460D02*
X1578593Y535361D01*
G01X1531987Y539460D02*
X1574494D01*
G01X1537854Y528316D02*
X1569527D01*
G01X1537542Y529068D02*
X1569839D01*
G01X1574177Y529553D02*
X1580014D01*
G01X1571254Y532476D02*
X1574177Y529553D01*
G01X1536128Y532476D02*
X1571254D01*
G01X1570151Y529820D02*
X1537230D01*
G01X1573074Y526897D02*
X1570151Y529820D01*
G01X1578913Y526897D02*
X1573074D01*
G01X1555395Y582898D02*
X1561795Y589298D01*
G01X1544533Y582898D02*
X1555395D01*
G01X1543424Y584007D02*
X1544533Y582898D01*
G01X1543424Y584900D02*
Y584007D01*
G01X1542600Y585724D02*
X1543424Y584900D01*
G01X1529318Y587828D02*
X1534992Y593502D01*
G01X1555000Y583850D02*
X1561400Y590250D01*
G01X1544928Y583850D02*
X1555000D01*
G01X1544376Y584402D02*
X1544928Y583850D01*
G01X1544376Y584900D02*
Y584402D01*
G01X1545200Y585724D02*
X1544376Y584900D01*
G01X1583282Y599000D02*
X1590800D01*
G01X1582188Y597906D02*
X1583282Y599000D01*
G01X1574317Y597906D02*
X1582188D01*
G01X1570660Y601563D02*
X1574317Y597906D01*
G01X1581500Y620100D02*
X1586700D01*
G01X1578200Y616800D02*
X1581500Y620100D01*
G01X1550948Y616800D02*
X1578200D01*
G01X1547202Y620546D02*
X1550948Y616800D01*
G01X1540715Y620546D02*
X1547202D01*
G01X1540477Y620308D02*
X1540715Y620546D01*
G01X1573589Y622842D02*
X1617311D01*
G01X1569095Y618348D02*
X1573589Y622842D01*
G01X1550822Y618348D02*
X1569095D01*
G01X1546235Y622935D02*
X1550822Y618348D01*
G01X1582688Y600800D02*
X1590608D01*
G01X1581308Y599420D02*
X1582688Y600800D01*
G01X1575440Y599420D02*
X1581308D01*
G01X1573260Y601600D02*
X1575440Y599420D01*
G01X1573194Y623794D02*
X1617706D01*
G01X1568700Y619300D02*
X1573194Y623794D01*
G01X1551300Y619300D02*
X1568700D01*
G01X1546874Y623726D02*
X1551300Y619300D01*
G01X1584753Y608703D02*
X1591767Y615717D01*
G01X1575672Y608703D02*
X1584753D01*
G01X1571060Y604091D02*
X1575672Y608703D01*
G01X1569612Y604091D02*
X1571060D01*
G01X1567802Y602281D02*
X1569612Y604091D01*
G01X1567802Y599090D02*
Y602281D01*
G01X1565603Y596891D02*
X1567802Y599090D01*
G01X1557452Y596891D02*
X1565603D01*
G01X1554815Y594254D02*
X1557452Y596891D01*
G01X1534124Y594254D02*
X1554815D01*
G01X1528538Y588668D02*
X1534124Y594254D01*
G01X1577545Y592848D02*
X1590748D01*
G01X1573995Y589298D02*
X1577545Y592848D01*
G01X1561795Y589298D02*
X1573995D01*
G01X1585030Y607751D02*
X1592719Y615440D01*
G01X1576067Y607751D02*
X1585030D01*
G01X1571655Y603339D02*
X1576067Y607751D01*
G01X1569924Y603339D02*
X1571655D01*
G01X1568554Y601969D02*
X1569924Y603339D01*
G01X1568554Y598495D02*
Y601969D01*
G01X1565998Y595939D02*
X1568554Y598495D01*
G01X1557847Y595939D02*
X1565998D01*
G01X1555410Y593502D02*
X1557847Y595939D01*
G01X1534992Y593502D02*
X1555410D01*
G01X1577150Y593800D02*
X1590353D01*
G01X1573600Y590250D02*
X1577150Y593800D01*
G01X1561400Y590250D02*
X1573600D01*
G01X1607061Y28277D02*
X1752974D01*
G01X1607060Y28276D02*
X1607061Y28277D01*
G01X1606272Y28276D02*
X1607060D01*
G01X1594887Y39661D02*
X1606272Y28276D01*
G01X1591400Y26683D02*
X1589401Y28682D01*
G01X1591400Y25423D02*
Y26683D01*
G01X1592363Y24460D02*
X1591400Y25423D01*
G01X1592829Y24460D02*
X1592363D01*
G01X1619244Y-8456D02*
X1616700Y-11000D01*
G01X1668715Y-8456D02*
X1619244D01*
G01X1604500Y-700D02*
X1602400Y-2800D01*
G01X1636396Y-700D02*
X1604500D01*
G01X1643000Y-7304D02*
X1636396Y-700D01*
G01X1667996Y-7304D02*
X1643000D01*
G01X1597800Y26371D02*
Y24300D01*
G01X1591633Y32538D02*
X1597800Y26371D01*
G01X1607061Y30181D02*
X1753764D01*
G01X1595050Y42192D02*
X1607061Y30181D01*
G01X1645126Y22800D02*
X1718580D01*
G01X1640801Y27125D02*
X1645126Y22800D01*
G01X1607539Y27125D02*
X1640801D01*
G01X1607538Y27124D02*
X1607539Y27125D01*
G01X1605794Y27124D02*
X1607538D01*
G01X1605793Y27125D02*
X1605794Y27124D01*
G01X1603774Y27125D02*
X1605793D01*
G01X1596559Y34340D02*
X1603774Y27125D01*
G01X1589061Y31339D02*
X1589060Y31338D01*
G01X1590307Y31339D02*
X1589061D01*
G01X1595909Y25737D02*
X1590307Y31339D01*
G01X1595909Y23200D02*
Y25737D01*
G01X1597209Y21900D02*
X1595909Y23200D01*
G01X1603000Y21900D02*
X1597209D01*
G01X1604436Y23336D02*
X1603000Y21900D01*
G01X1629818Y23336D02*
X1604436D01*
G01X1631185Y24703D02*
X1629818Y23336D01*
G01X1641360Y24703D02*
X1631185D01*
G01X1646407Y19656D02*
X1641360Y24703D01*
G01X1671602Y19656D02*
X1646407D01*
G01X1600848Y5052D02*
X1589752D01*
G01X1604148Y1752D02*
X1600848Y5052D01*
G01X1637426Y1752D02*
X1604148D01*
G01X1644578Y-5400D02*
X1637426Y1752D01*
G01X1663601Y-5400D02*
X1644578D01*
G01X1645648Y18152D02*
X1670978D01*
G01X1640601Y23199D02*
X1645648Y18152D01*
G01X1633100Y23199D02*
X1640601D01*
G01X1630153Y20252D02*
X1633100Y23199D01*
G01X1596448Y20252D02*
X1630153D01*
G01X1594405Y22295D02*
X1596448Y20252D01*
G01X1594405Y25113D02*
Y22295D01*
G01X1589684Y29834D02*
X1594405Y25113D01*
G01X1648094Y11500D02*
X1653100D01*
G01X1639594Y3000D02*
X1648094Y11500D01*
G01X1604530Y3000D02*
X1639594D01*
G01X1601326Y6204D02*
X1604530Y3000D01*
G01X1590230Y6204D02*
X1601326D01*
G01X1634959Y19100D02*
X1637482Y21623D01*
G01X1589373Y30587D02*
X1589372Y30586D01*
G01X1589995Y30587D02*
X1589373D01*
G01X1595157Y25425D02*
X1589995Y30587D01*
G01X1595157Y22607D02*
Y25425D01*
G01X1596760Y21004D02*
X1595157Y22607D01*
G01X1628550Y21004D02*
X1596760D01*
G01X1631497Y23951D02*
X1628550Y21004D01*
G01X1641048Y23951D02*
X1631497D01*
G01X1646095Y18904D02*
X1641048Y23951D01*
G01X1671290Y18904D02*
X1646095D01*
G01X1644100Y-6552D02*
X1667448D01*
G01X1636948Y600D02*
X1644100Y-6552D01*
G01X1603300Y600D02*
X1636948D01*
G01X1602300Y1600D02*
X1603300Y600D01*
G01X1590648Y25553D02*
X1589623Y24528D01*
G01X1590648Y26371D02*
Y25553D01*
G01X1589089Y27930D02*
X1590648Y26371D01*
G01X1618300Y-19000D02*
X1671350D01*
G01X1611708Y-12408D02*
X1618300Y-19000D01*
G01X1606666Y29229D02*
X1753369D01*
G01X1594655Y41240D02*
X1606666Y29229D01*
G01X1634388Y73500D02*
X1617456Y56568D01*
G01X1635337Y73500D02*
X1634388D01*
G01X1649900Y64161D02*
X1650876Y65137D01*
G01X1649900Y61734D02*
Y64161D01*
G01X1642830Y54664D02*
X1649900Y61734D01*
G01X1654047Y62125D02*
X1644482Y52560D01*
G01X1645667Y49704D02*
X1655232Y59269D01*
G01X1601024Y93925D02*
X1604000D01*
G01X1595300Y88201D02*
X1601024Y93925D01*
G01X1595300Y81023D02*
Y88201D01*
G01X1593000Y78723D02*
X1595300Y81023D01*
G01X1593000Y78140D02*
Y78723D01*
G01X1655478Y58168D02*
X1646062Y48752D01*
G01X1649549Y75651D02*
X1667264D01*
G01X1646820Y78380D02*
X1649549Y75651D01*
G01X1632488Y78380D02*
X1646820D01*
G01X1628356Y82512D02*
X1632488Y78380D01*
G01X1624624Y82512D02*
X1628356D01*
G01X1621636Y79524D02*
X1624624Y82512D01*
G01X1615624Y79524D02*
X1621636D01*
G01X1612214Y82934D02*
X1615624Y79524D01*
G01X1612214Y101736D02*
Y82934D01*
G01X1649173Y87785D02*
X1657999Y78959D01*
G01X1640139Y87785D02*
X1649173D01*
G01X1635524Y92400D02*
X1640139Y87785D01*
G01X1630700Y92400D02*
X1635524D01*
G01X1626339Y96761D02*
X1630700Y92400D01*
G01X1589109Y79969D02*
Y79029D01*
G01X1592393Y83253D02*
X1589109Y79969D01*
G01X1592393Y90293D02*
Y83253D01*
G01X1593600Y91500D02*
X1592393Y90293D01*
G01X1593600Y105728D02*
Y91500D01*
G01X1625075Y74083D02*
Y80182D01*
G01X1623103Y72111D02*
X1625075Y74083D01*
G01X1619281Y72111D02*
X1623103D01*
G01X1615870Y68700D02*
X1619281Y72111D01*
G01X1593700Y68700D02*
X1615870D01*
G01X1593159Y69241D02*
X1593700Y68700D01*
G01X1592004Y69241D02*
X1593159D01*
G01X1591476Y90775D02*
Y83400D01*
G01X1592845Y92144D02*
X1591476Y90775D01*
G01X1592845Y104875D02*
Y92144D01*
G01X1596050Y76100D02*
Y75400D01*
G01X1596800Y76850D02*
X1596050Y76100D01*
G01X1598000Y76850D02*
X1596800D01*
G01X1600550Y79400D02*
X1598000Y76850D01*
G01X1607001Y79400D02*
X1600550D01*
G01X1609738Y82137D02*
X1607001Y79400D01*
G01X1609738Y95362D02*
Y82137D01*
G01X1621376Y77624D02*
X1623200Y75800D01*
G01X1613697Y77624D02*
X1621376D01*
G01X1610588Y80733D02*
X1613697Y77624D01*
G01X1610588Y104803D02*
Y80733D01*
G01X1647247Y45896D02*
X1656033Y54682D01*
G01X1649757Y89193D02*
X1659150Y79800D01*
G01X1640723Y89193D02*
X1649757D01*
G01X1635084Y94832D02*
X1640723Y89193D01*
G01X1656318Y53337D02*
X1647725Y44744D01*
G01X1655540Y56883D02*
X1646457Y47800D01*
G01X1646852Y46848D02*
X1655787Y55783D01*
G01X1654442Y61173D02*
X1644877Y51608D01*
G01X1648276Y65121D02*
Y65221D01*
G01X1648948Y64449D02*
X1648276Y65121D01*
G01X1648948Y61846D02*
Y64449D01*
G01X1642518Y55416D02*
X1648948Y61846D01*
G01X1653652Y63077D02*
X1644087Y53512D01*
G01X1645272Y50656D02*
X1654837Y60221D01*
G01X1609116Y155705D02*
Y163347D01*
G01X1608304Y154893D02*
X1609116Y155705D01*
G01X1606439Y154893D02*
X1608304D01*
G01X1605461Y153915D02*
X1606439Y154893D01*
G01X1605461Y152717D02*
Y153915D01*
G01X1606776Y151402D02*
X1605461Y152717D01*
G01X1606776Y148470D02*
Y151402D01*
G01X1605900Y147594D02*
X1606776Y148470D01*
G01X1605900Y141482D02*
Y147594D01*
G01X1603373Y138955D02*
X1605900Y141482D01*
G01X1603373Y138457D02*
Y138955D01*
G01X1604292Y137538D02*
X1603373Y138457D01*
G01X1624675Y151625D02*
X1623200Y153100D01*
G01X1647805Y151625D02*
X1624675D01*
G01X1647818Y151638D02*
X1647805Y151625D01*
G01X1649042Y151638D02*
X1647818D01*
G01X1649055Y151625D02*
X1649042Y151638D01*
G01X1665290Y151625D02*
X1649055D01*
G01X1589355Y135376D02*
X1589880Y134851D01*
G01X1589355Y136709D02*
Y135376D01*
G01X1649765Y139101D02*
X1670464D01*
G01X1648362Y140504D02*
X1649765Y139101D01*
G01X1629965Y140504D02*
X1648362D01*
G01X1626999Y137538D02*
X1629965Y140504D01*
G01X1613741Y137538D02*
X1626999D01*
G01X1615363Y104885D02*
X1612214Y101736D01*
G01X1615363Y116265D02*
Y104885D01*
G01X1616098Y117000D02*
X1615363Y116265D01*
G01X1617548Y117000D02*
X1616098D01*
G01X1618504Y117956D02*
X1617548Y117000D01*
G01X1618504Y120593D02*
Y117956D01*
G01X1615415Y123682D02*
X1618504Y120593D01*
G01X1615415Y125352D02*
Y123682D01*
G01X1615166Y125601D02*
X1615415Y125352D01*
G01X1615166Y125602D02*
Y125601D01*
G01X1614302Y126466D02*
X1615166Y125602D01*
G01X1614301Y126466D02*
X1614302D01*
G01X1614250Y126517D02*
X1614301Y126466D01*
G01X1612677Y126517D02*
X1614250D01*
G01X1612215Y126979D02*
X1612677Y126517D01*
G01X1612215Y129901D02*
Y126979D01*
G01X1608916Y133200D02*
X1612215Y129901D01*
G01X1608916Y141180D02*
Y133200D01*
G01X1609971Y142235D02*
X1608916Y141180D01*
G01X1611295Y142235D02*
X1609971D01*
G01X1612258Y143198D02*
X1611295Y142235D01*
G01X1612258Y147708D02*
Y143198D01*
G01X1611524Y148442D02*
X1612258Y147708D01*
G01X1611223Y148442D02*
X1611524D01*
G01X1611203Y148462D02*
X1611223Y148442D01*
G01X1610179Y148462D02*
X1611203D01*
G01X1609038Y149603D02*
X1610179Y148462D01*
G01X1609038Y150796D02*
Y149603D01*
G01X1609981Y151739D02*
X1609038Y150796D01*
G01X1614454Y151739D02*
X1609981D01*
G01X1615322Y152607D02*
X1614454Y151739D01*
G01X1615322Y156605D02*
Y152607D01*
G01X1626339Y109191D02*
Y96761D01*
G01X1602700Y120232D02*
X1607441Y115491D01*
G01X1602700Y126661D02*
Y120232D01*
G01X1598673Y130688D02*
X1602700Y126661D01*
G01X1598673Y159309D02*
Y130688D01*
G01X1605224Y131358D02*
X1607239D01*
G01X1601945Y134637D02*
X1605224Y131358D01*
G01X1601945Y138780D02*
Y134637D01*
G01X1603500Y140335D02*
X1601945Y138780D01*
G01X1603500Y140748D02*
Y140335D01*
G01X1603528Y140776D02*
X1603500Y140748D01*
G01X1603528Y148511D02*
Y140776D01*
G01X1603679Y148662D02*
X1603528Y148511D01*
G01X1604904Y148662D02*
X1603679D01*
G01X1605767Y149525D02*
X1604904Y148662D01*
G01X1605767Y150749D02*
Y149525D01*
G01X1605359Y151157D02*
X1605767Y150749D01*
G01X1605359Y151357D02*
Y151157D01*
G01X1604391Y152325D02*
X1605359Y151357D01*
G01X1604391Y154406D02*
Y152325D01*
G01X1605918Y155933D02*
X1604391Y154406D01*
G01X1605918Y163365D02*
Y155933D01*
G01X1591463Y107865D02*
X1593600Y105728D01*
G01X1591463Y116002D02*
Y107865D01*
G01X1597336Y121875D02*
X1591463Y116002D01*
G01X1597336Y128836D02*
Y121875D01*
G01X1596082Y130090D02*
X1597336Y128836D01*
G01X1596082Y142581D02*
Y130090D01*
G01X1594565Y144098D02*
X1596082Y142581D01*
G01X1594565Y148720D02*
Y144098D01*
G01X1649058Y103842D02*
X1664504D01*
G01X1645237Y107663D02*
X1649058Y103842D01*
G01X1645237Y109191D02*
Y107663D01*
G01X1590775Y133348D02*
Y121000D01*
G01X1591666Y134239D02*
X1590775Y133348D01*
G01X1591666Y135488D02*
Y134239D01*
G01X1592375Y136197D02*
X1591666Y135488D01*
G01X1594322Y136197D02*
X1592375D01*
G01X1595331Y137206D02*
X1594322Y136197D01*
G01X1595331Y142269D02*
Y137206D01*
G01X1592045Y145555D02*
X1595331Y142269D01*
G01X1592045Y154868D02*
Y145555D01*
G01X1590404Y156509D02*
X1592045Y154868D01*
G01X1591527Y131191D02*
Y120689D01*
G01X1593241Y132905D02*
X1591527Y131191D01*
G01X1593241Y134295D02*
Y132905D01*
G01X1611436Y140688D02*
X1610591D01*
G01X1613151Y142403D02*
X1611436Y140688D01*
G01X1624448Y142403D02*
X1613151D01*
G01X1628269Y146224D02*
X1624448Y142403D01*
G01X1647991Y146224D02*
X1628269D01*
G01X1648738Y145477D02*
X1647991Y146224D01*
G01X1671856Y145477D02*
X1648738D01*
G01X1605493Y99607D02*
X1609738Y95362D01*
G01X1605493Y108193D02*
Y99607D01*
G01X1608985Y111685D02*
X1605493Y108193D01*
G01X1608985Y116243D02*
Y111685D01*
G01X1609726Y116984D02*
X1608985Y116243D01*
G01X1611362Y116984D02*
X1609726D01*
G01X1612220Y117842D02*
X1611362Y116984D01*
G01X1612220Y122394D02*
Y117842D01*
G01X1611151Y123463D02*
X1612220Y122394D01*
G01X1609979Y123463D02*
X1611151D01*
G01X1609978Y123464D02*
X1609979Y123463D01*
G01X1609647Y123464D02*
X1609978D01*
G01X1608916Y124195D02*
X1609647Y123464D01*
G01X1608916Y124326D02*
Y124195D01*
G01X1608917Y124327D02*
X1608916Y124326D01*
G01X1608917Y125551D02*
Y124327D01*
G01X1608053Y126415D02*
X1608917Y125551D01*
G01X1608052Y126415D02*
X1608053D01*
G01X1607682Y126785D02*
X1608052Y126415D01*
G01X1607682Y127279D02*
Y126785D01*
G01X1601104Y133857D02*
X1607682Y127279D01*
G01X1601104Y139415D02*
Y133857D01*
G01X1602777Y141088D02*
X1601104Y139415D01*
G01X1602777Y152185D02*
Y141088D01*
G01X1602775Y152187D02*
X1602777Y152185D01*
G01X1602775Y152513D02*
Y152187D01*
G01X1602552Y152736D02*
X1602775Y152513D01*
G01X1602552Y156922D02*
Y152736D01*
G01X1609116Y106275D02*
X1610588Y104803D01*
G01X1609116Y109802D02*
Y106275D01*
G01X1609980Y110666D02*
X1609116Y109802D01*
G01X1611002Y110666D02*
X1609980D01*
G01X1611201Y110865D02*
X1611002Y110666D01*
G01X1611203Y110865D02*
X1611201D01*
G01X1612067Y111729D02*
X1611203Y110865D01*
G01X1612067Y115905D02*
Y111729D01*
G01X1613129Y116967D02*
X1612067Y115905D01*
G01X1614156Y116967D02*
X1613129D01*
G01X1615217Y118028D02*
X1614156Y116967D01*
G01X1615217Y122402D02*
Y118028D01*
G01X1615216Y122403D02*
X1615217Y122402D01*
G01X1615216Y122532D02*
Y122403D01*
G01X1614346Y123402D02*
X1615216Y122532D01*
G01X1613204Y123402D02*
X1614346D01*
G01X1613092Y123514D02*
X1613204Y123402D01*
G01X1613078Y123514D02*
X1613092D01*
G01X1612214Y124378D02*
X1613078Y123514D01*
G01X1612214Y125404D02*
Y124378D01*
G01X1611203Y126415D02*
X1612214Y125404D01*
G01X1609979Y126415D02*
X1611203D01*
G01X1609978Y126414D02*
X1609979Y126415D01*
G01X1609906Y126414D02*
X1609978D01*
G01X1608961Y127359D02*
X1609906Y126414D01*
G01X1608961Y129061D02*
Y127359D01*
G01X1608917Y129105D02*
X1608961Y129061D01*
G01X1608917Y131885D02*
Y129105D01*
G01X1607888Y132914D02*
X1608917Y131885D01*
G01X1606829Y132914D02*
X1607888D01*
G01X1606818Y132925D02*
X1606829Y132914D01*
G01X1606225Y132925D02*
X1606818D01*
G01X1605858Y133292D02*
X1606225Y132925D01*
G01X1605858Y138582D02*
Y133292D01*
G01X1607356Y140080D02*
X1605858Y138582D01*
G01X1607356Y141180D02*
Y140080D01*
G01X1608917Y142741D02*
X1607356Y141180D01*
G01X1608917Y147891D02*
Y142741D01*
G01X1607754Y149054D02*
X1608917Y147891D01*
G01X1607754Y151512D02*
Y149054D01*
G01X1608916Y152674D02*
X1607754Y151512D01*
G01X1608916Y152693D02*
Y152674D01*
G01X1608917Y152694D02*
X1608916Y152693D01*
G01X1608917Y153824D02*
Y152694D01*
G01X1610054Y154961D02*
X1608917Y153824D01*
G01X1611203Y154961D02*
X1610054D01*
G01X1611257Y155015D02*
X1611203Y154961D01*
G01X1611722Y155015D02*
X1611257D01*
G01X1612120Y155413D02*
X1611722Y155015D01*
G01X1612120Y157104D02*
Y155413D01*
G01X1644911Y142342D02*
X1671412D01*
G01X1643948Y141379D02*
X1644911Y142342D01*
G01X1629309Y141379D02*
X1643948D01*
G01X1627001Y139071D02*
X1629309Y141379D01*
G01X1612599Y139071D02*
X1627001D01*
G01X1611066Y137538D02*
X1612599Y139071D01*
G01X1610591Y137538D02*
X1611066D01*
G01X1635084Y98330D02*
Y94832D01*
G01X1627857Y105557D02*
X1635084Y98330D01*
G01X1627857Y116604D02*
Y105557D01*
G01X1628059Y116806D02*
X1627857Y116604D01*
G01X1628059Y117983D02*
Y116806D01*
G01X1628014Y118028D02*
X1628059Y117983D01*
G01X1628014Y119252D02*
Y118028D01*
G01X1628059Y119297D02*
X1628014Y119252D01*
G01X1628059Y120000D02*
Y119297D01*
G01X1628358Y120299D02*
X1628059Y120000D01*
G01X1628358Y122601D02*
Y120299D01*
G01X1627461Y123498D02*
X1628358Y122601D01*
G01X1626984Y123498D02*
X1627461D01*
G01X1626951Y123465D02*
X1626984Y123498D01*
G01X1625727Y123465D02*
X1626951D01*
G01X1625694Y123498D02*
X1625727Y123465D01*
G01X1623835Y123498D02*
X1625694D01*
G01X1623802Y123465D02*
X1623835Y123498D01*
G01X1622578Y123465D02*
X1623802D01*
G01X1622545Y123498D02*
X1622578Y123465D01*
G01X1620419Y123498D02*
X1622545D01*
G01X1617503Y126414D02*
X1620419Y123498D01*
G01X1617501Y126414D02*
X1617503D01*
G01X1617301Y126614D02*
X1617501Y126414D01*
G01X1616015Y126614D02*
X1617301D01*
G01X1615322Y127307D02*
X1616015Y126614D01*
G01X1615322Y132808D02*
Y127307D01*
G01X1613741Y134389D02*
X1615322Y132808D01*
G01X1611471Y150137D02*
X1610591D01*
G01X1612983Y148625D02*
X1611471Y150137D01*
G01X1635714Y148625D02*
X1612983D01*
G01X1636372Y147967D02*
X1635714Y148625D01*
G01X1649886Y147967D02*
X1636372D01*
G01X1650559Y148640D02*
X1649886Y147967D01*
G01X1648387Y111974D02*
Y112341D01*
G01X1646906Y110493D02*
X1648387Y111974D01*
G01X1646906Y107757D02*
Y110493D01*
G01X1649965Y104698D02*
X1646906Y107757D01*
G01X1676702Y104698D02*
X1649965D01*
G01X1601100Y111376D02*
X1600490Y110766D01*
G01X1601100Y126135D02*
Y111376D01*
G01X1597171Y130064D02*
X1601100Y126135D01*
G01X1597171Y152389D02*
Y130064D01*
G01X1594952Y154608D02*
X1597171Y152389D01*
G01X1594952Y158752D02*
Y154608D01*
G01X1597922Y130376D02*
Y159621D01*
G01X1601948Y126350D02*
X1597922Y130376D01*
G01X1601948Y117834D02*
Y126350D01*
G01X1607441Y112341D02*
X1601948Y117834D01*
G01X1594174Y152994D02*
Y159175D01*
G01X1595390Y151778D02*
X1594174Y152994D01*
G01X1614725Y150137D02*
X1613741D01*
G01X1616263Y151675D02*
X1614725Y150137D01*
G01X1617593Y151675D02*
X1616263D01*
G01X1618486Y152568D02*
X1617593Y151675D01*
G01X1618486Y153838D02*
Y152568D01*
G01X1619449Y154801D02*
X1618486Y153838D01*
G01X1668798Y154801D02*
X1619449D01*
G01X1650275Y100765D02*
X1653723D01*
G01X1643600Y107440D02*
X1650275Y100765D01*
G01X1643600Y113978D02*
Y107440D01*
G01X1642084Y115494D02*
X1643600Y113978D01*
G01X1601659Y152566D02*
Y157092D01*
G01X1601945Y152280D02*
X1601659Y152566D01*
G01X1601945Y146824D02*
Y152280D01*
G01X1601593Y146472D02*
X1601945Y146824D01*
G01X1599852Y146472D02*
X1601593D01*
G01X1599500Y146120D02*
X1599852Y146472D01*
G01X1599500Y145416D02*
Y146120D01*
G01X1599852Y145064D02*
X1599500Y145416D01*
G01X1601593Y145064D02*
X1599852D01*
G01X1601945Y144712D02*
X1601593Y145064D01*
G01X1601945Y141791D02*
Y144712D01*
G01X1599424Y139270D02*
X1601945Y141791D01*
G01X1599424Y131000D02*
Y139270D01*
G01X1603822Y126602D02*
X1599424Y131000D01*
G01X1603822Y123323D02*
Y126602D01*
G01X1606893Y120252D02*
X1603822Y123323D01*
G01X1608979Y120252D02*
X1606893D01*
G01X1610591Y118640D02*
X1608979Y120252D01*
G01X1631999Y168962D02*
X1656462D01*
G01X1631662Y168625D02*
X1631999Y168962D01*
G01X1625206Y168625D02*
X1631662D01*
G01X1623981Y167400D02*
X1625206Y168625D01*
G01X1622400Y167400D02*
X1623981D01*
G01X1621600Y166600D02*
X1622400Y167400D01*
G01X1621600Y164900D02*
Y166600D01*
G01X1621100Y164400D02*
X1621600Y164900D01*
G01X1610169Y164400D02*
X1621100D01*
G01X1609116Y163347D02*
X1610169Y164400D01*
G01X1626618Y159585D02*
X1626339D01*
G01X1628178Y158025D02*
X1626618Y159585D01*
G01X1662972Y158025D02*
X1628178D01*
G01X1589652Y159503D02*
Y156988D01*
G01X1592046Y161897D02*
X1589652Y159503D01*
G01X1594260Y161897D02*
X1592046D01*
G01X1597954Y165591D02*
X1594260Y161897D01*
G01X1597954Y168288D02*
Y165591D01*
G01X1599614Y169948D02*
X1597954Y168288D01*
G01X1602111Y169948D02*
X1599614D01*
G01X1604007Y171844D02*
X1602111Y169948D01*
G01X1604007Y175108D02*
Y171844D01*
G01X1607492Y178593D02*
X1604007Y175108D01*
G01X1610256Y178593D02*
X1607492D01*
G01X1612562Y180899D02*
X1610256Y178593D01*
G01X1615386Y180899D02*
X1612562D01*
G01X1617005Y179280D02*
X1615386Y180899D01*
G01X1619895Y179280D02*
X1617005D01*
G01X1620886Y180271D02*
X1619895Y179280D01*
G01X1629995Y180271D02*
X1620886D01*
G01X1632580Y177686D02*
X1629995Y180271D01*
G01X1637488Y177686D02*
X1632580D01*
G01X1639875Y180073D02*
X1637488Y177686D01*
G01X1644352Y180073D02*
X1639875D01*
G01X1645749Y181470D02*
X1644352Y180073D01*
G01X1645749Y183341D02*
Y181470D01*
G01X1647244Y184836D02*
X1645749Y183341D01*
G01X1647244Y186237D02*
Y184836D01*
G01X1649677Y188670D02*
X1647244Y186237D01*
G01X1651323Y188670D02*
X1649677D01*
G01X1616577Y157860D02*
X1615322Y156605D01*
G01X1623684Y157860D02*
X1616577D01*
G01X1624864Y159040D02*
X1623684Y157860D01*
G01X1624864Y160197D02*
Y159040D01*
G01X1625727Y161060D02*
X1624864Y160197D01*
G01X1625893Y161060D02*
X1625727D01*
G01X1626008Y161175D02*
X1625893Y161060D01*
G01X1631617Y161175D02*
X1626008D01*
G01X1634846Y164404D02*
X1631617Y161175D01*
G01X1646905Y164404D02*
X1634846D01*
G01X1648386Y165885D02*
X1646905Y164404D01*
G01X1609364Y170000D02*
X1598673Y159309D01*
G01X1616500Y170000D02*
X1609364D01*
G01X1618595Y172095D02*
X1616500Y170000D01*
G01X1620997Y172095D02*
X1618595D01*
G01X1621330Y171762D02*
X1620997Y172095D01*
G01X1622553Y171762D02*
X1621330D01*
G01X1623417Y172626D02*
X1622553Y171762D01*
G01X1623417Y173473D02*
Y172626D01*
G01X1624355Y174411D02*
X1623417Y173473D01*
G01X1629133Y174411D02*
X1624355D01*
G01X1630363Y173181D02*
X1629133Y174411D01*
G01X1639051Y173181D02*
X1630363D01*
G01X1641287Y175417D02*
X1639051Y173181D01*
G01X1652480Y175417D02*
X1641287D01*
G01X1609915Y167362D02*
X1605918Y163365D01*
G01X1621163Y167362D02*
X1609915D01*
G01X1623310Y169509D02*
X1621163Y167362D01*
G01X1630858Y169509D02*
X1623310D01*
G01X1630859Y169508D02*
X1630858Y169509D01*
G01X1631481Y169508D02*
X1630859D01*
G01X1631482Y169509D02*
X1631481Y169508D01*
G01X1631483Y169509D02*
X1631482D01*
G01X1631687Y169713D02*
X1631483Y169509D01*
G01X1655941Y169713D02*
X1631687D01*
G01X1650404Y171215D02*
X1659225Y180036D01*
G01X1645056Y171215D02*
X1650404D01*
G01X1643662Y172609D02*
X1645056Y171215D01*
G01X1590404Y159138D02*
Y156509D01*
G01X1592411Y161145D02*
X1590404Y159138D01*
G01X1594571Y161145D02*
X1592411D01*
G01X1598705Y165279D02*
X1594571Y161145D01*
G01X1598705Y167976D02*
Y165279D01*
G01X1599926Y169197D02*
X1598705Y167976D01*
G01X1602423Y169197D02*
X1599926D01*
G01X1604758Y171532D02*
X1602423Y169197D01*
G01X1604758Y174623D02*
Y171532D01*
G01X1607977Y177842D02*
X1604758Y174623D01*
G01X1610568Y177842D02*
X1607977D01*
G01X1612850Y180124D02*
X1610568Y177842D01*
G01X1615074Y180124D02*
X1612850D01*
G01X1616669Y178529D02*
X1615074Y180124D01*
G01X1620207Y178529D02*
X1616669D01*
G01X1621197Y179519D02*
X1620207Y178529D01*
G01X1629684Y179519D02*
X1621197D01*
G01X1630817Y178386D02*
X1629684Y179519D01*
G01X1630817Y178385D02*
Y178386D01*
G01X1632267Y176935D02*
X1630817Y178385D01*
G01X1637800Y176935D02*
X1632267D01*
G01X1640187Y179322D02*
X1637800Y176935D01*
G01X1644665Y179322D02*
X1640187D01*
G01X1646501Y181158D02*
X1644665Y179322D01*
G01X1646501Y183029D02*
Y181158D01*
G01X1648100Y184628D02*
X1646501Y183029D01*
G01X1648100Y186029D02*
Y184628D01*
G01X1649989Y187918D02*
X1648100Y186029D01*
G01X1651635Y187918D02*
X1649989D01*
G01X1603600Y157970D02*
X1602552Y156922D01*
G01X1603600Y162110D02*
Y157970D01*
G01X1609790Y168300D02*
X1603600Y162110D01*
G01X1617099Y168300D02*
X1609790D01*
G01X1619271Y170472D02*
X1617099Y168300D01*
G01X1620494Y170472D02*
X1619271D01*
G01X1620706Y170260D02*
X1620494Y170472D01*
G01X1631170Y170260D02*
X1620706D01*
G01X1631374Y170464D02*
X1631170Y170260D01*
G01X1650764Y170464D02*
X1631374D01*
G01X1613741Y158725D02*
X1612120Y157104D01*
G01X1613741Y159585D02*
Y158725D01*
G01X1649353Y189613D02*
X1651202D01*
G01X1646418Y186678D02*
X1649353Y189613D01*
G01X1646418Y185118D02*
Y186678D01*
G01X1644800Y183500D02*
X1646418Y185118D01*
G01X1643290Y183500D02*
X1644800D01*
G01X1640614Y180824D02*
X1643290Y183500D01*
G01X1639324Y180824D02*
X1640614D01*
G01X1637118Y178618D02*
X1639324Y180824D01*
G01X1633197Y178618D02*
X1637118D01*
G01X1630715Y181100D02*
X1633197Y178618D01*
G01X1620600Y181100D02*
X1630715D01*
G01X1619568Y180068D02*
X1620600Y181100D01*
G01X1617332Y180068D02*
X1619568D01*
G01X1615750Y181650D02*
X1617332Y180068D01*
G01X1612250Y181650D02*
X1615750D01*
G01X1609944Y179344D02*
X1612250Y181650D01*
G01X1606956Y179344D02*
X1609944D01*
G01X1603256Y175644D02*
X1606956Y179344D01*
G01X1603256Y172156D02*
Y175644D01*
G01X1601805Y170705D02*
X1603256Y172156D01*
G01X1599308Y170705D02*
X1601805D01*
G01X1597203Y168600D02*
X1599308Y170705D01*
G01X1597203Y165903D02*
Y168600D01*
G01X1593950Y162650D02*
X1597203Y165903D01*
G01X1590451Y162650D02*
X1593950D01*
G01X1632418Y168211D02*
X1657111D01*
G01X1631934Y167727D02*
X1632418Y168211D01*
G01X1625616Y167727D02*
X1631934D01*
G01X1624800Y166911D02*
X1625616Y167727D01*
G01X1624800Y161600D02*
Y166911D01*
G01X1624321Y161121D02*
X1624800Y161600D01*
G01X1613191Y161121D02*
X1624321D01*
G01X1613131Y161061D02*
X1613191Y161121D01*
G01X1613129Y161061D02*
X1613131D01*
G01X1612265Y160197D02*
X1613129Y161061D01*
G01X1612265Y160195D02*
Y160197D01*
G01X1612067Y159997D02*
X1612265Y160195D01*
G01X1612067Y158544D02*
Y159997D01*
G01X1610591Y157068D02*
X1612067Y158544D01*
G01X1610591Y156436D02*
Y157068D01*
G01X1634844Y167423D02*
X1657423D01*
G01X1631830Y164409D02*
X1634844Y167423D01*
G01X1627814Y164409D02*
X1631830D01*
G01X1626339Y165884D02*
X1627814Y164409D01*
G01X1642348Y162749D02*
X1642101D01*
G01X1643924Y161173D02*
X1642348Y162749D01*
G01X1661665Y161173D02*
X1643924D01*
G01X1596401Y160201D02*
X1594952Y158752D01*
G01X1597436Y160201D02*
X1596401D01*
G01X1605883Y168648D02*
X1597436Y160201D01*
G01X1605886Y168648D02*
X1605883D01*
G01X1607140Y169902D02*
X1605886Y168648D01*
G01X1607140Y169934D02*
Y169902D01*
G01X1607141Y169935D02*
X1607140Y169934D01*
G01X1607141Y170557D02*
Y169935D01*
G01X1607140Y170558D02*
X1607141Y170557D01*
G01X1607140Y173393D02*
Y170558D01*
G01X1608972Y175225D02*
X1607140Y173393D01*
G01X1614426Y175225D02*
X1608972D01*
G01X1615362Y174289D02*
X1614426Y175225D01*
G01X1618371Y174289D02*
X1615362D01*
G01X1619665Y175583D02*
X1618371Y174289D01*
G01X1623141Y175583D02*
X1619665D01*
G01X1623471Y175913D02*
X1623141Y175583D01*
G01X1629902Y175913D02*
X1623471D01*
G01X1631132Y174683D02*
X1629902Y175913D01*
G01X1638427Y174683D02*
X1631132D01*
G01X1640777Y177033D02*
X1638427Y174683D01*
G01X1651970Y177033D02*
X1640777D01*
G01X1641014Y176207D02*
X1652207D01*
G01X1638739Y173932D02*
X1641014Y176207D01*
G01X1630820Y173932D02*
X1638739D01*
G01X1629590Y175162D02*
X1630820Y173932D01*
G01X1623783Y175162D02*
X1629590D01*
G01X1623341Y174720D02*
X1623783Y175162D01*
G01X1620121Y174720D02*
X1623341D01*
G01X1616466Y171065D02*
X1620121Y174720D01*
G01X1609334Y171065D02*
X1616466D01*
G01X1607891Y169622D02*
X1609334Y171065D01*
G01X1607891Y169590D02*
Y169622D01*
G01X1606198Y167897D02*
X1607891Y169590D01*
G01X1606195Y167897D02*
X1606198D01*
G01X1602640Y164342D02*
X1606195Y167897D01*
G01X1602640Y164339D02*
Y164342D01*
G01X1597922Y159621D02*
X1602640Y164339D01*
G01X1648409Y178362D02*
X1652705Y182658D01*
G01X1641043Y178362D02*
X1648409D01*
G01X1638115Y175434D02*
X1641043Y178362D01*
G01X1631444Y175434D02*
X1638115D01*
G01X1629794Y177084D02*
X1631444Y175434D01*
G01X1623579Y177084D02*
X1629794D01*
G01X1622829Y176334D02*
X1623579Y177084D01*
G01X1619353Y176334D02*
X1622829D01*
G01X1618059Y175040D02*
X1619353Y176334D01*
G01X1615674Y175040D02*
X1618059D01*
G01X1614674Y176040D02*
X1615674Y175040D01*
G01X1608723Y176040D02*
X1614674D01*
G01X1606389Y173706D02*
X1608723Y176040D01*
G01X1606389Y170214D02*
Y173706D01*
G01X1605574Y169399D02*
X1606389Y170214D01*
G01X1605571Y169399D02*
X1605574D01*
G01X1597124Y160952D02*
X1605571Y169399D01*
G01X1595951Y160952D02*
X1597124D01*
G01X1594174Y159175D02*
X1595951Y160952D01*
G01X1641313Y174380D02*
X1652506D01*
G01X1639197Y172264D02*
X1641313Y174380D01*
G01X1632110Y172264D02*
X1639197D01*
G01X1630857Y171011D02*
X1632110Y172264D01*
G01X1621018Y171011D02*
X1630857D01*
G01X1620806Y171223D02*
X1621018Y171011D01*
G01X1618823Y171223D02*
X1620806D01*
G01X1616800Y169200D02*
X1618823Y171223D01*
G01X1609627Y169200D02*
X1616800D01*
G01X1602813Y162386D02*
X1609627Y169200D01*
G01X1602813Y158246D02*
Y162386D01*
G01X1601659Y157092D02*
X1602813Y158246D01*
G01X1592125Y237147D02*
X1591865Y237407D01*
G01X1593295Y237147D02*
X1592125D01*
G01X1594242Y236200D02*
X1593295Y237147D01*
G01X1601839Y236200D02*
X1594242D01*
G01X1606849Y241210D02*
X1601839Y236200D01*
G01X1631600Y263318D02*
Y280100D01*
G01X1630474Y262192D02*
X1631600Y263318D01*
G01X1630474Y262063D02*
Y262192D01*
G01X1629299Y260888D02*
X1630474Y262063D01*
G01X1629299Y248874D02*
Y260888D01*
G01X1627311Y246886D02*
X1629299Y248874D01*
G01X1627311Y244611D02*
Y246886D01*
G01X1624798Y242098D02*
X1627311Y244611D01*
G01X1624798Y241937D02*
Y242098D01*
G01X1594167Y362075D02*
Y340788D01*
G01X1631600Y280100D02*
X1631300Y280400D01*
G01X1594919Y340476D02*
Y362387D01*
G01X1592946Y340914D02*
Y361949D01*
G01X1591794Y361471D02*
Y341392D01*
G01X1588788Y391288D02*
Y367454D01*
G01X1590997Y402356D02*
Y393497D01*
G01X1594000Y405359D02*
X1590997Y402356D01*
G01X1591749Y401849D02*
X1595800Y405900D01*
G01X1591749Y393149D02*
Y401849D01*
G01X1589968Y391368D02*
X1591749Y393149D01*
G01X1589968Y367338D02*
Y391368D01*
G01X1594919Y362387D02*
X1589968Y367338D01*
G01X1590000Y393999D02*
Y401602D01*
G01X1592028Y413083D02*
X1590548Y414563D01*
G01X1592028Y412225D02*
Y413083D01*
G01X1593006Y411247D02*
X1592028Y412225D01*
G01X1593006Y406595D02*
Y411247D01*
G01X1590581Y404170D02*
X1593006Y406595D01*
G01X1594000Y411600D02*
Y405359D01*
G01X1592980Y412620D02*
X1594000Y411600D01*
G01X1592980Y413478D02*
Y412620D01*
G01X1591824Y414634D02*
X1592980Y413478D01*
G01X1591824Y432957D02*
Y414634D01*
G01X1590612Y434169D02*
X1591824Y432957D01*
G01X1591076Y412688D02*
X1590153Y413611D01*
G01X1591076Y411796D02*
Y412688D01*
G01X1591430Y411442D02*
X1591076Y411796D01*
G01X1591430Y409440D02*
Y411442D01*
G01X1642931Y531016D02*
X1669519Y504428D01*
G01X1645969Y514613D02*
Y514870D01*
G01X1647325Y513257D02*
X1645969Y514613D01*
G01X1653641Y513257D02*
X1647325D01*
G01X1629778Y513588D02*
Y507294D01*
G01X1628912Y514454D02*
X1629778Y513588D01*
G01X1614198Y514454D02*
X1628912D01*
G01X1608995Y509251D02*
X1614198Y514454D01*
G01X1593369Y509251D02*
X1608995D01*
G01X1640109Y517500D02*
X1642670Y514939D01*
G01X1635629Y517500D02*
X1640109D01*
G01X1630945Y522184D02*
X1635629Y517500D01*
G01X1626031Y522184D02*
X1630945D01*
G01X1625424Y521577D02*
X1626031Y522184D01*
G01X1616001Y521577D02*
X1625424D01*
G01X1609048Y514624D02*
X1616001Y521577D01*
G01X1593323Y514624D02*
X1609048D01*
G01X1649853Y522747D02*
X1669253Y503347D01*
G01X1637757Y522747D02*
X1649853D01*
G01X1635477Y525027D02*
X1637757Y522747D01*
G01X1635477Y528974D02*
Y525027D01*
G01X1606356Y518728D02*
X1617204Y529576D01*
G01X1595027Y518728D02*
X1606356D01*
G01X1625831Y520318D02*
X1627407D01*
G01X1625573Y520576D02*
X1625831Y520318D01*
G01X1616064Y520576D02*
X1625573D01*
G01X1609360Y513872D02*
X1616064Y520576D01*
G01X1593008Y513872D02*
X1609360D01*
G01X1643326Y531968D02*
X1669914Y505380D01*
G01X1643735Y507330D02*
X1654570D01*
G01X1641290Y509775D02*
X1643735Y507330D01*
G01X1634655Y509775D02*
X1641290D01*
G01X1629224Y515206D02*
X1634655Y509775D01*
G01X1613886Y515206D02*
X1629224D01*
G01X1610296Y511616D02*
X1613886Y515206D01*
G01X1592068Y511616D02*
X1610296D01*
G01X1636498Y515958D02*
X1639391Y513065D01*
G01X1613574Y515958D02*
X1636498D01*
G01X1609984Y512368D02*
X1613574Y515958D01*
G01X1592381Y512368D02*
X1609984D01*
G01X1648326Y515215D02*
X1649545D01*
G01X1644841Y518700D02*
X1648326Y515215D01*
G01X1636059Y518700D02*
X1644841D01*
G01X1631423Y523336D02*
X1636059Y518700D01*
G01X1625553Y523336D02*
X1631423D01*
G01X1624946Y522729D02*
X1625553Y523336D01*
G01X1614816Y522729D02*
X1624946D01*
G01X1607863Y515776D02*
X1614816Y522729D01*
G01X1593803Y515776D02*
X1607863D01*
G01X1609672Y513120D02*
X1592694D01*
G01X1613262Y516710D02*
X1609672Y513120D01*
G01X1637975Y516710D02*
X1613262D01*
G01X1646038Y508647D02*
X1637975Y516710D01*
G01X1654317Y508647D02*
X1646038D01*
G01X1634782Y531016D02*
X1642931D01*
G01X1633441Y532357D02*
X1634782Y531016D01*
G01X1624440Y532357D02*
X1633441D01*
G01X1623897Y531814D02*
X1624440Y532357D01*
G01X1612976Y531814D02*
X1623897D01*
G01X1602310Y536414D02*
X1612976Y531814D01*
G01X1594737Y536414D02*
X1602310D01*
G01X1591780Y533457D02*
X1594737Y536414D01*
G01X1645844Y535709D02*
X1656535Y525018D01*
G01X1643974Y535709D02*
X1645844D01*
G01X1643099Y536584D02*
X1643974Y535709D01*
G01X1632434Y536584D02*
X1643099D01*
G01X1631559Y535709D02*
X1632434Y536584D01*
G01X1623468Y535709D02*
X1631559D01*
G01X1622629Y534870D02*
X1623468Y535709D01*
G01X1612600Y534870D02*
X1622629D01*
G01X1602561Y539204D02*
X1612600Y534870D01*
G01X1590359Y539204D02*
X1602561D01*
G01X1588813Y540750D02*
X1590359Y539204D01*
G01X1646239Y536661D02*
X1657487Y525413D01*
G01X1644369Y536661D02*
X1646239D01*
G01X1643494Y537536D02*
X1644369Y536661D01*
G01X1632039Y537536D02*
X1643494D01*
G01X1631164Y536661D02*
X1632039Y537536D01*
G01X1623073Y536661D02*
X1631164D01*
G01X1622234Y535822D02*
X1623073Y536661D01*
G01X1612295Y535822D02*
X1622234D01*
G01X1602426Y540082D02*
X1612295Y535822D01*
G01X1590828Y540082D02*
X1602426D01*
G01X1589208Y541702D02*
X1590828Y540082D01*
G01X1633046Y531405D02*
X1635477Y528974D01*
G01X1624835Y531405D02*
X1633046D01*
G01X1623006Y529576D02*
X1624835Y531405D01*
G01X1617204Y529576D02*
X1623006D01*
G01X1635177Y531968D02*
X1643326D01*
G01X1633836Y533309D02*
X1635177Y531968D01*
G01X1624045Y533309D02*
X1633836D01*
G01X1623502Y532766D02*
X1624045Y533309D01*
G01X1613174Y532766D02*
X1623502D01*
G01X1611121Y533651D02*
X1613174Y532766D01*
G01X1602511Y537366D02*
X1611121Y533651D01*
G01X1594342Y537366D02*
X1602511D01*
G01X1591385Y534409D02*
X1594342Y537366D01*
G01X1645366Y534557D02*
X1654718Y525205D01*
G01X1641429Y534557D02*
X1645366D01*
G01X1640554Y535432D02*
X1641429Y534557D01*
G01X1632912Y535432D02*
X1640554D01*
G01X1632037Y534557D02*
X1632912Y535432D01*
G01X1623946Y534557D02*
X1632037D01*
G01X1623107Y533718D02*
X1623946Y534557D01*
G01X1613371Y533718D02*
X1623107D01*
G01X1602608Y538363D02*
X1613371Y533718D01*
G01X1593992Y538363D02*
X1602608D01*
G01X1590990Y535361D02*
X1593992Y538363D01*
G01X1643029Y604930D02*
X1644856D01*
G01X1641657Y603558D02*
X1643029Y604930D01*
G01X1640185Y603558D02*
X1641657D01*
G01X1638743Y605000D02*
X1640185Y603558D01*
G01X1624009Y605000D02*
X1638743D01*
G01X1621726Y607283D02*
X1624009Y605000D01*
G01X1608325Y607283D02*
X1621726D01*
G01X1604191Y611417D02*
X1608325Y607283D01*
G01X1604191Y616379D02*
Y611417D01*
G01X1605326Y617514D02*
X1604191Y616379D01*
G01X1605326Y618986D02*
Y617514D01*
G01X1604286Y620026D02*
X1605326Y618986D01*
G01X1599466Y620026D02*
X1604286D01*
G01X1598040Y618600D02*
X1599466Y620026D01*
G01X1598040Y606240D02*
Y618600D01*
G01X1590800Y599000D02*
X1598040Y606240D01*
G01X1619229Y619659D02*
X1617600Y619800D01*
G01X1619552Y619930D02*
X1619229Y619659D01*
G01X1619552Y620601D02*
Y619930D01*
G01X1617311Y622842D02*
X1619552Y620601D01*
G01X1639455Y606800D02*
X1640921Y605334D01*
G01X1624400Y606800D02*
X1639455D01*
G01X1617400Y613800D02*
X1624400Y606800D01*
G01X1617400Y617488D02*
Y613800D01*
G01X1613454Y621434D02*
X1617400Y617488D01*
G01X1597642Y621434D02*
X1613454D01*
G01X1596632Y620424D02*
X1597642Y621434D01*
G01X1596632Y606824D02*
Y620424D01*
G01X1590608Y600800D02*
X1596632Y606824D01*
G01X1619842Y618930D02*
X1619700Y617300D01*
G01X1620223Y619250D02*
X1619842Y618930D01*
G01X1620504Y619531D02*
X1620223Y619250D01*
G01X1620504Y620996D02*
Y619531D01*
G01X1617706Y623794D02*
X1620504Y620996D01*
G01X1591767Y617902D02*
X1590881Y618788D01*
G01X1591767Y615717D02*
Y617902D01*
G01X1602752Y617452D02*
X1603550Y618250D01*
G01X1602752Y615101D02*
Y617452D01*
G01X1600402Y612751D02*
X1602752Y615101D01*
G01X1600402Y605255D02*
Y612751D01*
G01X1597450Y602303D02*
X1600402Y605255D01*
G01X1597450Y599550D02*
Y602303D01*
G01X1590748Y592848D02*
X1597450Y599550D01*
G01X1622330Y592450D02*
Y592325D01*
G01X1620908Y593872D02*
X1622330Y592450D01*
G01X1620908Y598945D02*
Y593872D01*
G01X1625041Y603078D02*
X1620908Y598945D01*
G01X1638376Y603078D02*
X1625041D01*
G01X1639304Y602150D02*
X1638376Y603078D01*
G01X1642395Y602150D02*
X1639304D01*
G01X1643051Y602806D02*
X1642395Y602150D01*
G01X1645244Y602806D02*
X1643051D01*
G01X1646632Y604194D02*
X1645244Y602806D01*
G01X1646632Y606668D02*
Y604194D01*
G01X1644630Y608670D02*
X1646632Y606668D01*
G01X1644630Y610881D02*
Y608670D01*
G01X1651115Y617366D02*
X1644630Y610881D01*
G01X1592719Y617936D02*
X1593519Y618736D01*
G01X1592719Y615440D02*
Y617936D01*
G01X1601800Y617400D02*
X1600950Y618250D01*
G01X1601800Y615496D02*
Y617400D01*
G01X1599450Y613146D02*
X1601800Y615496D01*
G01X1599450Y605650D02*
Y613146D01*
G01X1596498Y602698D02*
X1599450Y605650D01*
G01X1596498Y599945D02*
Y602698D01*
G01X1590353Y593800D02*
X1596498Y599945D01*
G01X1672300Y15200D02*
X1670500Y17000D01*
G01X1732501Y15200D02*
X1672300D01*
G01X1680034Y2863D02*
X1668715Y-8456D01*
G01X1678458Y3158D02*
X1667996Y-7304D01*
G01X1678458Y4058D02*
Y3158D01*
G01X1679662Y5262D02*
X1678458Y4058D01*
G01X1754138Y5262D02*
X1679662D01*
G01X1673402Y17856D02*
X1671602Y19656D01*
G01X1733603Y17856D02*
X1673402D01*
G01X1676167Y7166D02*
X1663601Y-5400D01*
G01X1679594Y7166D02*
X1676167D01*
G01X1679595Y7167D02*
X1679594Y7166D01*
G01X1680549Y7167D02*
X1679595D01*
G01X1680550Y7166D02*
X1680549Y7167D01*
G01X1761613Y7166D02*
X1680550D01*
G01X1672778Y16352D02*
X1732979D01*
G01X1670978Y18152D02*
X1672778Y16352D01*
G01X1677869Y8900D02*
X1731200D01*
G01X1677164Y9605D02*
X1677869Y8900D01*
G01X1675692Y9605D02*
X1677164D01*
G01X1669473Y15824D02*
X1675692Y9605D01*
G01X1673090Y17104D02*
X1671290Y18904D01*
G01X1733291Y17104D02*
X1673090D01*
G01X1679314Y6014D02*
X1756541D01*
G01X1677706Y4406D02*
X1679314Y6014D01*
G01X1677706Y3706D02*
Y4406D01*
G01X1667448Y-6552D02*
X1677706Y3706D01*
G01X1671350Y-19000D02*
X1673500Y-16850D01*
G01X1705356Y79487D02*
X1728907D01*
G01X1701979Y82864D02*
X1705356Y79487D01*
G01X1687904Y82864D02*
X1701979D01*
G01X1685444Y85324D02*
X1687904Y82864D01*
G01X1671724Y85324D02*
X1685444D01*
G01X1668000Y81600D02*
X1671724Y85324D01*
G01X1712652Y85343D02*
X1709184Y88811D01*
G01X1650876Y65137D02*
Y65237D01*
G01X1700269Y62125D02*
X1654047D01*
G01X1701010Y61384D02*
X1700269Y62125D01*
G01X1725840Y61384D02*
X1701010D01*
G01X1699825Y58528D02*
X1724655D01*
G01X1699084Y59269D02*
X1699825Y58528D01*
G01X1655232Y59269D02*
X1699084D01*
G01X1691077Y33500D02*
X1733500D01*
G01X1689653Y34924D02*
X1691077Y33500D01*
G01X1662781Y34924D02*
X1689653D01*
G01X1660944Y36761D02*
X1662781Y34924D01*
G01X1680597Y58168D02*
X1655478D01*
G01X1684816Y53949D02*
X1680597Y58168D01*
G01X1719780Y53949D02*
X1684816D01*
G01X1673801Y69114D02*
X1713974D01*
G01X1667264Y75651D02*
X1673801Y69114D01*
G01X1687850Y73950D02*
X1690500D01*
G01X1682841Y78959D02*
X1687850Y73950D01*
G01X1657999Y78959D02*
X1682841D01*
G01X1679556Y54616D02*
X1678627D01*
G01X1686364Y47808D02*
X1679556Y54616D01*
G01X1718392Y47808D02*
X1686364D01*
G01X1686700Y42879D02*
X1758473D01*
G01X1674897Y54682D02*
X1686700Y42879D01*
G01X1656033Y54682D02*
X1674897D01*
G01X1710273Y73204D02*
X1713217Y76148D01*
G01X1703489Y73204D02*
X1710273D01*
G01X1701548Y75145D02*
X1703489Y73204D01*
G01X1692144Y75145D02*
X1701548D01*
G01X1691397Y75892D02*
X1692144Y75145D01*
G01X1687900Y75892D02*
X1691397D01*
G01X1683992Y79800D02*
X1687900Y75892D01*
G01X1659150Y79800D02*
X1683992D01*
G01X1667663Y53337D02*
X1656318D01*
G01X1669500Y51500D02*
X1667663Y53337D01*
G01X1709512Y76092D02*
X1712153Y78733D01*
G01X1705397Y76092D02*
X1709512D01*
G01X1703633Y77856D02*
X1705397Y76092D01*
G01X1701445Y77856D02*
X1703633D01*
G01X1698253Y81048D02*
X1701445Y77856D01*
G01X1688656Y81048D02*
X1698253D01*
G01X1685132Y84572D02*
X1688656Y81048D01*
G01X1675972Y84572D02*
X1685132D01*
G01X1673000Y81600D02*
X1675972Y84572D01*
G01X1659524Y74038D02*
X1659100Y73614D01*
G01X1665877Y74038D02*
X1659524D01*
G01X1667774Y72141D02*
X1665877Y74038D01*
G01X1667774Y69114D02*
Y72141D01*
G01X1669303Y67585D02*
X1667774Y69114D01*
G01X1703821Y67585D02*
X1669303D01*
G01X1704614Y66792D02*
X1703821Y67585D01*
G01X1728083Y66792D02*
X1704614D01*
G01X1707493Y82991D02*
X1730360D01*
G01X1702368Y88116D02*
X1707493Y82991D01*
G01X1689414Y88116D02*
X1702368D01*
G01X1686511Y91019D02*
X1689414Y88116D01*
G01X1679646Y91019D02*
X1686511D01*
G01X1677060Y93605D02*
X1679646Y91019D01*
G01X1671451Y93605D02*
X1677060D01*
G01X1670703Y94353D02*
X1671451Y93605D01*
G01X1666365Y94353D02*
X1670703D01*
G01X1660012Y88000D02*
X1666365Y94353D01*
G01X1659000Y88000D02*
X1660012D01*
G01X1677170Y83270D02*
X1675500Y81600D01*
G01X1682921Y83270D02*
X1677170D01*
G01X1686280Y79911D02*
X1682921Y83270D01*
G01X1688163Y79911D02*
X1686280D01*
G01X1688178Y79896D02*
X1688163Y79911D01*
G01X1697775Y79896D02*
X1688178D01*
G01X1700967Y76704D02*
X1697775Y79896D01*
G01X1703155Y76704D02*
X1700967D01*
G01X1705156Y74703D02*
X1703155Y76704D01*
G01X1709780Y74703D02*
X1705156D01*
G01X1712658Y77581D02*
X1709780Y74703D01*
G01X1679423Y56883D02*
X1655540D01*
G01X1685442Y50864D02*
X1679423Y56883D01*
G01X1728834Y50864D02*
X1685442D01*
G01X1672349Y88651D02*
X1669000Y92000D01*
G01X1684207Y88651D02*
X1672349D01*
G01X1688842Y84016D02*
X1684207Y88651D01*
G01X1703141Y84016D02*
X1688842D01*
G01X1706518Y80639D02*
X1703141Y84016D01*
G01X1729385Y80639D02*
X1706518D01*
G01X1664604Y95104D02*
X1661900Y92400D01*
G01X1680425Y93567D02*
X1679415Y94577D01*
G01X1687290Y93567D02*
X1680425D01*
G01X1690389Y90468D02*
X1687290Y93567D01*
G01X1702459Y90468D02*
X1690389D01*
G01X1704000Y92009D02*
X1702459Y90468D01*
G01X1706089Y92009D02*
X1704000D01*
G01X1707468Y90630D02*
X1706089Y92009D01*
G01X1717802Y90630D02*
X1707468D01*
G01X1687171Y43831D02*
X1758868D01*
G01X1675219Y55783D02*
X1687171Y43831D01*
G01X1655787Y55783D02*
X1675219D01*
G01X1699874Y61173D02*
X1654442D01*
G01X1700615Y60432D02*
X1699874Y61173D01*
G01X1725445Y60432D02*
X1700615D01*
G01X1703114Y66040D02*
X1727771D01*
G01X1702373Y66781D02*
X1703114Y66040D01*
G01X1668331Y66781D02*
X1702373D01*
G01X1665926Y69186D02*
X1668331Y66781D01*
G01X1665926Y70615D02*
Y69186D01*
G01X1664350Y72191D02*
X1665926Y70615D01*
G01X1664350Y72462D02*
Y72191D01*
G01X1708443Y92982D02*
X1719763D01*
G01X1707064Y94361D02*
X1708443Y92982D01*
G01X1702979Y94361D02*
X1707064D01*
G01X1701438Y92820D02*
X1702979Y94361D01*
G01X1691364Y92820D02*
X1701438D01*
G01X1687182Y97002D02*
X1691364Y92820D01*
G01X1700664Y63077D02*
X1653652D01*
G01X1701405Y62336D02*
X1700664Y63077D01*
G01X1726235Y62336D02*
X1701405D01*
G01X1700220Y59480D02*
X1725050D01*
G01X1699479Y60221D02*
X1700220Y59480D01*
G01X1654837Y60221D02*
X1699479D01*
G01X1664350Y68378D02*
Y69962D01*
G01X1666699Y66029D02*
X1664350Y68378D01*
G01X1702061Y66029D02*
X1666699D01*
G01X1702802Y65288D02*
X1702061Y66029D01*
G01X1727459Y65288D02*
X1702802D01*
G01X1666828Y153163D02*
X1665290Y151625D01*
G01X1670065Y153163D02*
X1666828D01*
G01X1674195Y157293D02*
X1670065Y153163D01*
G01X1707721Y148931D02*
X1712444Y153654D01*
G01X1693915Y148931D02*
X1707721D01*
G01X1692035Y150811D02*
X1693915Y148931D01*
G01X1682174Y150811D02*
X1692035D01*
G01X1670464Y139101D02*
X1682174Y150811D01*
G01X1697800Y95386D02*
Y94612D01*
G01X1682561Y110625D02*
X1697800Y95386D01*
G01X1671330Y110625D02*
X1682561D01*
G01X1667284Y114671D02*
X1671330Y110625D01*
G01X1667284Y115491D02*
Y114671D01*
G01X1708490Y146980D02*
X1713248Y151738D01*
G01X1708490Y140588D02*
Y146980D01*
G01X1695792Y127890D02*
X1708490Y140588D01*
G01X1693444Y127890D02*
X1695792D01*
G01X1680741Y115187D02*
X1693444Y127890D01*
G01X1676735Y115187D02*
X1680741D01*
G01X1674778Y117144D02*
X1676735Y115187D01*
G01X1666492Y117144D02*
X1674778D01*
G01X1664839Y115491D02*
X1666492Y117144D01*
G01X1664135Y115491D02*
X1664839D01*
G01X1672882Y101182D02*
X1674800Y103100D01*
G01X1667164Y101182D02*
X1672882D01*
G01X1664504Y103842D02*
X1667164Y101182D01*
G01X1680232Y153853D02*
X1671856Y145477D01*
G01X1693410Y153853D02*
X1680232D01*
G01X1694802Y155245D02*
X1693410Y153853D01*
G01X1710790Y155245D02*
X1694802D01*
G01X1711126Y155581D02*
X1710790Y155245D01*
G01X1747912Y155581D02*
X1711126D01*
G01X1711736Y154629D02*
X1712685D01*
G01X1707414Y150307D02*
X1711736Y154629D01*
G01X1695933Y150307D02*
X1707414D01*
G01X1693625Y152615D02*
X1695933Y150307D01*
G01X1681685Y152615D02*
X1693625D01*
G01X1671412Y142342D02*
X1681685Y152615D01*
G01X1678449Y95104D02*
X1664604D01*
G01X1678976Y94577D02*
X1678449Y95104D01*
G01X1679415Y94577D02*
X1678976D01*
G01X1673094Y148640D02*
X1650559D01*
G01X1679423Y154969D02*
X1673094Y148640D01*
G01X1679718Y154969D02*
X1679423D01*
G01X1679754Y155005D02*
X1679718Y154969D01*
G01X1692932Y155005D02*
X1679754D01*
G01X1694324Y156397D02*
X1692932Y155005D01*
G01X1678400Y103000D02*
X1676702Y104698D01*
G01X1661898Y97002D02*
X1687182D01*
G01X1660400Y98500D02*
X1661898Y97002D01*
G01X1672119Y158122D02*
X1668798Y154801D01*
G01X1678896Y100316D02*
X1680139Y99073D01*
G01X1665616Y100316D02*
X1678896D01*
G01X1664475Y101457D02*
X1665616Y100316D01*
G01X1654415Y101457D02*
X1664475D01*
G01X1653723Y100765D02*
X1654415Y101457D01*
G01X1657835Y112431D02*
Y112341D01*
G01X1659275Y113871D02*
X1657835Y112431D01*
G01X1661722Y113871D02*
X1659275D01*
G01X1662639Y112954D02*
X1661722Y113871D01*
G01X1662639Y110715D02*
Y112954D01*
G01X1663818Y109536D02*
X1662639Y110715D01*
G01X1682447Y109536D02*
X1663818D01*
G01X1692285Y99698D02*
X1682447Y109536D01*
G01X1692285Y94612D02*
Y99698D01*
G01X1671302Y114623D02*
X1670434Y115491D01*
G01X1674937Y114623D02*
X1671302D01*
G01X1675901Y113659D02*
X1674937Y114623D01*
G01X1680741Y113659D02*
X1675901D01*
G01X1693892Y126810D02*
X1680741Y113659D01*
G01X1696240Y126810D02*
X1693892D01*
G01X1709570Y140140D02*
X1696240Y126810D01*
G01X1709570Y146624D02*
Y140140D01*
G01X1713604Y150658D02*
X1709570Y146624D01*
G01X1660985Y119586D02*
Y118640D01*
G01X1662460Y121061D02*
X1660985Y119586D01*
G01X1662460Y122315D02*
Y121061D01*
G01X1663617Y123472D02*
X1662460Y122315D01*
G01X1670497Y123472D02*
X1663617D01*
G01X1672882Y125857D02*
X1670497Y123472D01*
G01X1689844Y125857D02*
X1672882D01*
G01X1692693Y128706D02*
X1689844Y125857D01*
G01X1695454Y128706D02*
X1692693D01*
G01X1707674Y140926D02*
X1695454Y128706D01*
G01X1707674Y147356D02*
Y140926D01*
G01X1712872Y152554D02*
X1707674Y147356D01*
G01X1683228Y203881D02*
Y228091D01*
G01X1678500Y199153D02*
X1683228Y203881D01*
G01X1678500Y195964D02*
Y199153D01*
G01X1673981Y191445D02*
X1678500Y195964D01*
G01X1673981Y190495D02*
Y191445D01*
G01X1667361Y183875D02*
X1673981Y190495D01*
G01X1666487Y183875D02*
X1667361D01*
G01X1665432Y182820D02*
X1666487Y183875D01*
G01X1665432Y181360D02*
Y182820D01*
G01X1665720Y181072D02*
X1665432Y181360D01*
G01X1665720Y181071D02*
Y181072D01*
G01X1666289Y180502D02*
X1665720Y181071D01*
G01X1666289Y178789D02*
Y180502D01*
G01X1656462Y168962D02*
X1666289Y178789D01*
G01X1671525Y213062D02*
Y237005D01*
G01X1660440Y201977D02*
X1671525Y213062D01*
G01X1660440Y200789D02*
Y201977D01*
G01X1709783Y157293D02*
X1674195D01*
G01X1710241Y157751D02*
X1709783Y157293D01*
G01X1748695Y157751D02*
X1710241D01*
G01X1664221Y159274D02*
X1662972Y158025D01*
G01X1709013Y159274D02*
X1664221D01*
G01X1712963Y163224D02*
X1709013Y159274D01*
G01X1653964Y191311D02*
X1651323Y188670D01*
G01X1653964Y199417D02*
Y191311D01*
G01X1665373Y210826D02*
X1653964Y199417D01*
G01X1665373Y217213D02*
Y210826D01*
G01X1670021Y221861D02*
X1665373Y217213D01*
G01X1679721Y213826D02*
Y236187D01*
G01X1680781Y212766D02*
X1679721Y213826D01*
G01X1680781Y211730D02*
Y212766D01*
G01X1680780Y211729D02*
X1680781Y211730D01*
G01X1680780Y204587D02*
Y211729D01*
G01X1675687Y199494D02*
X1680780Y204587D01*
G01X1672894Y199494D02*
X1675687D01*
G01X1671237Y197837D02*
X1672894Y199494D01*
G01X1671237Y196801D02*
Y197837D01*
G01X1671238Y196800D02*
X1671237Y196801D01*
G01X1671238Y195494D02*
Y196800D01*
G01X1671425Y195307D02*
X1671238Y195494D01*
G01X1671425Y192225D02*
Y195307D01*
G01X1666586Y187386D02*
X1671425Y192225D01*
G01X1666586Y186678D02*
Y187386D01*
G01X1663400Y183492D02*
X1666586Y186678D01*
G01X1663400Y179475D02*
Y183492D01*
G01X1657722Y180659D02*
X1652480Y175417D01*
G01X1657722Y180921D02*
Y180659D01*
G01X1657723Y180922D02*
X1657722Y180921D01*
G01X1657723Y183032D02*
Y180922D01*
G01X1657722Y183033D02*
X1657723Y183032D01*
G01X1657722Y184508D02*
Y183033D01*
G01X1659903Y186689D02*
X1657722Y184508D01*
G01X1659903Y187823D02*
Y186689D01*
G01X1665897Y193817D02*
X1659903Y187823D01*
G01X1665897Y197747D02*
Y193817D01*
G01X1668053Y199903D02*
X1665897Y197747D01*
G01X1668053Y201899D02*
Y199903D01*
G01X1676156Y210002D02*
X1668053Y201899D01*
G01X1676156Y237878D02*
Y210002D01*
G01X1665202Y178974D02*
X1655941Y169713D01*
G01X1665202Y180245D02*
Y178974D01*
G01X1664681Y180766D02*
X1665202Y180245D01*
G01X1664681Y183710D02*
Y180766D01*
G01X1672677Y191706D02*
X1664681Y183710D01*
G01X1672677Y195826D02*
Y191706D01*
G01X1672490Y196013D02*
X1672677Y195826D01*
G01X1672490Y197319D02*
Y196013D01*
G01X1673413Y198242D02*
X1672490Y197319D01*
G01X1676206Y198242D02*
X1673413D01*
G01X1682476Y204512D02*
X1676206Y198242D01*
G01X1682476Y228403D02*
Y204512D01*
G01X1678460Y213316D02*
Y236922D01*
G01X1679528Y212248D02*
X1678460Y213316D01*
G01X1679528Y205106D02*
Y212248D01*
G01X1677578Y203156D02*
X1679528Y205106D01*
G01X1672570Y203156D02*
X1677578D01*
G01X1671125Y201711D02*
X1672570Y203156D01*
G01X1671125Y199496D02*
Y201711D01*
G01X1669986Y198357D02*
X1671125Y199496D01*
G01X1669986Y198345D02*
Y198357D01*
G01X1668201Y196560D02*
X1669986Y198345D01*
G01X1668201Y194591D02*
Y196560D01*
G01X1668202Y194590D02*
X1668201Y194591D01*
G01X1668202Y193636D02*
Y194590D01*
G01X1668201Y193635D02*
X1668202Y193636D01*
G01X1668201Y192294D02*
Y193635D01*
G01X1661622Y185715D02*
X1668201Y192294D01*
G01X1661055Y185715D02*
X1661622D01*
G01X1659225Y183885D02*
X1661055Y185715D01*
G01X1659225Y180036D02*
Y183885D01*
G01X1654971Y191254D02*
X1651635Y187918D01*
G01X1654971Y198272D02*
Y191254D01*
G01X1670773Y214074D02*
X1654971Y198272D01*
G01X1670773Y237317D02*
Y214074D01*
G01X1660800Y180500D02*
X1650764Y170464D01*
G01X1660800Y181900D02*
Y180500D01*
G01X1687570Y198913D02*
X1715200Y226543D01*
G01X1687570Y197236D02*
Y198913D01*
G01X1681891Y191557D02*
X1687570Y197236D01*
G01X1680612Y191557D02*
X1681891D01*
G01X1677989Y188934D02*
X1680612Y191557D01*
G01X1677989Y182347D02*
Y188934D01*
G01X1677990Y182346D02*
X1677989Y182347D01*
G01X1677990Y181724D02*
Y182346D01*
G01X1673967Y177701D02*
X1677990Y181724D01*
G01X1672313Y177701D02*
X1673967D01*
G01X1671605Y176993D02*
X1672313Y177701D01*
G01X1671605Y173355D02*
Y176993D01*
G01X1660985Y162735D02*
X1671605Y173355D01*
G01X1661400Y214592D02*
X1669269Y222461D01*
G01X1661400Y208199D02*
Y214592D01*
G01X1653212Y200011D02*
X1661400Y208199D01*
G01X1653212Y191623D02*
Y200011D01*
G01X1651202Y189613D02*
X1653212Y191623D01*
G01X1671688Y182788D02*
Y182925D01*
G01X1657111Y168211D02*
X1671688Y182788D01*
G01X1685566Y199744D02*
X1711958Y226136D01*
G01X1685566Y198067D02*
Y199744D01*
G01X1681258Y193759D02*
X1685566Y198067D01*
G01X1679979Y193759D02*
X1681258D01*
G01X1675985Y189765D02*
X1679979Y193759D01*
G01X1675985Y186349D02*
Y189765D01*
G01X1676487Y185847D02*
X1675985Y186349D01*
G01X1676487Y182347D02*
Y185847D01*
G01X1673529Y179389D02*
X1676487Y182347D01*
G01X1669389Y179389D02*
X1673529D01*
G01X1657423Y167423D02*
X1669389Y179389D01*
G01X1686818Y199225D02*
X1714447Y226854D01*
G01X1686818Y197548D02*
Y199225D01*
G01X1681717Y192447D02*
X1686818Y197548D01*
G01X1680438Y192447D02*
X1681717D01*
G01X1677237Y189246D02*
X1680438Y192447D01*
G01X1677237Y186556D02*
Y189246D01*
G01X1677238Y186555D02*
X1677237Y186556D01*
G01X1677238Y182035D02*
Y186555D01*
G01X1673807Y178604D02*
X1677238Y182035D01*
G01X1672122Y178604D02*
X1673807D01*
G01X1666738Y173220D02*
X1672122Y178604D01*
G01X1666738Y171638D02*
Y173220D01*
G01X1660985Y165885D02*
X1666738Y171638D01*
G01X1664980Y164488D02*
X1661665Y161173D01*
G01X1664980Y165667D02*
Y164488D01*
G01X1673606Y174293D02*
X1664980Y165667D01*
G01X1675172Y174293D02*
X1673606D01*
G01X1678741Y177862D02*
X1675172Y174293D01*
G01X1678741Y182658D02*
Y177862D01*
G01X1678740Y182659D02*
X1678741Y182658D01*
G01X1678740Y186555D02*
Y182659D01*
G01X1678741Y186556D02*
X1678740Y186555D01*
G01X1678741Y187502D02*
Y186556D01*
G01X1680571Y189332D02*
X1678741Y187502D01*
G01X1686710Y189332D02*
X1680571D01*
G01X1688722Y191344D02*
X1686710Y189332D01*
G01X1688722Y198435D02*
Y191344D01*
G01X1716353Y226066D02*
X1688722Y198435D01*
G01X1710262Y156397D02*
X1694324D01*
G01X1710654Y156789D02*
X1710262Y156397D01*
G01X1748593Y156789D02*
X1710654D01*
G01X1709900Y188303D02*
Y187300D01*
G01X1712962Y191365D02*
X1709900Y188303D01*
G01X1653456Y178519D02*
X1651970Y177033D01*
G01X1653456Y185415D02*
Y178519D01*
G01X1660841Y192800D02*
X1653456Y185415D01*
G01X1660841Y195385D02*
Y192800D01*
G01X1666149Y200693D02*
X1660841Y195385D01*
G01X1666149Y206622D02*
Y200693D01*
G01X1672373Y212846D02*
X1666149Y206622D01*
G01X1672373Y236789D02*
Y212846D01*
G01X1674733Y183179D02*
X1674912Y183000D01*
G01X1674733Y191133D02*
Y183179D01*
G01X1679252Y195652D02*
X1674733Y191133D01*
G01X1679252Y198841D02*
Y195652D01*
G01X1683980Y203569D02*
X1679252Y198841D01*
G01X1683980Y210181D02*
Y203569D01*
G01X1687550Y213751D02*
X1683980Y210181D01*
G01X1673184Y212593D02*
Y236536D01*
G01X1666901Y206310D02*
X1673184Y212593D01*
G01X1666901Y200381D02*
Y206310D01*
G01X1661593Y195073D02*
X1666901Y200381D01*
G01X1661593Y191143D02*
Y195073D01*
G01X1658751Y188301D02*
X1661593Y191143D01*
G01X1658751Y186600D02*
Y188301D01*
G01X1656971Y184820D02*
X1658751Y186600D01*
G01X1656971Y182721D02*
Y184820D01*
G01X1656972Y182720D02*
X1656971Y182721D01*
G01X1656972Y181234D02*
Y182720D01*
G01X1656971Y181233D02*
X1656972Y181234D01*
G01X1656971Y180971D02*
Y181233D01*
G01X1652207Y176207D02*
X1656971Y180971D01*
G01X1689943Y207617D02*
Y242793D01*
G01X1682930Y200604D02*
X1689943Y207617D01*
G01X1682803Y200604D02*
X1682930D01*
G01X1681880Y199681D02*
X1682803Y200604D01*
G01X1681880Y199554D02*
Y199681D01*
G01X1681352Y199026D02*
X1681880Y199554D01*
G01X1681352Y196092D02*
Y199026D01*
G01X1664304Y201077D02*
X1664390Y201163D01*
G01X1664304Y200697D02*
Y201077D01*
G01X1659810Y196203D02*
X1664304Y200697D01*
G01X1659810Y192833D02*
Y196203D01*
G01X1653820Y186843D02*
X1659810Y192833D01*
G01X1653820Y186842D02*
Y186843D01*
G01X1652705Y185727D02*
X1653820Y186842D01*
G01X1652705Y182658D02*
Y185727D01*
G01X1709491Y158122D02*
X1672119D01*
G01X1713554Y162185D02*
X1709491Y158122D01*
G01X1705666Y212166D02*
Y198055D01*
G01X1719080Y225580D02*
X1705666Y212166D01*
G01X1677308Y209524D02*
Y237400D01*
G01X1669973Y202189D02*
X1677308Y209524D01*
G01X1669973Y200193D02*
Y202189D01*
G01X1667049Y197269D02*
X1669973Y200193D01*
G01X1667049Y192772D02*
Y197269D01*
G01X1658474Y184197D02*
X1667049Y192772D01*
G01X1658474Y180348D02*
Y184197D01*
G01X1652506Y174380D02*
X1658474Y180348D01*
G01X1682880Y241497D02*
X1683729Y242346D01*
G01X1682880Y240143D02*
Y241497D01*
G01X1686750Y236273D02*
X1682880Y240143D01*
G01X1686750Y231613D02*
Y236273D01*
G01X1683228Y228091D02*
X1686750Y231613D01*
G01X1671616Y266543D02*
Y305055D01*
G01X1677961Y260198D02*
X1671616Y266543D01*
G01X1677961Y251305D02*
Y260198D01*
G01X1674232Y247576D02*
X1677961Y251305D01*
G01X1674232Y239712D02*
Y247576D01*
G01X1671525Y237005D02*
X1674232Y239712D01*
G01X1670021Y237629D02*
Y221861D01*
G01X1672728Y240336D02*
X1670021Y237629D01*
G01X1672728Y248534D02*
Y240336D01*
G01X1676457Y252263D02*
X1672728Y248534D01*
G01X1676457Y259574D02*
Y252263D01*
G01X1670112Y265919D02*
X1676457Y259574D01*
G01X1670112Y304431D02*
Y265919D01*
G01X1689809Y254802D02*
X1835640D01*
G01X1676176Y268435D02*
X1689809Y254802D01*
G01X1676176Y305776D02*
Y268435D01*
G01X1681116Y237582D02*
Y238614D01*
G01X1679721Y236187D02*
X1681116Y237582D01*
G01X1676888Y238610D02*
X1676156Y237878D01*
G01X1676888Y246474D02*
Y238610D01*
G01X1680618Y250204D02*
X1676888Y246474D01*
G01X1680618Y261299D02*
Y250204D01*
G01X1674272Y267645D02*
X1680618Y261299D01*
G01X1674272Y306566D02*
Y267645D01*
G01X1685998Y231925D02*
X1682476Y228403D01*
G01X1685998Y235961D02*
Y231925D01*
G01X1682128Y239831D02*
X1685998Y235961D01*
G01X1682128Y241246D02*
Y239831D01*
G01X1680769Y242605D02*
X1682128Y241246D01*
G01X1683615Y249941D02*
Y250493D01*
G01X1679192Y245518D02*
X1683615Y249941D01*
G01X1679192Y237654D02*
Y245518D01*
G01X1678460Y236922D02*
X1679192Y237654D01*
G01X1673480Y240024D02*
X1670773Y237317D01*
G01X1673480Y248222D02*
Y240024D01*
G01X1677209Y251951D02*
X1673480Y248222D01*
G01X1677209Y259886D02*
Y251951D01*
G01X1670864Y266231D02*
X1677209Y259886D01*
G01X1670864Y304743D02*
Y266231D01*
G01X1677428Y270216D02*
Y305257D01*
G01X1677848Y269796D02*
X1677428Y270216D01*
G01X1677848Y269005D02*
Y269796D01*
G01X1684284Y262569D02*
X1677848Y269005D01*
G01X1829644Y262569D02*
X1684284D01*
G01X1669359Y265608D02*
Y310812D01*
G01X1675705Y259262D02*
X1669359Y265608D01*
G01X1675705Y252575D02*
Y259262D01*
G01X1671976Y248846D02*
X1675705Y252575D01*
G01X1671976Y240648D02*
Y248846D01*
G01X1669268Y237940D02*
X1671976Y240648D01*
G01X1669268Y236070D02*
Y237940D01*
G01X1669269Y236069D02*
X1669268Y236070D01*
G01X1669269Y222461D02*
Y236069D01*
G01X1711958Y249921D02*
X1714016Y251979D01*
G01X1711958Y226136D02*
Y249921D01*
G01X1679100Y269524D02*
Y271300D01*
G01X1684803Y263821D02*
X1679100Y269524D01*
G01X1830743Y263821D02*
X1684803D01*
G01X1674984Y239400D02*
X1672373Y236789D01*
G01X1674984Y247264D02*
Y239400D01*
G01X1678714Y250994D02*
X1674984Y247264D01*
G01X1678714Y256137D02*
Y250994D01*
G01X1678713Y256138D02*
X1678714Y256137D01*
G01X1678713Y260510D02*
Y256138D01*
G01X1672368Y266855D02*
X1678713Y260510D01*
G01X1672368Y305367D02*
Y266855D01*
G01X1673120Y267167D02*
Y305679D01*
G01X1679465Y260822D02*
X1673120Y267167D01*
G01X1679465Y256450D02*
Y260822D01*
G01X1679466Y256449D02*
X1679465Y256450D01*
G01X1679466Y250682D02*
Y256449D01*
G01X1675736Y246952D02*
X1679466Y250682D01*
G01X1675736Y239088D02*
Y246952D01*
G01X1673184Y236536D02*
X1675736Y239088D01*
G01X1683760Y247500D02*
X1681760Y245500D01*
G01X1685236Y247500D02*
X1683760D01*
G01X1689943Y242793D02*
X1685236Y247500D01*
G01X1675424Y268123D02*
Y306088D01*
G01X1681770Y261777D02*
X1675424Y268123D01*
G01X1681770Y249726D02*
Y261777D01*
G01X1678040Y245996D02*
X1681770Y249726D01*
G01X1678040Y238132D02*
Y245996D01*
G01X1677308Y237400D02*
X1678040Y238132D01*
G01X1674141Y313328D02*
Y433649D01*
G01X1671616Y310803D02*
X1674141Y313328D01*
G01X1671616Y309877D02*
Y310803D01*
G01X1671615Y309876D02*
X1671616Y309877D01*
G01X1671615Y305056D02*
Y309876D01*
G01X1671616Y305055D02*
X1671615Y305056D01*
G01X1670111Y304432D02*
X1670112Y304431D01*
G01X1670111Y310500D02*
Y304432D01*
G01X1670112Y310501D02*
X1670111Y310500D01*
G01X1670112Y311427D02*
Y310501D01*
G01X1672637Y313952D02*
X1670112Y311427D01*
G01X1672637Y434273D02*
Y313952D01*
G01X1678701Y308301D02*
X1676176Y305776D01*
G01X1678701Y431757D02*
Y308301D01*
G01X1676797Y309091D02*
X1674272Y306566D01*
G01X1676797Y432547D02*
Y309091D01*
G01X1670863Y304744D02*
X1670864Y304743D01*
G01X1670863Y310188D02*
Y304744D01*
G01X1670864Y310189D02*
X1670863Y310188D01*
G01X1670864Y311115D02*
Y310189D01*
G01X1673389Y313640D02*
X1670864Y311115D01*
G01X1673389Y433961D02*
Y313640D01*
G01X1679953Y307782D02*
Y431238D01*
G01X1677428Y305257D02*
X1679953Y307782D01*
G01X1671885Y314264D02*
Y438802D01*
G01X1669360Y311739D02*
X1671885Y314264D01*
G01X1669360Y310813D02*
Y311739D01*
G01X1669359Y310812D02*
X1669360Y310813D01*
G01X1672367Y305368D02*
X1672368Y305367D01*
G01X1672367Y309564D02*
Y305368D01*
G01X1672368Y309565D02*
X1672367Y309564D01*
G01X1672368Y310491D02*
Y309565D01*
G01X1674893Y313016D02*
X1672368Y310491D01*
G01X1674893Y433337D02*
Y313016D01*
G01X1675645Y312704D02*
Y433025D01*
G01X1673120Y310179D02*
X1675645Y312704D01*
G01X1673120Y309253D02*
Y310179D01*
G01X1673119Y309252D02*
X1673120Y309253D01*
G01X1673119Y305680D02*
Y309252D01*
G01X1673120Y305679D02*
X1673119Y305680D01*
G01X1677949Y308613D02*
Y432069D01*
G01X1675424Y306088D02*
X1677949Y308613D01*
G01X1711546Y447002D02*
X1729398D01*
G01X1705261Y440717D02*
X1711546Y447002D01*
G01X1681209Y440717D02*
X1705261D01*
G01X1674141Y433649D02*
X1681209Y440717D01*
G01X1689448Y451084D02*
X1672637Y434273D01*
G01X1689448Y461228D02*
Y451084D01*
G01X1695295Y467075D02*
X1689448Y461228D01*
G01X1716859Y454205D02*
X1703989Y467075D01*
G01X1683101Y436157D02*
X1678701Y431757D01*
G01X1727592Y436157D02*
X1683101D01*
G01X1682311Y438061D02*
X1676797Y432547D01*
G01X1712098Y438061D02*
X1682311D01*
G01X1718587Y444550D02*
X1712098Y438061D01*
G01X1690200Y450772D02*
X1673389Y433961D01*
G01X1690200Y460916D02*
Y450772D01*
G01X1695607Y466323D02*
X1690200Y460916D01*
G01X1722246Y447754D02*
X1703677Y466323D01*
G01X1683620Y434905D02*
X1868732D01*
G01X1679953Y431238D02*
X1683620Y434905D01*
G01X1704572Y467827D02*
X1717442Y454957D01*
G01X1688408Y461492D02*
X1694743Y467827D01*
G01X1688408Y451808D02*
Y461492D01*
G01X1682404Y445804D02*
X1688408Y451808D01*
G01X1678887Y445804D02*
X1682404D01*
G01X1671885Y438802D02*
X1678887Y445804D01*
G01X1681521Y439965D02*
X1674893Y433337D01*
G01X1705573Y439965D02*
X1681521D01*
G01X1711858Y446250D02*
X1705573Y439965D01*
G01X1720261Y446250D02*
X1711858D01*
G01X1710700Y439213D02*
X1716037Y444550D01*
G01X1681833Y439213D02*
X1710700D01*
G01X1675645Y433025D02*
X1681833Y439213D01*
G01X1682789Y436909D02*
X1716978D01*
G01X1677949Y432069D02*
X1682789Y436909D01*
G01X1678001Y473701D02*
Y473205D01*
G01X1679406Y475106D02*
X1678001Y473701D01*
G01X1681218Y475106D02*
X1679406D01*
G01X1683169Y473155D02*
X1681218Y475106D01*
G01X1710563Y473155D02*
X1683169D01*
G01X1721739Y461979D02*
X1710563Y473155D01*
G01X1679091Y492409D02*
X1687500Y484000D01*
G01X1679091Y499797D02*
Y492409D01*
G01X1678192Y500696D02*
X1679091Y499797D01*
G01X1678154Y500696D02*
X1678192D01*
G01X1674422Y504428D02*
X1678154Y500696D01*
G01X1669519Y504428D02*
X1674422D01*
G01X1685924Y503624D02*
X1687500Y505200D01*
G01X1679653Y503624D02*
X1685924D01*
G01X1675746Y507531D02*
X1679653Y503624D01*
G01X1670891Y507531D02*
X1675746D01*
G01X1656535Y521887D02*
X1670891Y507531D01*
G01X1656535Y525018D02*
Y521887D01*
G01X1703989Y467075D02*
X1695295D01*
G01X1671297Y495601D02*
X1653641Y513257D01*
G01X1671489Y495601D02*
X1671297D01*
G01X1671506Y495618D02*
X1671489Y495601D01*
G01X1672812Y495618D02*
X1671506D01*
G01X1672829Y495601D02*
X1672812Y495618D01*
G01X1673016Y495601D02*
X1672829D01*
G01X1674395Y494222D02*
X1673016Y495601D01*
G01X1674395Y482678D02*
Y494222D01*
G01X1675570Y481503D02*
X1674395Y482678D01*
G01X1678635Y481503D02*
X1675570D01*
G01X1679132Y482000D02*
X1678635Y481503D01*
G01X1681500Y482000D02*
X1679132D01*
G01X1684026Y504576D02*
X1684650Y505200D01*
G01X1680048Y504576D02*
X1684026D01*
G01X1676141Y508483D02*
X1680048Y504576D01*
G01X1671286Y508483D02*
X1676141D01*
G01X1657487Y522282D02*
X1671286Y508483D01*
G01X1657487Y525413D02*
Y522282D01*
G01X1703677Y466323D02*
X1695607D01*
G01X1701335Y482424D02*
X1701617Y482706D01*
G01X1686847Y482424D02*
X1701335D01*
G01X1678139Y491132D02*
X1686847Y482424D01*
G01X1678139Y499402D02*
Y491132D01*
G01X1677797Y499744D02*
X1678139Y499402D01*
G01X1677759Y499744D02*
X1677797D01*
G01X1674156Y503347D02*
X1677759Y499744D01*
G01X1669253Y503347D02*
X1674156D01*
G01X1694743Y467827D02*
X1704572D01*
G01X1687443Y492792D02*
Y487203D01*
G01X1678587Y501648D02*
X1687443Y492792D01*
G01X1678549Y501648D02*
X1678587D01*
G01X1674817Y505380D02*
X1678549Y501648D01*
G01X1669914Y505380D02*
X1674817D01*
G01X1688696Y502600D02*
X1690091Y503995D01*
G01X1678944Y502600D02*
X1688696D01*
G01X1675212Y506332D02*
X1678944Y502600D01*
G01X1670309Y506332D02*
X1675212D01*
G01X1654718Y521923D02*
X1670309Y506332D01*
G01X1654718Y525205D02*
Y521923D01*
G01X1654570Y507330D02*
X1671050Y490850D01*
G01X1670538Y492426D02*
X1654317Y508647D01*
G01X1671703Y492426D02*
X1670538D01*
G01X1672800Y491329D02*
X1671703Y492426D01*
G01X1672800Y488750D02*
Y491329D01*
G01X1671050Y487000D02*
X1672800Y488750D01*
G01X1652804Y483804D02*
X1651867Y484741D01*
G01X1654143Y483804D02*
X1652804D01*
G01X1667097Y470852D02*
X1654143Y483804D01*
G01X1667534Y470415D02*
X1667097Y470852D01*
G01X1708472Y470415D02*
X1667534D01*
G01X1720135Y458752D02*
X1708472Y470415D01*
G01X1681961Y471864D02*
X1680500Y473325D01*
G01X1710224Y471864D02*
X1681961D01*
G01X1721261Y460827D02*
X1710224Y471864D01*
G01X1652581Y482852D02*
X1651926Y482197D01*
G01X1653748Y482852D02*
X1652581D01*
G01X1666980Y469620D02*
X1653748Y482852D01*
G01X1707920Y469620D02*
X1666980D01*
G01X1719740Y457800D02*
X1707920Y469620D01*
G01X1660743Y617366D02*
X1651115D01*
G01X1671609Y606500D02*
X1660743Y617366D01*
G01X1718444Y606500D02*
X1671609D01*
G01X1772700Y21085D02*
X1785366Y8419D01*
G01X1772700Y24611D02*
Y21085D01*
G01X1769786Y27525D02*
X1772700Y24611D01*
G01X1760661Y27525D02*
X1769786D01*
G01X1759308Y26172D02*
X1760661Y27525D01*
G01X1755079Y26172D02*
X1759308D01*
G01X1752974Y28277D02*
X1755079Y26172D01*
G01X1734794Y12907D02*
X1732501Y15200D01*
G01X1760122Y12907D02*
X1734794D01*
G01X1770861Y2168D02*
X1760122Y12907D01*
G01X1810468Y2168D02*
X1770861D01*
G01X1781333Y24060D02*
X1755917Y49476D01*
G01X1763648Y-4248D02*
X1754138Y5262D01*
G01X1763648Y-6950D02*
Y-4248D01*
G01X1767378Y-10680D02*
X1763648Y-6950D01*
G01X1823493Y-10680D02*
X1767378D01*
G01X1758473Y42879D02*
X1782740Y18612D01*
G01X1770405Y29600D02*
X1784741Y15264D01*
G01X1760042Y29600D02*
X1770405D01*
G01X1758518Y28076D02*
X1760042Y29600D01*
G01X1755869Y28076D02*
X1758518D01*
G01X1753764Y30181D02*
X1755869Y28076D01*
G01X1767123Y17662D02*
X1778261Y6524D01*
G01X1736489Y17662D02*
X1767123D01*
G01X1734567Y19584D02*
X1736489Y17662D01*
G01X1721796Y19584D02*
X1734567D01*
G01X1718580Y22800D02*
X1721796Y19584D01*
G01X1735896Y15563D02*
X1733603Y17856D01*
G01X1761224Y15563D02*
X1735896D01*
G01X1761225Y15562D02*
X1761224Y15563D01*
G01X1765444Y15562D02*
X1761225D01*
G01X1775806Y5200D02*
X1765444Y15562D01*
G01X1769263Y-484D02*
X1761613Y7166D01*
G01X1801164Y-484D02*
X1769263D01*
G01X1781671Y22375D02*
X1758960Y45086D01*
G01X1764820Y14058D02*
X1775558Y3320D01*
G01X1760601Y14058D02*
X1764820D01*
G01X1760600Y14059D02*
X1760601Y14058D01*
G01X1735272Y14059D02*
X1760600D01*
G01X1732979Y16352D02*
X1735272Y14059D01*
G01X1758868Y43831D02*
X1783135Y19564D01*
G01X1770599Y800D02*
X1802500D01*
G01X1759644Y11755D02*
X1770599Y800D01*
G01X1734055Y11755D02*
X1759644D01*
G01X1731200Y8900D02*
X1734055Y11755D01*
G01X1735584Y14811D02*
X1733291Y17104D01*
G01X1760912Y14811D02*
X1735584D01*
G01X1760913Y14810D02*
X1760912Y14811D01*
G01X1765132Y14810D02*
X1760913D01*
G01X1775870Y4072D02*
X1765132Y14810D01*
G01X1767690Y-9928D02*
X1823805D01*
G01X1764700Y-6938D02*
X1767690Y-9928D01*
G01X1764700Y-2145D02*
Y-6938D01*
G01X1756541Y6014D02*
X1764700Y-2145D01*
G01X1770181Y28477D02*
X1783780Y14878D01*
G01X1760266Y28477D02*
X1770181D01*
G01X1758913Y27124D02*
X1760266Y28477D01*
G01X1755474Y27124D02*
X1758913D01*
G01X1753369Y29229D02*
X1755474Y27124D01*
G01X1773531Y67104D02*
X1780821Y59814D01*
G01X1773531Y72203D02*
Y67104D01*
G01X1771654Y74080D02*
X1773531Y72203D01*
G01X1763689Y74080D02*
X1771654D01*
G01X1761648Y76121D02*
X1763689Y74080D01*
G01X1754732Y76121D02*
X1761648D01*
G01X1754405Y75794D02*
X1754732Y76121D01*
G01X1732600Y75794D02*
X1754405D01*
G01X1728907Y79487D02*
X1732600Y75794D01*
G01X1731335Y85343D02*
X1712652D01*
G01X1733250Y83428D02*
X1731335Y85343D01*
G01X1751568Y83428D02*
X1733250D01*
G01X1752519Y82477D02*
X1751568Y83428D01*
G01X1763576Y82477D02*
X1752519D01*
G01X1764301Y81752D02*
X1763576Y82477D01*
G01X1772303Y81752D02*
X1764301D01*
G01X1779752Y74303D02*
X1772303Y81752D01*
G01X1731870Y55354D02*
X1725840Y61384D01*
G01X1755536Y55354D02*
X1731870D01*
G01X1776033Y34857D02*
X1755536Y55354D01*
G01X1755980Y50760D02*
X1781690Y25050D01*
G01X1732423Y50760D02*
X1755980D01*
G01X1724655Y58528D02*
X1732423Y50760D01*
G01X1745152Y37500D02*
X1746552Y38900D01*
G01X1737500Y37500D02*
X1745152D01*
G01X1733500Y33500D02*
X1737500Y37500D01*
G01X1719847Y54016D02*
X1719780Y53949D01*
G01X1721153Y54016D02*
X1719847D01*
G01X1721220Y53949D02*
X1721153Y54016D01*
G01X1727887Y53949D02*
X1721220D01*
G01X1732360Y49476D02*
X1727887Y53949D01*
G01X1755917Y49476D02*
X1732360D01*
G01X1772123Y46767D02*
X1780875D01*
G01X1754890Y64000D02*
X1772123Y46767D01*
G01X1751270Y64000D02*
X1754890D01*
G01X1747144Y68126D02*
X1751270Y64000D01*
G01X1729950Y68126D02*
X1747144D01*
G01X1727050Y71026D02*
X1729950Y68126D01*
G01X1724047Y71026D02*
X1727050D01*
G01X1721445Y68424D02*
X1724047Y71026D01*
G01X1714664Y68424D02*
X1721445D01*
G01X1713974Y69114D02*
X1714664Y68424D01*
G01X1720100Y46100D02*
X1718392Y47808D01*
G01X1766333Y66144D02*
Y59116D01*
G01X1762121Y70356D02*
X1766333Y66144D01*
G01X1756239Y70356D02*
X1762121D01*
G01X1753939Y72656D02*
X1756239Y70356D01*
G01X1731027Y72656D02*
X1753939D01*
G01X1727535Y76148D02*
X1731027Y72656D01*
G01X1713217Y76148D02*
X1727535D01*
G01X1772778Y66793D02*
X1780069Y59502D01*
G01X1772778Y71892D02*
Y66793D01*
G01X1771342Y73328D02*
X1772778Y71892D01*
G01X1763377Y73328D02*
X1771342D01*
G01X1761375Y75330D02*
X1763377Y73328D01*
G01X1755005Y75330D02*
X1761375D01*
G01X1754717Y75042D02*
X1755005Y75330D01*
G01X1732288Y75042D02*
X1754717D01*
G01X1728597Y78733D02*
X1732288Y75042D01*
G01X1712153Y78733D02*
X1728597D01*
G01X1728391Y66484D02*
X1728083Y66792D01*
G01X1746483Y66484D02*
X1728391D01*
G01X1746863Y66104D02*
X1746483Y66484D01*
G01X1747174Y66104D02*
X1746863D01*
G01X1750686Y62592D02*
X1747174Y66104D01*
G01X1753912Y62592D02*
X1750686D01*
G01X1772104Y44400D02*
X1753912Y62592D01*
G01X1779497Y44400D02*
X1772104D01*
G01X1771328Y79400D02*
X1777212Y73516D01*
G01X1763326Y79400D02*
X1771328D01*
G01X1763099Y79627D02*
X1763326Y79400D01*
G01X1752042Y79627D02*
X1763099D01*
G01X1750593Y81076D02*
X1752042Y79627D01*
G01X1732275Y81076D02*
X1750593D01*
G01X1730360Y82991D02*
X1732275Y81076D01*
G01X1728119Y77581D02*
X1712658D01*
G01X1731892Y73808D02*
X1728119Y77581D01*
G01X1754622Y73808D02*
X1731892D01*
G01X1756448Y71982D02*
X1754622Y73808D01*
G01X1764615Y71982D02*
X1756448D01*
G01X1764809Y72176D02*
X1764615Y71982D01*
G01X1770864Y72176D02*
X1764809D01*
G01X1771626Y71414D02*
X1770864Y72176D01*
G01X1771626Y66315D02*
Y71414D01*
G01X1778917Y59024D02*
X1771626Y66315D01*
G01X1728835Y50865D02*
X1728834Y50864D01*
G01X1729623Y50865D02*
X1728835D01*
G01X1735402Y45086D02*
X1729623Y50865D01*
G01X1758960Y45086D02*
X1735402D01*
G01X1733053Y76971D02*
X1729385Y80639D01*
G01X1753952Y76971D02*
X1733053D01*
G01X1754256Y77275D02*
X1753952Y76971D01*
G01X1762124Y77275D02*
X1754256D01*
G01X1764167Y75232D02*
X1762124Y77275D01*
G01X1772132Y75232D02*
X1764167D01*
G01X1774683Y72681D02*
X1772132Y75232D01*
G01X1720708Y87724D02*
X1717802Y90630D01*
G01X1767274Y87724D02*
X1720708D01*
G01X1770694Y84304D02*
X1767274Y87724D01*
G01X1776415Y84304D02*
X1770694D01*
G01X1731475Y54402D02*
X1725445Y60432D01*
G01X1755141Y54402D02*
X1731475D01*
G01X1775638Y33905D02*
X1755141Y54402D01*
G01X1771912Y43400D02*
X1779433D01*
G01X1753598Y61714D02*
X1771912Y43400D01*
G01X1750500Y61714D02*
X1753598D01*
G01X1746862Y65352D02*
X1750500Y61714D01*
G01X1728459Y65352D02*
X1746862D01*
G01X1727771Y66040D02*
X1728459Y65352D01*
G01X1772293Y91753D02*
X1786808Y77238D01*
G01X1767047Y91753D02*
X1772293D01*
G01X1765503Y93297D02*
X1767047Y91753D01*
G01X1757554Y93297D02*
X1765503D01*
G01X1754333Y90076D02*
X1757554Y93297D01*
G01X1722669Y90076D02*
X1754333D01*
G01X1719763Y92982D02*
X1722669Y90076D01*
G01X1732265Y56306D02*
X1726235Y62336D01*
G01X1755949Y56306D02*
X1732265D01*
G01X1773159Y39096D02*
X1755949Y56306D01*
G01X1774959Y39096D02*
X1773159D01*
G01X1756056Y52031D02*
X1779587Y28500D01*
G01X1732499Y52031D02*
X1756056D01*
G01X1725050Y59480D02*
X1732499Y52031D01*
G01X1728220Y64527D02*
X1727459Y65288D01*
G01X1746435Y64527D02*
X1728220D01*
G01X1750000Y60962D02*
X1746435Y64527D01*
G01X1752792Y60962D02*
X1750000D01*
G01X1756296Y57458D02*
X1752792Y60962D01*
G01X1756427Y57458D02*
X1756296D01*
G01X1771550Y42335D02*
X1756427Y57458D01*
G01X1779434Y42335D02*
X1771550D01*
G01X1768977Y150414D02*
X1762710Y156681D01*
G01X1791174Y150414D02*
X1768977D01*
G01X1763699Y145420D02*
X1803633D01*
G01X1756779Y152340D02*
X1763699Y145420D01*
G01X1754056Y152340D02*
X1756779D01*
G01X1753475Y151759D02*
X1754056Y152340D01*
G01X1744304Y151759D02*
X1753475D01*
G01X1742409Y153654D02*
X1744304Y151759D01*
G01X1712444Y153654D02*
X1742409D01*
G01X1768173Y135747D02*
X1804315D01*
G01X1756992Y146928D02*
X1768173Y135747D01*
G01X1755633Y146928D02*
X1756992D01*
G01X1752467Y150094D02*
X1755633Y146928D01*
G01X1743001Y150094D02*
X1752467D01*
G01X1741357Y151738D02*
X1743001Y150094D01*
G01X1713248Y151738D02*
X1741357D01*
G01X1748875Y154618D02*
X1747912Y155581D01*
G01X1758781Y154618D02*
X1748875D01*
G01X1765355Y148044D02*
X1758781Y154618D01*
G01X1792444Y148044D02*
X1765355D01*
G01X1764544Y146653D02*
X1792459D01*
G01X1757542Y153655D02*
X1764544Y146653D01*
G01X1748295Y153655D02*
X1757542D01*
G01X1747230Y154720D02*
X1748295Y153655D01*
G01X1712776Y154720D02*
X1747230D01*
G01X1712685Y154629D02*
X1712776Y154720D01*
G01X1750643Y155770D02*
X1749942Y156471D01*
G01X1760197Y155770D02*
X1750643D01*
G01X1766771Y149196D02*
X1760197Y155770D01*
G01X1791945Y149196D02*
X1766771D01*
G01X1770516Y107187D02*
X1775616D01*
G01X1769516Y108187D02*
X1770516Y107187D01*
G01X1768116Y108187D02*
X1769516D01*
G01X1761300Y115003D02*
X1768116Y108187D01*
G01X1761300Y119100D02*
Y115003D01*
G01X1769986Y151331D02*
X1760816Y160501D01*
G01X1790472Y151331D02*
X1769986D01*
G01X1769900Y105700D02*
X1775000D01*
G01X1768900Y106700D02*
X1769900Y105700D01*
G01X1767500Y106700D02*
X1768900D01*
G01X1758100Y116100D02*
X1767500Y106700D01*
G01X1758100Y119100D02*
Y116100D01*
G01X1740727Y150658D02*
X1713604D01*
G01X1742042Y149343D02*
X1740727Y150658D01*
G01X1752155Y149343D02*
X1742042D01*
G01X1755364Y146134D02*
X1752155Y149343D01*
G01X1756258Y146134D02*
X1755364D01*
G01X1767725Y134667D02*
X1756258Y146134D01*
G01X1802031Y134667D02*
X1767725D01*
G01X1741643Y152554D02*
X1712872D01*
G01X1743264Y150933D02*
X1741643Y152554D01*
G01X1752773Y150933D02*
X1743264D01*
G01X1755708Y147998D02*
X1752773Y150933D01*
G01X1758246Y147998D02*
X1755708D01*
G01X1768122Y138122D02*
X1758246Y147998D01*
G01X1821691Y138122D02*
X1768122D01*
G01X1749224Y157222D02*
X1748695Y157751D01*
G01X1750512Y157222D02*
X1749224D01*
G01X1751053Y156681D02*
X1750512Y157222D01*
G01X1762710Y156681D02*
X1751053D01*
G01X1713014Y163224D02*
X1712963D01*
G01X1713127Y163337D02*
X1713014Y163224D01*
G01X1750261Y163337D02*
X1713127D01*
G01X1751797Y161801D02*
X1750261Y163337D01*
G01X1761503Y161801D02*
X1751797D01*
G01X1763778Y159526D02*
X1761503Y161801D01*
G01X1809460Y159526D02*
X1763778D01*
G01X1748635Y156747D02*
X1748593Y156789D01*
G01X1748636Y156747D02*
X1748635D01*
G01X1748912Y156471D02*
X1748636Y156747D01*
G01X1749942Y156471D02*
X1748912D01*
G01X1717635Y193300D02*
X1712962Y191365D01*
G01X1847700Y193300D02*
X1717635D01*
G01X1749783Y162185D02*
X1713554D01*
G01X1751467Y160501D02*
X1749783Y162185D01*
G01X1760816Y160501D02*
X1751467D01*
G01X1738350Y241750D02*
X1733900Y237300D01*
G01X1741650Y241750D02*
X1738350D01*
G01X1746900Y247000D02*
X1741650Y241750D01*
G01X1746900Y249804D02*
Y247000D01*
G01X1722444Y244422D02*
X1724181Y246159D01*
G01X1722444Y243695D02*
Y244422D01*
G01X1715200Y236451D02*
X1722444Y243695D01*
G01X1715200Y226543D02*
Y236451D01*
G01X1720804Y251979D02*
X1722251Y250532D01*
G01X1714016Y251979D02*
X1720804D01*
G01X1715837Y244106D02*
Y246178D01*
G01X1714447Y242716D02*
X1715837Y244106D01*
G01X1714447Y226854D02*
Y242716D01*
G01X1716353Y227020D02*
Y226066D01*
G01X1716352Y227021D02*
X1716353Y227020D01*
G01X1716352Y232723D02*
Y227021D01*
G01X1719080Y235451D02*
X1716352Y232723D01*
G01X1719080Y236152D02*
Y235451D01*
G01X1737618Y233334D02*
X1736847D01*
G01X1738721Y232231D02*
X1737618Y233334D01*
G01X1738721Y229580D02*
Y232231D01*
G01X1740001Y228300D02*
X1738721Y229580D01*
G01X1793948Y228300D02*
X1740001D01*
G01X1719080Y232852D02*
Y225580D01*
G01X1739300Y240200D02*
X1736400Y237300D01*
G01X1742400Y240200D02*
X1739300D01*
G01X1751900Y249700D02*
X1742400Y240200D01*
G01X1739673Y233160D02*
X1739847Y233334D01*
G01X1739673Y229975D02*
Y233160D01*
G01X1740396Y229252D02*
X1739673Y229975D01*
G01X1793509Y229252D02*
X1740396D01*
G01X1735210Y441190D02*
X1855361D01*
G01X1729398Y447002D02*
X1735210Y441190D01*
G01X1730321Y461979D02*
X1721739D01*
G01X1737652Y454648D02*
X1730321Y461979D01*
G01X1836011Y454648D02*
X1737652D01*
G01X1726061Y454205D02*
X1716859D01*
G01X1727833Y452433D02*
X1726061Y454205D01*
G01X1727833Y450853D02*
Y452433D01*
G01X1735800Y442886D02*
X1727833Y450853D01*
G01X1847551Y442886D02*
X1735800D01*
G01X1731439Y440004D02*
X1727592Y436157D01*
G01X1861833Y440004D02*
X1731439D01*
G01X1729746Y447754D02*
X1722246D01*
G01X1735430Y442070D02*
X1729746Y447754D01*
G01X1847799Y442070D02*
X1735430D01*
G01X1736112Y443638D02*
X1847239D01*
G01X1728700Y451050D02*
X1736112Y443638D01*
G01X1728700Y452630D02*
Y451050D01*
G01X1726373Y454957D02*
X1728700Y452630D01*
G01X1717442Y454957D02*
X1726373D01*
G01X1725575Y458752D02*
X1720135D01*
G01X1730952Y453375D02*
X1725575Y458752D01*
G01X1730952Y451775D02*
Y453375D01*
G01X1737185Y445542D02*
X1730952Y451775D01*
G01X1845552Y445542D02*
X1737185D01*
G01X1729593Y460827D02*
X1721261D01*
G01X1736924Y453496D02*
X1729593Y460827D01*
G01X1825704Y453496D02*
X1736924D01*
G01X1721990Y444521D02*
X1720261Y446250D01*
G01X1716978Y436909D02*
X1724590Y444521D01*
G01X1725180Y457800D02*
X1719740D01*
G01X1730000Y452980D02*
X1725180Y457800D01*
G01X1730000Y451380D02*
Y452980D01*
G01X1736590Y444790D02*
X1730000Y451380D01*
G01X1846147Y444790D02*
X1736590D01*
G01X1769205Y534500D02*
X1779200D01*
G01X1766747Y536958D02*
X1769205Y534500D01*
G01X1766748Y536959D02*
X1766747Y536958D01*
G01X1766748Y538922D02*
Y536959D01*
G01X1757478Y548192D02*
X1766748Y538922D01*
G01X1738930Y554255D02*
X1738498D01*
G01X1740864Y556189D02*
X1738930Y554255D01*
G01X1740864Y565713D02*
Y556189D01*
G01X1736498Y570079D02*
X1740864Y565713D01*
G01X1736498Y582385D02*
Y570079D01*
G01X1734026Y584857D02*
X1736498Y582385D01*
G01X1734026Y588671D02*
Y584857D01*
G01X1769683Y535652D02*
X1779678D01*
G01X1767900Y537435D02*
X1769683Y535652D01*
G01X1767900Y542223D02*
Y537435D01*
G01X1760355Y549768D02*
X1767900Y542223D01*
G01X1755392Y549768D02*
X1760355D01*
G01X1753807Y548183D02*
X1755392Y549768D01*
G01X1737280Y570720D02*
X1743500Y564500D01*
G01X1737280Y583067D02*
Y570720D01*
G01X1736003Y584344D02*
X1737280Y583067D01*
G01X1736003Y588244D02*
Y584344D01*
G01X1753418Y595849D02*
X1786881D01*
G01X1744300Y604967D02*
X1753418Y595849D01*
G01X1739714Y604967D02*
X1744300D01*
G01X1737425Y592070D02*
X1734026Y588671D01*
G01X1739179Y592070D02*
X1737425D01*
G01X1720473Y608529D02*
X1718444Y606500D01*
G01X1763621Y608529D02*
X1720473D01*
G01X1767650Y604500D02*
X1763621Y608529D01*
G01X1792600Y604500D02*
X1767650D01*
G01X1718900Y601500D02*
X1716950Y603450D01*
G01X1745999Y601500D02*
X1718900D01*
G01X1753060Y594439D02*
X1745999Y601500D01*
G01X1779003Y594439D02*
X1753060D01*
G01X1788775Y28452D02*
X1782370Y34857D01*
G01X1789966Y28452D02*
X1788775D01*
G01X1791500Y26918D02*
X1789966Y28452D01*
G01X1785366Y8419D02*
Y8100D01*
G01X1812163Y3863D02*
X1810468Y2168D01*
G01X1814566Y3863D02*
X1812163D01*
G01X1815489Y2940D02*
X1814566Y3863D01*
G01X1815489Y-6326D02*
Y2940D01*
G01X1817939Y-8776D02*
X1815489Y-6326D01*
G01X1824283Y-8776D02*
X1817939D01*
G01X1829394Y-3665D02*
X1824283Y-8776D01*
G01X1829394Y-1648D02*
Y-3665D01*
G01X1831980Y938D02*
X1829394Y-1648D01*
G01X1831980Y4480D02*
Y938D01*
G01X1834200Y6700D02*
X1831980Y4480D01*
G01X1844600Y6700D02*
X1834200D01*
G01X1829520Y24010D02*
X1838910D01*
G01X1829519Y24009D02*
X1829520Y24010D01*
G01X1828731Y24009D02*
X1829519D01*
G01X1828512Y24228D02*
X1828731Y24009D01*
G01X1818591Y24228D02*
X1828512D01*
G01X1812483Y18120D02*
X1818591Y24228D01*
G01X1804533Y18120D02*
X1812483D01*
G01X1801182Y21471D02*
X1804533Y18120D01*
G01X1801182Y22459D02*
Y21471D01*
G01X1799143Y24498D02*
X1801182Y22459D01*
G01X1796257Y24498D02*
X1799143D01*
G01X1794876Y23117D02*
X1796257Y24498D01*
G01X1789871Y23117D02*
X1794876D01*
G01X1787976Y25012D02*
X1789871Y23117D01*
G01X1787596Y25012D02*
X1787976D01*
G01X1787558Y25050D02*
X1787596Y25012D01*
G01X1781690Y25050D02*
X1787558D01*
G01X1787581Y24060D02*
X1781333D01*
G01X1789551Y22090D02*
X1787581Y24060D01*
G01X1795196Y22090D02*
X1789551D01*
G01X1796652Y23546D02*
X1795196Y22090D01*
G01X1798748Y23546D02*
X1796652D01*
G01X1800229Y22065D02*
X1798748Y23546D01*
G01X1800229Y21077D02*
Y22065D01*
G01X1804138Y17168D02*
X1800229Y21077D01*
G01X1813076Y17168D02*
X1804138D01*
G01X1819184Y23276D02*
X1813076Y17168D01*
G01X1827116Y23276D02*
X1819184D01*
G01X1827881Y22511D02*
X1827116Y23276D01*
G01X1827881Y19950D02*
Y22511D01*
G01X1830532Y17299D02*
X1827881Y19950D01*
G01X1837801Y17299D02*
X1830532D01*
G01X1823494Y-10681D02*
X1823493Y-10680D01*
G01X1825072Y-10681D02*
X1823494D01*
G01X1825073Y-10680D02*
X1825072Y-10681D01*
G01X1825620Y-10680D02*
X1825073D01*
G01X1831298Y-5002D02*
X1825620Y-10680D01*
G01X1831298Y-2438D02*
Y-5002D01*
G01X1835600Y1864D02*
X1831298Y-2438D01*
G01X1797700Y19664D02*
Y21018D01*
G01X1796648Y18612D02*
X1797700Y19664D01*
G01X1794412Y18612D02*
X1796648D01*
G01X1794411Y18611D02*
X1794412Y18612D01*
G01X1789956Y18611D02*
X1794411D01*
G01X1789955Y18612D02*
X1789956Y18611D01*
G01X1782740Y18612D02*
X1789955D01*
G01X1829635Y10735D02*
X1829888D01*
G01X1826100Y7200D02*
X1829635Y10735D01*
G01X1822971Y7200D02*
X1826100D01*
G01X1821200Y8971D02*
X1822971Y7200D01*
G01X1821200Y13290D02*
Y8971D01*
G01X1818390Y16100D02*
X1821200Y13290D01*
G01X1814702Y16100D02*
X1818390D01*
G01X1813866Y15264D02*
X1814702Y16100D01*
G01X1784741Y15264D02*
X1813866D01*
G01X1824299Y1000D02*
X1825324D01*
G01X1817228Y8071D02*
X1824299Y1000D01*
G01X1809671Y8071D02*
X1817228D01*
G01X1808124Y6524D02*
X1809671Y8071D01*
G01X1778261Y6524D02*
X1808124D01*
G01X1809742Y5200D02*
X1775806D01*
G01X1811442Y6900D02*
X1809742Y5200D01*
G01X1816300Y6900D02*
X1811442D01*
G01X1819800Y3400D02*
X1816300Y6900D01*
G01X1819800Y2100D02*
Y3400D01*
G01X1804033Y-3353D02*
X1801164Y-484D01*
G01X1805567Y-3353D02*
X1804033D01*
G01X1805820Y-3100D02*
X1805567Y-3353D01*
G01X1805922Y-3100D02*
X1805820D01*
G01X1809472Y450D02*
X1805922Y-3100D01*
G01X1812076Y450D02*
X1809472D01*
G01X1813913Y2287D02*
X1812076Y450D01*
G01X1814350Y-19846D02*
X1809504Y-15000D01*
G01X1822406Y-19846D02*
X1814350D01*
G01X1827108Y-15144D02*
X1822406Y-19846D01*
G01X1827108Y-10393D02*
Y-15144D01*
G01X1832050Y-5451D02*
X1827108Y-10393D01*
G01X1832050Y-2750D02*
Y-5451D01*
G01X1835583Y783D02*
X1832050Y-2750D01*
G01X1808271Y29200D02*
X1804147Y33324D01*
G01X1812070Y29200D02*
X1808271D01*
G01X1813668Y30798D02*
X1812070Y29200D01*
G01X1842921Y30798D02*
X1813668D01*
G01X1807037Y32552D02*
X1799527Y40062D01*
G01X1842801Y32552D02*
X1807037D01*
G01X1786865Y22375D02*
X1781671D01*
G01X1833700Y7900D02*
X1844100D01*
G01X1830800Y5000D02*
X1833700Y7900D01*
G01X1830800Y1388D02*
Y5000D01*
G01X1826798Y-2614D02*
X1830800Y1388D01*
G01X1823185Y-2614D02*
X1826798D01*
G01X1820799Y-228D02*
X1823185Y-2614D01*
G01X1818835Y-228D02*
X1820799D01*
G01X1816641Y1966D02*
X1818835Y-228D01*
G01X1816641Y3418D02*
Y1966D01*
G01X1815043Y5016D02*
X1816641Y3418D01*
G01X1814089Y5016D02*
X1815043D01*
G01X1814088Y5015D02*
X1814089Y5016D01*
G01X1811685Y5015D02*
X1814088D01*
G01X1809990Y3320D02*
X1811685Y5015D01*
G01X1775558Y3320D02*
X1809990D01*
G01X1823600Y12247D02*
Y8800D01*
G01X1818794Y17053D02*
X1823600Y12247D01*
G01X1814308Y17053D02*
X1818794D01*
G01X1813471Y16216D02*
X1814308Y17053D01*
G01X1802643Y16216D02*
X1813471D01*
G01X1799276Y19583D02*
X1802643Y16216D01*
G01X1799276Y21671D02*
Y19583D01*
G01X1798353Y22594D02*
X1799276Y21671D01*
G01X1797047Y22594D02*
X1798353D01*
G01X1794016Y19563D02*
X1797047Y22594D01*
G01X1790351Y19563D02*
X1794016D01*
G01X1790350Y19564D02*
X1790351Y19563D01*
G01X1783135Y19564D02*
X1790350D01*
G01X1790728Y25152D02*
X1781975Y33905D01*
G01X1791952Y25152D02*
X1790728D01*
G01X1792142Y25342D02*
X1791952Y25152D01*
G01X1792153Y25342D02*
X1792142D01*
G01X1794611Y27800D02*
X1792153Y25342D01*
G01X1800448Y27800D02*
X1794611D01*
G01X1804438Y23810D02*
X1800448Y27800D01*
G01X1804438Y23192D02*
Y23810D01*
G01X1805778Y21852D02*
X1804438Y23192D01*
G01X1808048Y21852D02*
X1805778D01*
G01X1808100Y21800D02*
X1808048Y21852D01*
G01X1802500Y800D02*
X1804800Y-1500D01*
G01X1803835Y32572D02*
X1809822Y26585D01*
G01X1800749Y32572D02*
X1803835D01*
G01X1800739Y32562D02*
X1800749Y32572D01*
G01X1798809Y32562D02*
X1800739D01*
G01X1798799Y32572D02*
X1798809Y32562D01*
G01X1789735Y32572D02*
X1798799D01*
G01X1784382Y37925D02*
X1789735Y32572D01*
G01X1809678Y4072D02*
X1775870D01*
G01X1811373Y5767D02*
X1809678Y4072D01*
G01X1813776Y5767D02*
X1811373D01*
G01X1813777Y5768D02*
X1813776Y5767D01*
G01X1815355Y5768D02*
X1813777D01*
G01X1817393Y3730D02*
X1815355Y5768D01*
G01X1817393Y2278D02*
Y3730D01*
G01X1819147Y524D02*
X1817393Y2278D01*
G01X1821276Y524D02*
X1819147D01*
G01X1823350Y-1550D02*
X1821276Y524D01*
G01X1825250Y-1550D02*
X1823350D01*
G01X1827248Y448D02*
X1825250Y-1550D01*
G01X1827248Y4352D02*
Y448D01*
G01X1828696Y5800D02*
X1827248Y4352D01*
G01X1830500Y5800D02*
X1828696D01*
G01X1833500Y8800D02*
X1830500Y5800D01*
G01X1837000Y8800D02*
X1833500D01*
G01X1834700Y5500D02*
X1845099D01*
G01X1833132Y3932D02*
X1834700Y5500D01*
G01X1833132Y460D02*
Y3932D01*
G01X1830546Y-2126D02*
X1833132Y460D01*
G01X1830546Y-4143D02*
Y-2126D01*
G01X1824760Y-9929D02*
X1830546Y-4143D01*
G01X1823806Y-9929D02*
X1824760D01*
G01X1823805Y-9928D02*
X1823806Y-9929D01*
G01X1829125Y24962D02*
X1840187D01*
G01X1828907Y25180D02*
X1829125Y24962D01*
G01X1819974Y25180D02*
X1828907D01*
G01X1819973Y25181D02*
X1819974Y25180D01*
G01X1818011Y25181D02*
X1819973D01*
G01X1811902Y19072D02*
X1818011Y25181D01*
G01X1804928Y19072D02*
X1811902D01*
G01X1802134Y21866D02*
X1804928Y19072D01*
G01X1802134Y22854D02*
Y21866D01*
G01X1799538Y25450D02*
X1802134Y22854D01*
G01X1795862Y25450D02*
X1799538D01*
G01X1794481Y24069D02*
X1795862Y25450D01*
G01X1790266Y24069D02*
X1794481D01*
G01X1785835Y28500D02*
X1790266Y24069D01*
G01X1779587Y28500D02*
X1785835D01*
G01X1789535Y31708D02*
X1783630Y37613D01*
G01X1802337Y31708D02*
X1789535D01*
G01X1807127Y26918D02*
X1802337Y31708D01*
G01X1831400Y8800D02*
X1832900Y10300D01*
G01X1829700Y8800D02*
X1831400D01*
G01X1827100Y6200D02*
X1829700Y8800D01*
G01X1822153Y6200D02*
X1827100D01*
G01X1819547Y8806D02*
X1822153Y6200D01*
G01X1819547Y13253D02*
Y8806D01*
G01X1817893Y14907D02*
X1819547Y13253D01*
G01X1814857Y14907D02*
X1817893D01*
G01X1814260Y14310D02*
X1814857Y14907D01*
G01X1784340Y14310D02*
X1814260D01*
G01X1783780Y14870D02*
X1784340Y14310D01*
G01X1783780Y14878D02*
Y14870D01*
G01X1834140Y37300D02*
X1839300D01*
G01X1833050Y36210D02*
X1834140Y37300D01*
G01X1828790Y36210D02*
X1833050D01*
G01X1827395Y37605D02*
X1828790Y36210D01*
G01X1823477Y37605D02*
X1827395D01*
G01X1822554Y38528D02*
X1823477Y37605D01*
G01X1822554Y39834D02*
Y38528D01*
G01X1819940Y42448D02*
X1822554Y39834D01*
G01X1790022Y42448D02*
X1819940D01*
G01X1780821Y51649D02*
X1790022Y42448D01*
G01X1780821Y59814D02*
Y51649D01*
G01X1779752Y69167D02*
Y74303D01*
G01X1784078Y64841D02*
X1779752Y69167D01*
G01X1784341Y64841D02*
X1784078D01*
G01X1782370Y34857D02*
X1776033D01*
G01X1780875Y46767D02*
X1789356Y38286D01*
G01X1816500Y81300D02*
X1858671Y123471D01*
G01X1816500Y55638D02*
Y81300D01*
G01X1815637Y54775D02*
X1816500Y55638D01*
G01X1834296Y59204D02*
X1843067D01*
G01X1829784Y63716D02*
X1834296Y59204D01*
G01X1829784Y73995D02*
Y63716D01*
G01X1834504Y78715D02*
X1829784Y73995D01*
G01X1834504Y93130D02*
Y78715D01*
G01X1843289Y101915D02*
X1834504Y93130D01*
G01X1812945Y33704D02*
X1842323D01*
G01X1810493Y36156D02*
X1812945Y33704D01*
G01X1810493Y40506D02*
Y36156D01*
G01X1809348Y41651D02*
X1810493Y40506D01*
G01X1789755Y41651D02*
X1809348D01*
G01X1780069Y51337D02*
X1789755Y41651D01*
G01X1780069Y59502D02*
Y51337D01*
G01X1817655Y81313D02*
X1859423Y123081D01*
G01X1817655Y55493D02*
Y81313D01*
G01X1818396Y54752D02*
X1817655Y55493D01*
G01X1785134Y38763D02*
X1779497Y44400D01*
G01X1785134Y38237D02*
Y38763D01*
G01X1790047Y33324D02*
X1785134Y38237D01*
G01X1799111Y33324D02*
X1790047D01*
G01X1799121Y33314D02*
X1799111Y33324D01*
G01X1800427Y33314D02*
X1799121D01*
G01X1800437Y33324D02*
X1800427Y33314D01*
G01X1804147Y33324D02*
X1800437D01*
G01X1833984Y58452D02*
X1842755D01*
G01X1829032Y63404D02*
X1833984Y58452D01*
G01X1829032Y74307D02*
Y63404D01*
G01X1831609Y76884D02*
X1829032Y74307D01*
G01X1831609Y92075D02*
Y76884D01*
G01X1842334Y102800D02*
X1831609Y92075D01*
G01X1823202Y46320D02*
X1837907D01*
G01X1822270Y47252D02*
X1823202Y46320D01*
G01X1812748Y47252D02*
X1822270D01*
G01X1810592Y49408D02*
X1812748Y47252D01*
G01X1795493Y49408D02*
X1810592D01*
G01X1784947Y59954D02*
X1795493Y49408D01*
G01X1784947Y60645D02*
Y59954D01*
G01X1777212Y68380D02*
X1784947Y60645D01*
G01X1777212Y73516D02*
Y68380D01*
G01X1778917Y50859D02*
Y59024D01*
G01X1789714Y40062D02*
X1778917Y50859D01*
G01X1799527Y40062D02*
X1789714D01*
G01X1774683Y67582D02*
Y72681D01*
G01X1781973Y60292D02*
X1774683Y67582D01*
G01X1781973Y52127D02*
Y60292D01*
G01X1788196Y45904D02*
X1781973Y52127D01*
G01X1804096Y45904D02*
X1788196D01*
G01X1806400Y43600D02*
X1804096Y45904D01*
G01X1820965Y43600D02*
X1806400D01*
G01X1821749Y42816D02*
X1820965Y43600D01*
G01X1825583Y42816D02*
X1821749D01*
G01X1826900Y41499D02*
X1825583Y42816D01*
G01X1826900Y40400D02*
Y41499D01*
G01X1784456Y76263D02*
X1776415Y84304D01*
G01X1784456Y68798D02*
Y76263D01*
G01X1790588Y62666D02*
X1784456Y68798D01*
G01X1790588Y60786D02*
Y62666D01*
G01X1799614Y51760D02*
X1790588Y60786D01*
G01X1811640Y51760D02*
X1799614D01*
G01X1813796Y49604D02*
X1811640Y51760D01*
G01X1823245Y49604D02*
X1813796D01*
G01X1824177Y48672D02*
X1823245Y49604D01*
G01X1838882Y48672D02*
X1824177D01*
G01X1796100Y72394D02*
Y68800D01*
G01X1794187Y74307D02*
X1796100Y72394D01*
G01X1794187Y91916D02*
Y74307D01*
G01X1789474Y96629D02*
X1794187Y91916D01*
G01X1832006Y54400D02*
X1839808D01*
G01X1825976Y60430D02*
X1832006Y54400D01*
G01X1825976Y76976D02*
Y60430D01*
G01X1829733Y80733D02*
X1825976Y76976D01*
G01X1829733Y92327D02*
Y80733D01*
G01X1857706Y120300D02*
X1829733Y92327D01*
G01X1781975Y33905D02*
X1775638D01*
G01X1831670Y55800D02*
X1839472D01*
G01X1826728Y60742D02*
X1831670Y55800D01*
G01X1826728Y76428D02*
Y60742D01*
G01X1830485Y80185D02*
X1826728Y76428D01*
G01X1830485Y92015D02*
Y80185D01*
G01X1858018Y119548D02*
X1830485Y92015D01*
G01X1802119Y71276D02*
Y56581D01*
G01X1818729Y87886D02*
X1802119Y71276D01*
G01X1818729Y96470D02*
Y87886D01*
G01X1784382Y38451D02*
Y37925D01*
G01X1779433Y43400D02*
X1784382Y38451D01*
G01X1825152Y51024D02*
X1839857D01*
G01X1824220Y51956D02*
X1825152Y51024D01*
G01X1814771Y51956D02*
X1824220D01*
G01X1811922Y54805D02*
X1814771Y51956D01*
G01X1801383Y54805D02*
X1811922D01*
G01X1799767Y56421D02*
X1801383Y54805D01*
G01X1799767Y64402D02*
Y56421D01*
G01X1798215Y65954D02*
X1799767Y64402D01*
G01X1790627Y65954D02*
X1798215D01*
G01X1786808Y69773D02*
X1790627Y65954D01*
G01X1786808Y77238D02*
Y69773D01*
G01X1792700Y72298D02*
X1794100Y70898D01*
G01X1792700Y91300D02*
Y72298D01*
G01X1788815Y95185D02*
X1792700Y91300D01*
G01X1774976Y39079D02*
X1774959Y39096D01*
G01X1777201Y39079D02*
X1774976D01*
G01X1779750Y36530D02*
X1777201Y39079D01*
G01X1783630Y38139D02*
X1779434Y42335D01*
G01X1783630Y37613D02*
Y38139D01*
G01X1796567Y155807D02*
X1791174Y150414D01*
G01X1804067Y155807D02*
X1796567D01*
G01X1806658Y153216D02*
X1804067Y155807D01*
G01X1815376Y153216D02*
X1806658D01*
G01X1815383Y153209D02*
X1815376Y153216D01*
G01X1817313Y153209D02*
X1815383D01*
G01X1817320Y153216D02*
X1817313Y153209D01*
G01X1819676Y153216D02*
X1817320D01*
G01X1819683Y153209D02*
X1819676Y153216D01*
G01X1821613Y153209D02*
X1819683D01*
G01X1821620Y153216D02*
X1821613Y153209D01*
G01X1822132Y153216D02*
X1821620D01*
G01X1827738Y158822D02*
X1822132Y153216D01*
G01X1829735Y147576D02*
X1837606D01*
G01X1828637Y146478D02*
X1829735Y147576D01*
G01X1811425Y146478D02*
X1828637D01*
G01X1809820Y144873D02*
X1811425Y146478D01*
G01X1804970Y144873D02*
X1809820D01*
G01X1804969Y144872D02*
X1804970Y144873D01*
G01X1804181Y144872D02*
X1804969D01*
G01X1803633Y145420D02*
X1804181Y144872D01*
G01X1805109Y130100D02*
X1803509Y128500D01*
G01X1851100Y130100D02*
X1805109D01*
G01X1822944Y132833D02*
X1853374D01*
G01X1819703Y136074D02*
X1822944Y132833D01*
G01X1814322Y136074D02*
X1819703D01*
G01X1812610Y134362D02*
X1814322Y136074D01*
G01X1805700Y134362D02*
X1812610D01*
G01X1804315Y135747D02*
X1805700Y134362D01*
G01X1797963Y153563D02*
X1792444Y148044D01*
G01X1802306Y153563D02*
X1797963D01*
G01X1804557Y151312D02*
X1802306Y153563D01*
G01X1814586Y151312D02*
X1804557D01*
G01X1814593Y151305D02*
X1814586Y151312D01*
G01X1818103Y151305D02*
X1814593D01*
G01X1818110Y151312D02*
X1818103Y151305D01*
G01X1818886Y151312D02*
X1818110D01*
G01X1818893Y151305D02*
X1818886Y151312D01*
G01X1822403Y151305D02*
X1818893D01*
G01X1822410Y151312D02*
X1822403Y151305D01*
G01X1822922Y151312D02*
X1822410D01*
G01X1828338Y156728D02*
X1822922Y151312D01*
G01X1828080Y155123D02*
X1841532D01*
G01X1823317Y150360D02*
X1828080Y155123D01*
G01X1822805Y150360D02*
X1823317D01*
G01X1822798Y150353D02*
X1822805Y150360D01*
G01X1814198Y150353D02*
X1822798D01*
G01X1814191Y150360D02*
X1814198Y150353D01*
G01X1796166Y150360D02*
X1814191D01*
G01X1792459Y146653D02*
X1796166Y150360D01*
G01X1797504Y154755D02*
X1791945Y149196D01*
G01X1803193Y154755D02*
X1797504D01*
G01X1805484Y152464D02*
X1803193Y154755D01*
G01X1815064Y152464D02*
X1805484D01*
G01X1815071Y152457D02*
X1815064Y152464D01*
G01X1817625Y152457D02*
X1815071D01*
G01X1817632Y152464D02*
X1817625Y152457D01*
G01X1819364Y152464D02*
X1817632D01*
G01X1819371Y152457D02*
X1819364Y152464D01*
G01X1821925Y152457D02*
X1819371D01*
G01X1821932Y152464D02*
X1821925Y152457D01*
G01X1822444Y152464D02*
X1821932D01*
G01X1827860Y157880D02*
X1822444Y152464D01*
G01X1786174Y96629D02*
X1789474D01*
G01X1775616Y107187D02*
X1786174Y96629D01*
G01X1776828Y155211D02*
X1779428Y157811D01*
G01X1818474Y96725D02*
X1818729Y96470D01*
G01X1818474Y97923D02*
Y96725D01*
G01X1820700Y100149D02*
X1818474Y97923D01*
G01X1820700Y119079D02*
Y100149D01*
G01X1813118Y126661D02*
X1820700Y119079D01*
G01X1813118Y127976D02*
Y126661D01*
G01X1795700Y156559D02*
X1790472Y151331D01*
G01X1807495Y153968D02*
X1804904Y156559D01*
G01X1815688Y153968D02*
X1807495D01*
G01X1815695Y153961D02*
X1815688Y153968D01*
G01X1817001Y153961D02*
X1815695D01*
G01X1817008Y153968D02*
X1817001Y153961D01*
G01X1819988Y153968D02*
X1817008D01*
G01X1819995Y153961D02*
X1819988Y153968D01*
G01X1821301Y153961D02*
X1819995D01*
G01X1821308Y153968D02*
X1821301Y153961D01*
G01X1821820Y153968D02*
X1821308D01*
G01X1825940Y158088D02*
X1821820Y153968D01*
G01X1785515Y95185D02*
X1788815D01*
G01X1775000Y105700D02*
X1785515Y95185D01*
G01X1801520Y149340D02*
X1800420Y148240D01*
G01X1810360Y149340D02*
X1801520D01*
G01X1812270Y147430D02*
X1810360Y149340D01*
G01X1828039Y147430D02*
X1812270D01*
G01X1829137Y148528D02*
X1828039Y147430D01*
G01X1833559Y148528D02*
X1829137D01*
G01X1836437Y151406D02*
X1833559Y148528D01*
G01X1804293Y132405D02*
X1802031Y134667D01*
G01X1815011Y132405D02*
X1804293D01*
G01X1815883Y133277D02*
X1815011Y132405D01*
G01X1823983Y135830D02*
X1821691Y138122D01*
G01X1836396Y135830D02*
X1823983D01*
G01X1833647Y158822D02*
X1827738D01*
G01X1838888Y164063D02*
X1833647Y158822D01*
G01X1811478Y161544D02*
X1809460Y159526D01*
G01X1811478Y165824D02*
Y161544D01*
G01X1815146Y169492D02*
X1811478Y165824D01*
G01X1816125Y169492D02*
X1815146D01*
G01X1825298Y177998D02*
X1824200Y176900D01*
G01X1825298Y181050D02*
Y177998D01*
G01X1831275Y187027D02*
X1825298Y181050D01*
G01X1853227Y187027D02*
X1831275D01*
G01X1834731Y156728D02*
X1828338D01*
G01X1837160Y159157D02*
X1834731Y156728D01*
G01X1834253Y157880D02*
X1827860D01*
G01X1836682Y160309D02*
X1834253Y157880D01*
G01X1833446Y183941D02*
X1851912D01*
G01X1829884Y180379D02*
X1833446Y183941D01*
G01X1829884Y175061D02*
Y180379D01*
G01X1821048Y166225D02*
X1829884Y175061D01*
G01X1816707Y166225D02*
X1821048D01*
G01X1813892Y163410D02*
X1816707Y166225D01*
G01X1813892Y162119D02*
Y163410D01*
G01X1809584Y157811D02*
X1813892Y162119D01*
G01X1779428Y157811D02*
X1809584D01*
G01X1804904Y156559D02*
X1795700D01*
G01X1825940Y166919D02*
Y158088D01*
G01X1829828Y170807D02*
X1825940Y166919D01*
G01X1833629Y170807D02*
X1829828D01*
G01X1802246Y240876D02*
X1840953D01*
G01X1796470Y235100D02*
X1802246Y240876D01*
G01X1793600Y235100D02*
X1796470D01*
G01X1849552Y242661D02*
X1829644Y262569D01*
G01X1844132Y250432D02*
X1830743Y263821D01*
G01X1795500Y232500D02*
X1793700D01*
G01X1803103Y240103D02*
X1795500Y232500D01*
G01X1839497Y240103D02*
X1803103D01*
G01X1807591Y228300D02*
X1844836D01*
G01X1803280Y232611D02*
X1807591Y228300D01*
G01X1799654Y234006D02*
X1793948Y228300D01*
G01X1801885Y234006D02*
X1799654D01*
G01X1803280Y232611D02*
X1801885Y234006D01*
G01X1809415Y229252D02*
X1845231D01*
G01X1806083Y232584D02*
X1809415Y229252D01*
G01X1799015Y234758D02*
X1793509Y229252D01*
G01X1803909Y234758D02*
X1799015D01*
G01X1806083Y232584D02*
X1803909Y234758D01*
G01X1827000Y452200D02*
X1825704Y453496D01*
G01X1827000Y449471D02*
Y452200D01*
G01X1829777Y446694D02*
X1827000Y449471D01*
G01X1843424Y446694D02*
X1829777D01*
G01X1803900Y526800D02*
X1804500Y526200D01*
G01X1806100D02*
X1810080Y530180D01*
G01X1804500Y526200D02*
X1806100D01*
G01X1825100Y501100D02*
X1820400D01*
G01X1828300Y504300D02*
X1825100Y501100D01*
G01X1839250Y504300D02*
X1828300D01*
G01X1822700Y525700D02*
X1816800D01*
G01X1827800Y530800D02*
X1822700Y525700D01*
G01X1796600Y526800D02*
X1803900D01*
G01X1795400Y528000D02*
X1796600Y526800D01*
G01X1785700Y528000D02*
X1795400D01*
G01X1779200Y534500D02*
X1785700Y528000D01*
G01X1828485Y535800D02*
X1829000Y536315D01*
G01X1817200Y535800D02*
X1828485D01*
G01X1811580Y530180D02*
X1817200Y535800D01*
G01X1810080Y530180D02*
X1811580D01*
G01X1833776Y569880D02*
X1842120D01*
G01X1830756Y572900D02*
X1833776Y569880D01*
G01X1829300Y572900D02*
X1830756D01*
G01X1815907Y587480D02*
X1816458D01*
G01X1814149Y589238D02*
X1815907Y587480D01*
G01X1823116Y532500D02*
X1818509Y527893D01*
G01X1827800Y532500D02*
X1823116D01*
G01X1831100Y535800D02*
X1827800Y532500D01*
G01X1831100Y537400D02*
Y535800D01*
G01X1830000Y538500D02*
X1831100Y537400D01*
G01X1817200Y538500D02*
X1830000D01*
G01X1814400Y535700D02*
X1817200Y538500D01*
G01X1782900Y535700D02*
X1814400D01*
G01X1782000Y534800D02*
X1782900Y535700D01*
G01X1780530Y534800D02*
X1782000D01*
G01X1779678Y535652D02*
X1780530Y534800D01*
G01X1809067Y580821D02*
X1836035D01*
G01X1793170Y564924D02*
X1809067Y580821D01*
G01X1784643Y564924D02*
X1793170D01*
G01X1781174Y561455D02*
X1784643Y564924D01*
G01X1780845Y561455D02*
X1781174D01*
G01X1780394Y561004D02*
X1780845Y561455D01*
G01X1780394Y561076D02*
Y561004D01*
G01X1836744Y530800D02*
X1827800D01*
G01X1792170Y583900D02*
X1784140Y591930D01*
G01X1793492Y589238D02*
X1814149D01*
G01X1786881Y595849D02*
X1793492Y589238D01*
G01X1798100Y599000D02*
X1792600Y604500D01*
G01X1820363Y599000D02*
X1798100D01*
G01X1825573Y604210D02*
X1820363Y599000D01*
G01X1840139Y604210D02*
X1825573D01*
G01X1781512Y591930D02*
X1779003Y594439D01*
G01X1784140Y591930D02*
X1781512D01*
G01X1877022Y31812D02*
X1875206Y33628D01*
G01X1877022Y27339D02*
Y31812D01*
G01X1873208Y23525D02*
X1877022Y27339D01*
G01X1873208Y21999D02*
Y23525D01*
G01X1867433Y16224D02*
X1873208Y21999D01*
G01X1866886Y16224D02*
X1867433D01*
G01X1858796Y8134D02*
X1866886Y16224D01*
G01X1852174Y8134D02*
X1858796D01*
G01X1851270Y7230D02*
X1852174Y8134D01*
G01X1848957Y7230D02*
X1851270D01*
G01X1839600Y-2127D02*
X1848957Y7230D01*
G01X1839600Y-16000D02*
Y-2127D01*
G01X1836700Y-18900D02*
X1839600Y-16000D01*
G01X1847800Y9900D02*
X1844600Y6700D01*
G01X1848800Y9900D02*
X1847800D01*
G01X1848814Y9886D02*
X1848800Y9900D01*
G01X1850168Y9886D02*
X1848814D01*
G01X1851072Y10790D02*
X1850168Y9886D01*
G01X1857694Y10790D02*
X1851072D01*
G01X1865784Y18880D02*
X1857694Y10790D01*
G01X1866331Y18880D02*
X1865784D01*
G01X1868278Y20827D02*
X1866331Y18880D01*
G01X1868278Y23173D02*
Y20827D01*
G01X1867265Y24186D02*
X1868278Y23173D01*
G01X1867265Y32005D02*
Y24186D01*
G01X1872550Y37290D02*
X1867265Y32005D01*
G01X1838910Y24010D02*
X1841289Y21631D01*
G01X1843426Y11674D02*
X1837801Y17299D01*
G01X1843426Y9528D02*
Y11674D01*
G01X1835600Y3900D02*
Y1864D01*
G01X1841446Y783D02*
X1835583D01*
G01X1848645Y7982D02*
X1841446Y783D01*
G01X1850958Y7982D02*
X1848645D01*
G01X1851862Y8886D02*
X1850958Y7982D01*
G01X1858484Y8886D02*
X1851862D01*
G01X1866574Y16976D02*
X1858484Y8886D01*
G01X1867121Y16976D02*
X1866574D01*
G01X1872456Y22311D02*
X1867121Y16976D01*
G01X1872456Y23837D02*
Y22311D01*
G01X1876270Y27651D02*
X1872456Y23837D01*
G01X1876270Y31500D02*
Y27651D01*
G01X1874454Y33316D02*
X1876270Y31500D01*
G01X1844613Y32490D02*
X1842921Y30798D01*
G01X1851680Y32490D02*
X1844613D01*
G01X1852380Y31790D02*
X1851680Y32490D01*
G01X1860420Y31790D02*
X1852380D01*
G01X1865102Y36472D02*
X1860420Y31790D01*
G01X1844684Y34435D02*
X1842801Y32552D01*
G01X1866113Y32593D02*
X1871398Y37878D01*
G01X1866113Y23708D02*
Y32593D01*
G01X1867126Y22695D02*
X1866113Y23708D01*
G01X1867126Y21305D02*
Y22695D01*
G01X1865853Y20032D02*
X1867126Y21305D01*
G01X1865306Y20032D02*
X1865853D01*
G01X1857216Y11942D02*
X1865306Y20032D01*
G01X1850594Y11942D02*
X1857216D01*
G01X1849752Y11100D02*
X1850594Y11942D01*
G01X1847300Y11100D02*
X1849752D01*
G01X1844100Y7900D02*
X1847300Y11100D01*
G01X1837900Y9700D02*
X1837000Y8800D01*
G01X1868417Y31527D02*
X1873702Y36812D01*
G01X1868417Y24664D02*
Y31527D01*
G01X1869430Y23651D02*
X1868417Y24664D01*
G01X1869430Y20349D02*
Y23651D01*
G01X1866809Y17728D02*
X1869430Y20349D01*
G01X1866262Y17728D02*
X1866809D01*
G01X1858172Y9638D02*
X1866262Y17728D01*
G01X1851550Y9638D02*
X1858172D01*
G01X1850646Y8734D02*
X1851550Y9638D01*
G01X1848333Y8734D02*
X1850646D01*
G01X1845099Y5500D02*
X1848333Y8734D01*
G01X1848322Y13579D02*
Y12723D01*
G01X1842865Y19036D02*
X1848322Y13579D01*
G01X1842865Y22284D02*
Y19036D01*
G01X1840187Y24962D02*
X1842865Y22284D01*
G01X1839300Y37300D02*
X1841060Y35540D01*
G01X1874589Y73283D02*
Y99490D01*
G01X1870360Y69054D02*
X1874589Y73283D01*
G01X1870360Y50322D02*
Y69054D01*
G01X1875207Y45475D02*
X1870360Y50322D01*
G01X1875207Y41361D02*
Y45475D01*
G01X1875206Y41360D02*
X1875207Y41361D01*
G01X1875206Y33628D02*
Y41360D01*
G01X1872550Y44374D02*
Y37290D01*
G01X1867704Y49220D02*
X1872550Y44374D01*
G01X1867704Y70460D02*
Y49220D01*
G01X1870279Y73035D02*
X1867704Y70460D01*
G01X1870279Y99327D02*
Y73035D01*
G01X1867619Y40913D02*
Y39779D01*
G01X1865854Y42678D02*
X1867619Y40913D01*
G01X1865854Y44140D02*
Y42678D01*
G01X1855070Y54924D02*
X1865854Y44140D01*
G01X1847347Y54924D02*
X1855070D01*
G01X1843067Y59204D02*
X1847347Y54924D01*
G01X1847442Y36011D02*
X1849027Y34426D01*
G01X1844630Y36011D02*
X1847442D01*
G01X1842323Y33704D02*
X1844630Y36011D01*
G01X1874454Y41672D02*
Y33316D01*
G01X1874455Y41673D02*
X1874454Y41672D01*
G01X1874455Y45163D02*
Y41673D01*
G01X1869608Y50010D02*
X1874455Y45163D01*
G01X1869608Y69366D02*
Y50010D01*
G01X1873289Y73047D02*
X1869608Y69366D01*
G01X1873289Y99437D02*
Y73047D01*
G01X1865102Y43828D02*
Y36472D01*
G01X1854758Y54172D02*
X1865102Y43828D01*
G01X1847035Y54172D02*
X1854758D01*
G01X1842755Y58452D02*
X1847035Y54172D01*
G01X1842879Y41348D02*
X1850600D01*
G01X1837907Y46320D02*
X1842879Y41348D01*
G01X1846527Y34435D02*
X1844684D01*
G01X1843853Y43701D02*
X1838882Y48672D01*
G01X1850759Y43701D02*
X1843853D01*
G01X1852850Y41610D02*
X1850759Y43701D01*
G01X1852850Y37477D02*
Y41610D01*
G01X1853467Y36860D02*
X1852850Y37477D01*
G01X1853467Y35000D02*
Y36860D01*
G01X1869127Y73513D02*
Y98848D01*
G01X1866552Y70938D02*
X1869127Y73513D01*
G01X1866552Y48742D02*
Y70938D01*
G01X1871398Y43896D02*
X1866552Y48742D01*
G01X1871398Y37878D02*
Y43896D01*
G01X1860786Y43492D02*
Y41200D01*
G01X1853275Y51003D02*
X1860786Y43492D01*
G01X1843205Y51003D02*
X1853275D01*
G01X1839808Y54400D02*
X1843205Y51003D01*
G01X1860098Y39208D02*
X1858198Y41108D01*
G01X1861308Y39208D02*
X1860098D01*
G01X1862600Y40500D02*
X1861308Y39208D01*
G01X1862600Y43000D02*
Y40500D01*
G01X1853732Y51868D02*
X1862600Y43000D01*
G01X1843404Y51868D02*
X1853732D01*
G01X1839472Y55800D02*
X1843404Y51868D01*
G01X1855400Y42400D02*
Y40800D01*
G01X1851747Y46053D02*
X1855400Y42400D01*
G01X1844828Y46053D02*
X1851747D01*
G01X1839857Y51024D02*
X1844828Y46053D01*
G01X1871939Y72761D02*
Y99723D01*
G01X1868856Y69678D02*
X1871939Y72761D01*
G01X1868856Y49698D02*
Y69678D01*
G01X1873703Y44851D02*
X1868856Y49698D01*
G01X1873703Y41985D02*
Y44851D01*
G01X1873702Y41984D02*
X1873703Y41985D01*
G01X1873702Y36812D02*
Y41984D01*
G01X1886081Y151431D02*
X1886050D01*
G01X1882698Y148048D02*
X1886081Y151431D01*
G01X1882698Y133027D02*
Y148048D01*
G01X1878780Y129109D02*
X1882698Y133027D01*
G01X1878780Y113683D02*
Y129109D01*
G01X1878102Y113005D02*
X1878780Y113683D01*
G01X1878102Y104652D02*
Y113005D01*
G01X1875985Y102535D02*
X1878102Y104652D01*
G01X1875985Y100886D02*
Y102535D01*
G01X1874589Y99490D02*
X1875985Y100886D01*
G01X1839667Y149637D02*
Y151994D01*
G01X1837606Y147576D02*
X1839667Y149637D01*
G01X1868026Y101580D02*
X1870279Y99327D01*
G01X1868026Y107528D02*
Y101580D01*
G01X1874074Y113576D02*
X1868026Y107528D01*
G01X1874074Y131074D02*
Y113576D01*
G01X1877105Y134105D02*
X1874074Y131074D01*
G01X1877105Y148027D02*
Y134105D01*
G01X1879672Y150594D02*
X1877105Y148027D01*
G01X1879672Y153496D02*
Y150594D01*
G01X1878568Y154600D02*
X1879672Y153496D01*
G01X1876101Y154600D02*
X1878568D01*
G01X1875600Y155101D02*
X1876101Y154600D01*
G01X1875600Y156300D02*
Y155101D01*
G01X1851848Y129352D02*
X1851100Y130100D01*
G01X1855070Y129352D02*
X1851848D01*
G01X1855444Y129726D02*
X1855070Y129352D01*
G01X1855444Y130272D02*
Y129726D01*
G01X1856367Y131195D02*
X1855444Y130272D01*
G01X1856389Y131195D02*
X1856367D01*
G01X1857033Y131839D02*
X1856389Y131195D01*
G01X1857033Y131861D02*
Y131839D01*
G01X1857290Y132118D02*
X1857033Y131861D01*
G01X1857290Y135011D02*
Y132118D01*
G01X1859603Y137324D02*
X1857290Y135011D01*
G01X1859603Y148748D02*
Y137324D01*
G01X1854115Y154236D02*
X1859603Y148748D01*
G01X1849971Y154236D02*
X1854115D01*
G01X1848436Y155771D02*
X1849971Y154236D01*
G01X1848436Y159278D02*
Y155771D01*
G01X1854993Y133613D02*
X1854962D01*
G01X1854763Y133383D02*
X1854993Y133613D01*
G01X1853924Y133383D02*
X1854763D01*
G01X1853374Y132833D02*
X1853924Y133383D01*
G01X1858671Y134071D02*
X1860969Y136369D01*
G01X1858671Y123471D02*
Y134071D01*
G01X1855627Y101915D02*
X1843289D01*
G01X1871308Y117596D02*
X1855627Y101915D01*
G01X1871308Y127420D02*
Y117596D01*
G01X1871310Y127422D02*
X1871308Y127420D01*
G01X1871310Y134126D02*
Y127422D01*
G01X1874601Y137417D02*
X1871310Y134126D01*
G01X1874601Y147962D02*
Y137417D01*
G01X1873097Y149466D02*
X1874601Y147962D01*
G01X1873097Y157236D02*
Y149466D01*
G01X1871800Y155500D02*
X1870676Y156624D01*
G01X1871800Y153872D02*
Y155500D01*
G01X1871521Y153593D02*
X1871800Y153872D01*
G01X1854169Y151759D02*
X1857849Y148079D01*
G01X1850478Y151759D02*
X1854169D01*
G01X1850464Y151773D02*
X1850478Y151759D01*
G01X1849676Y151773D02*
X1850464D01*
G01X1849675Y151772D02*
X1849676Y151773D01*
G01X1844883Y151772D02*
X1849675D01*
G01X1841532Y155123D02*
X1844883Y151772D01*
G01X1869952Y102774D02*
X1873289Y99437D01*
G01X1869952Y106488D02*
Y102774D01*
G01X1878028Y114564D02*
X1869952Y106488D01*
G01X1878028Y130114D02*
Y114564D01*
G01X1881754Y133840D02*
X1878028Y130114D01*
G01X1881754Y149982D02*
Y133840D01*
G01X1883652Y151880D02*
X1881754Y149982D01*
G01X1883652Y164649D02*
Y151880D01*
G01X1859423Y132223D02*
X1860969Y133769D01*
G01X1859423Y123081D02*
Y132223D01*
G01X1855448Y102800D02*
X1842334D01*
G01X1870556Y117908D02*
X1855448Y102800D01*
G01X1870556Y127732D02*
Y117908D01*
G01X1870558Y127734D02*
X1870556Y127732D01*
G01X1870558Y129644D02*
Y127734D01*
G01X1870557Y129645D02*
X1870558Y129644D01*
G01X1870557Y130267D02*
Y129645D01*
G01X1868856Y131968D02*
X1870557Y130267D01*
G01X1868856Y145044D02*
Y131968D01*
G01X1865208Y148692D02*
X1868856Y145044D01*
G01X1865208Y150899D02*
Y148692D01*
G01X1859372Y156735D02*
X1865208Y150899D01*
G01X1873849Y150150D02*
Y156924D01*
G01X1875680Y148319D02*
X1873849Y150150D01*
G01X1875680Y134753D02*
Y148319D01*
G01X1872922Y131995D02*
X1875680Y134753D01*
G01X1872922Y114054D02*
Y131995D01*
G01X1866874Y108006D02*
X1872922Y114054D01*
G01X1866874Y101102D02*
Y108006D01*
G01X1867170Y100806D02*
X1866874Y101102D01*
G01X1867170Y100805D02*
Y100806D01*
G01X1869127Y98848D02*
X1867170Y100805D01*
G01X1866600Y120300D02*
X1857706D01*
G01X1867500Y121200D02*
X1866600Y120300D01*
G01X1867500Y129000D02*
Y121200D01*
G01X1864373Y132127D02*
X1867500Y129000D01*
G01X1864373Y137480D02*
Y132127D01*
G01X1865902Y139009D02*
X1864373Y137480D01*
G01X1865902Y144847D02*
Y139009D01*
G01X1855217Y155532D02*
X1865902Y144847D01*
G01X1853836Y155532D02*
X1855217D01*
G01X1850048Y159320D02*
X1853836Y155532D01*
G01X1866288Y119548D02*
X1858018D01*
G01X1866289Y119547D02*
X1866288Y119548D01*
G01X1866911Y119547D02*
X1866289D01*
G01X1868252Y120888D02*
X1866911Y119547D01*
G01X1868252Y128688D02*
Y120888D01*
G01X1868253Y128689D02*
X1868252Y128688D01*
G01X1868253Y129311D02*
Y128689D01*
G01X1865595Y131969D02*
X1868253Y129311D01*
G01X1865595Y136899D02*
Y131969D01*
G01X1866696Y138000D02*
X1865595Y136899D01*
G01X1866696Y145117D02*
Y138000D01*
G01X1855529Y156284D02*
X1866696Y145117D01*
G01X1836553Y151406D02*
X1836437D01*
G01X1838927Y153780D02*
X1836553Y151406D01*
G01X1841260Y153780D02*
X1838927D01*
G01X1844220Y150820D02*
X1841260Y153780D01*
G01X1850070Y150820D02*
X1844220D01*
G01X1852020Y148870D02*
X1850070Y150820D01*
G01X1852020Y137570D02*
Y148870D01*
G01X1854140Y135450D02*
X1852020Y137570D01*
G01X1855430Y135450D02*
X1854140D01*
G01X1856538Y134342D02*
X1855430Y135450D01*
G01X1856538Y132430D02*
Y134342D01*
G01X1855229Y131121D02*
X1856538Y132430D01*
G01X1854115Y131121D02*
X1855229D01*
G01X1882900Y152192D02*
Y164337D01*
G01X1878770Y148062D02*
X1882900Y152192D01*
G01X1878770Y143187D02*
Y148062D01*
G01X1880705Y141252D02*
X1878770Y143187D01*
G01X1880705Y135951D02*
Y141252D01*
G01X1877276Y132522D02*
X1880705Y135951D01*
G01X1877276Y114876D02*
Y132522D01*
G01X1869200Y106800D02*
X1877276Y114876D01*
G01X1869200Y102462D02*
Y106800D01*
G01X1871939Y99723D02*
X1869200Y102462D01*
G01X1838230Y137664D02*
X1836396Y135830D01*
G01X1846925Y137664D02*
X1838230D01*
G01X1848100Y136489D02*
X1846925Y137664D01*
G01X1848100Y134750D02*
Y136489D01*
G01X1893110Y216368D02*
X1895589Y218847D01*
G01X1886732Y216368D02*
X1893110D01*
G01X1883800Y213436D02*
X1886732Y216368D01*
G01X1838888Y168514D02*
Y164063D01*
G01X1836916Y170486D02*
X1838888Y168514D01*
G01X1836932Y170486D02*
X1836916D01*
G01X1871926Y217514D02*
X1878512Y224100D01*
G01X1862056Y217514D02*
X1871926D01*
G01X1845947Y233623D02*
X1862056Y217514D01*
G01X1844000Y163714D02*
X1848436Y159278D01*
G01X1844000Y169500D02*
Y163714D01*
G01X1853035Y178535D02*
X1844000Y169500D01*
G01X1859106Y178535D02*
X1853035D01*
G01X1860276Y179705D02*
X1859106Y178535D01*
G01X1860276Y181838D02*
Y179705D01*
G01X1859667Y182447D02*
X1860276Y181838D01*
G01X1859667Y183753D02*
Y182447D01*
G01X1860276Y184362D02*
X1859667Y183753D01*
G01X1860276Y185045D02*
Y184362D01*
G01X1863650Y188419D02*
X1860276Y185045D01*
G01X1863650Y189750D02*
Y188419D01*
G01X1873435Y157574D02*
X1873097Y157236D01*
G01X1873435Y171465D02*
Y157574D01*
G01X1870500Y174400D02*
X1873435Y171465D01*
G01X1870500Y182893D02*
Y174400D01*
G01X1877844Y190237D02*
X1870500Y182893D01*
G01X1877844Y201454D02*
Y190237D01*
G01X1882009Y205619D02*
X1877844Y201454D01*
G01X1882009Y215535D02*
Y205619D01*
G01X1884340Y217866D02*
X1882009Y215535D01*
G01X1890786Y197830D02*
X1902327D01*
G01X1875135Y175801D02*
X1876657D01*
G01X1875110Y175826D02*
X1875135Y175801D01*
G01X1875110Y175782D02*
Y175826D01*
G01X1875066Y175782D02*
X1875110D01*
G01X1855016Y188816D02*
X1853227Y187027D01*
G01X1855016Y188820D02*
Y188816D01*
G01X1856880Y190684D02*
X1855016Y188820D01*
G01X1856884Y190684D02*
X1856880D01*
G01X1862824Y196624D02*
X1856884Y190684D01*
G01X1862824Y203317D02*
Y196624D01*
G01X1865352Y205845D02*
X1862824Y203317D01*
G01X1865352Y205854D02*
Y205845D01*
G01X1865659Y206161D02*
X1865352Y205854D01*
G01X1865659Y209240D02*
Y206161D01*
G01X1867704Y211285D02*
X1865659Y209240D01*
G01X1871113Y211285D02*
X1867704D01*
G01X1871649Y211821D02*
X1871113Y211285D01*
G01X1871708Y211821D02*
X1871649D01*
G01X1871753Y211866D02*
X1871708Y211821D01*
G01X1872361Y211866D02*
X1871753D01*
G01X1873284Y212789D02*
X1872361Y211866D01*
G01X1873284Y213456D02*
Y212789D01*
G01X1873628Y213800D02*
X1873284Y213456D01*
G01X1874236Y213800D02*
X1873628D01*
G01X1839672Y159157D02*
X1837160D01*
G01X1839873Y159358D02*
X1839672Y159157D01*
G01X1880600Y209039D02*
Y218142D01*
G01X1876256Y204695D02*
X1880600Y209039D01*
G01X1876256Y190641D02*
Y204695D01*
G01X1868822Y183207D02*
X1876256Y190641D01*
G01X1868822Y174322D02*
Y183207D01*
G01X1868100Y173600D02*
X1868822Y174322D01*
G01X1866329Y173600D02*
X1868100D01*
G01X1865753Y173024D02*
X1866329Y173600D01*
G01X1865724Y173024D02*
X1865753D01*
G01X1864620Y171920D02*
X1865724Y173024D01*
G01X1861598Y171920D02*
X1864620D01*
G01X1860624Y170946D02*
X1861598Y171920D01*
G01X1860624Y157254D02*
Y170946D01*
G01X1861254Y156624D02*
X1860624Y157254D01*
G01X1870676Y156624D02*
X1861254D01*
G01X1873334Y174967D02*
X1883652Y164649D01*
G01X1873334Y178605D02*
Y174967D01*
G01X1880100Y185371D02*
X1873334Y178605D01*
G01X1880100Y196005D02*
Y185371D01*
G01X1881635Y197540D02*
X1880100Y196005D01*
G01X1885195Y197540D02*
X1881635D01*
G01X1886093Y198438D02*
X1885195Y197540D01*
G01X1886093Y202184D02*
Y198438D01*
G01X1859372Y158258D02*
Y156735D01*
G01X1856300Y161330D02*
X1859372Y158258D01*
G01X1856300Y166200D02*
Y161330D01*
G01X1859372Y169272D02*
X1856300Y166200D01*
G01X1859372Y171465D02*
Y169272D01*
G01X1864424Y176517D02*
X1859372Y171465D01*
G01X1864424Y180801D02*
Y176517D01*
G01X1874848Y191225D02*
X1864424Y180801D01*
G01X1874848Y208060D02*
Y191225D01*
G01X1878266Y211478D02*
X1874848Y208060D01*
G01X1878266Y213140D02*
Y211478D01*
G01X1878789Y213663D02*
X1878266Y213140D01*
G01X1891378Y197078D02*
X1901622D01*
G01X1839944Y156858D02*
X1839941D01*
G01X1842770Y159684D02*
X1839944Y156858D01*
G01X1842770Y169628D02*
Y159684D01*
G01X1852937Y179795D02*
X1842770Y169628D01*
G01X1855311Y179795D02*
X1852937D01*
G01X1856324Y180808D02*
X1855311Y179795D01*
G01X1856324Y180853D02*
Y180808D01*
G01X1858547Y183076D02*
X1856324Y180853D01*
G01X1858547Y185087D02*
Y183076D01*
G01X1861437Y187977D02*
X1858547Y185087D01*
G01X1861437Y191082D02*
Y187977D01*
G01X1869782Y199427D02*
X1861437Y191082D01*
G01X1869782Y206981D02*
Y199427D01*
G01X1868843Y207920D02*
X1869782Y206981D01*
G01X1883800Y206320D02*
Y210575D01*
G01X1878596Y201116D02*
X1883800Y206320D01*
G01X1878596Y189925D02*
Y201116D01*
G01X1871830Y183159D02*
X1878596Y189925D01*
G01X1871830Y174270D02*
Y183159D01*
G01X1874187Y171913D02*
X1871830Y174270D01*
G01X1874187Y157262D02*
Y171913D01*
G01X1873849Y156924D02*
X1874187Y157262D01*
G01X1836691Y160309D02*
X1836682D01*
G01X1841273Y164891D02*
X1836691Y160309D01*
G01X1841273Y170607D02*
Y164891D01*
G01X1852321Y181655D02*
X1841273Y170607D01*
G01X1854942Y181655D02*
X1852321D01*
G01X1849900Y191100D02*
X1847700Y193300D01*
G01X1855657Y191100D02*
X1849900D01*
G01X1862072Y197515D02*
X1855657Y191100D01*
G01X1862072Y199982D02*
Y197515D01*
G01X1862071Y199983D02*
X1862072Y199982D01*
G01X1862071Y200605D02*
Y199983D01*
G01X1862072Y200606D02*
X1862071Y200605D01*
G01X1862072Y203629D02*
Y200606D01*
G01X1864600Y206157D02*
X1862072Y203629D01*
G01X1864600Y209245D02*
Y206157D01*
G01X1867392Y212037D02*
X1864600Y209245D01*
G01X1867797Y212037D02*
X1867392D01*
G01X1878284Y222524D02*
X1867797Y212037D01*
G01X1879347Y216846D02*
Y218660D01*
G01X1875862Y213361D02*
X1879347Y216846D01*
G01X1875862Y213197D02*
Y213361D01*
G01X1872665Y210000D02*
X1875862Y213197D01*
G01X1868524Y210000D02*
X1872665D01*
G01X1867267Y208743D02*
X1868524Y210000D01*
G01X1867267Y199038D02*
Y208743D01*
G01X1854472Y186243D02*
X1867267Y199038D01*
G01X1854214Y186243D02*
X1854472D01*
G01X1851912Y183941D02*
X1854214Y186243D01*
G01X1850048Y167342D02*
Y159320D01*
G01X1857400Y174694D02*
X1850048Y167342D01*
G01X1857400Y175900D02*
Y174694D01*
G01X1855670Y207542D02*
Y206430D01*
G01X1852800Y210412D02*
X1855670Y207542D01*
G01X1852800Y220336D02*
Y210412D01*
G01X1854148Y156284D02*
X1855529D01*
G01X1850800Y159632D02*
X1854148Y156284D01*
G01X1850800Y167030D02*
Y159632D01*
G01X1859670Y175900D02*
X1850800Y167030D01*
G01X1860900Y175900D02*
X1859670D01*
G01X1862000Y177000D02*
X1860900Y175900D01*
G01X1862000Y177500D02*
Y177000D01*
G01X1888224Y213125D02*
X1886952D01*
G01X1888576Y212773D02*
X1888224Y213125D01*
G01X1888576Y210007D02*
Y212773D01*
G01X1879348Y200779D02*
X1888576Y210007D01*
G01X1879348Y185683D02*
Y200779D01*
G01X1872582Y178917D02*
X1879348Y185683D01*
G01X1872582Y174655D02*
Y178917D01*
G01X1882900Y164337D02*
X1872582Y174655D01*
G01X1858224Y206335D02*
X1858470D01*
G01X1853752Y210807D02*
X1858224Y206335D01*
G01X1853752Y220731D02*
Y210807D01*
G01X1854374Y230597D02*
Y248790D01*
G01X1862307Y222664D02*
X1854374Y230597D01*
G01X1871875Y222664D02*
X1862307D01*
G01X1877534Y228323D02*
X1871875Y222664D01*
G01X1877534Y235816D02*
Y228323D01*
G01X1879901Y238183D02*
X1877534Y235816D01*
G01X1902959Y238183D02*
X1879901D01*
G01X1895589Y218847D02*
X1905318D01*
G01X1842829Y239000D02*
X1843600D01*
G01X1840953Y240876D02*
X1842829Y239000D01*
G01X1878512Y224100D02*
X1881900D01*
G01X1845947Y244495D02*
Y233623D01*
G01X1835640Y254802D02*
X1845947Y244495D01*
G01X1849552Y241019D02*
Y242661D01*
G01X1849553Y241018D02*
X1849552Y241019D01*
G01X1849553Y239982D02*
Y241018D01*
G01X1849552Y239981D02*
X1849553Y239982D01*
G01X1849552Y233648D02*
Y239981D01*
G01X1861788Y221412D02*
X1849552Y233648D01*
G01X1872394Y221412D02*
X1861788D01*
G01X1877682Y226700D02*
X1872394Y221412D01*
G01X1879729Y226700D02*
X1877682D01*
G01X1885421Y232392D02*
X1879729Y226700D01*
G01X1899626Y232392D02*
X1885421D01*
G01X1895071Y220100D02*
X1904800D01*
G01X1894889Y219918D02*
X1895071Y220100D01*
G01X1882376Y219918D02*
X1894889D01*
G01X1880600Y218142D02*
X1882376Y219918D01*
G01X1851639Y250432D02*
X1844132D01*
G01X1851647Y250424D02*
X1851639Y250432D01*
G01X1852953Y250424D02*
X1851647D01*
G01X1852961Y250432D02*
X1852953Y250424D01*
G01X1855533Y250432D02*
X1852961D01*
G01X1856564Y249401D02*
X1855533Y250432D01*
G01X1856564Y229916D02*
Y249401D01*
G01X1862864Y223616D02*
X1856564Y229916D01*
G01X1871480Y223616D02*
X1862864D01*
G01X1876582Y228718D02*
X1871480Y223616D01*
G01X1876582Y236211D02*
Y228718D01*
G01X1879506Y239135D02*
X1876582Y236211D01*
G01X1903805Y239135D02*
X1879506D01*
G01X1840300Y239300D02*
X1839497Y240103D01*
G01X1892182Y222524D02*
X1878284D01*
G01X1894558Y224900D02*
X1892182Y222524D01*
G01X1899600Y224900D02*
X1894558D01*
G01X1894982Y223553D02*
X1900797D01*
G01X1892663Y221234D02*
X1894982Y223553D01*
G01X1882163Y221234D02*
X1892663D01*
G01X1882099Y221170D02*
X1882163Y221234D01*
G01X1881857Y221170D02*
X1882099D01*
G01X1879347Y218660D02*
X1881857Y221170D01*
G01X1844836Y228300D02*
X1852800Y220336D01*
G01X1881936Y242402D02*
X1903609D01*
G01X1868838Y255500D02*
X1881936Y242402D01*
G01X1863180Y255500D02*
X1868838D01*
G01X1861605Y253925D02*
X1863180Y255500D01*
G01X1881458Y241250D02*
X1903037D01*
G01X1868360Y254348D02*
X1881458Y241250D01*
G01X1864828Y254348D02*
X1868360D01*
G01X1864305Y253825D02*
X1864828Y254348D01*
G01X1845231Y229252D02*
X1853752Y220731D01*
G01X1864426Y449476D02*
X1866050Y451100D01*
G01X1863647Y449476D02*
X1864426D01*
G01X1855361Y441190D02*
X1863647Y449476D01*
G01X1838115Y452544D02*
X1836011Y454648D01*
G01X1839525Y452544D02*
X1838115D01*
G01X1840875Y451194D02*
X1839525Y452544D01*
G01X1847944Y451194D02*
X1840875D01*
G01X1851620Y454870D02*
X1847944Y451194D01*
G01X1851620Y470080D02*
Y454870D01*
G01X1857468Y452803D02*
X1847551Y442886D01*
G01X1858633Y452803D02*
X1857468D01*
G01X1869116Y447287D02*
X1861833Y440004D01*
G01X1869116Y451323D02*
Y447287D01*
G01X1870815Y453022D02*
X1869116Y451323D01*
G01X1853805Y448076D02*
X1847799Y442070D01*
G01X1859059Y448076D02*
X1853805D01*
G01X1876945Y462567D02*
Y471316D01*
G01X1880076Y459436D02*
X1876945Y462567D01*
G01X1880076Y446249D02*
Y459436D01*
G01X1868732Y434905D02*
X1880076Y446249D01*
G01X1861468Y454379D02*
X1863137Y452710D01*
G01X1857980Y454379D02*
X1861468D01*
G01X1847239Y443638D02*
X1857980Y454379D01*
G01X1883717Y458721D02*
Y482683D01*
G01X1884353Y458085D02*
X1883717Y458721D01*
G01X1884353Y443547D02*
Y458085D01*
G01X1887400Y440500D02*
X1884353Y443547D01*
G01X1942000Y440500D02*
X1887400D01*
G01X1856558Y456548D02*
X1845552Y445542D01*
G01X1871965Y456548D02*
X1856558D01*
G01X1873615Y454898D02*
X1871965Y456548D01*
G01X1873615Y451305D02*
Y454898D01*
G01X1872860Y450550D02*
X1873615Y451305D01*
G01X1846772Y450042D02*
X1843424Y446694D01*
G01X1848422Y450042D02*
X1846772D01*
G01X1852772Y454392D02*
X1848422Y450042D01*
G01X1852772Y456042D02*
Y454392D01*
G01X1854020Y457290D02*
X1852772Y456042D01*
G01X1854020Y466520D02*
Y457290D01*
G01X1856953Y455596D02*
X1846147Y444790D01*
G01X1871570Y455596D02*
X1856953D01*
G01X1872500Y454666D02*
X1871570Y455596D01*
G01X1872500Y452449D02*
Y454666D01*
G01X1871230Y451179D02*
X1872500Y452449D01*
G01X1871230Y449580D02*
Y451179D01*
G01X1872860Y447950D02*
X1871230Y449580D01*
G01X1855227Y473687D02*
X1851620Y470080D01*
G01X1855227Y481597D02*
Y473687D01*
G01X1867196Y493566D02*
X1855227Y481597D01*
G01X1867196Y502864D02*
Y493566D01*
G01X1847383Y522677D02*
X1867196Y502864D01*
G01X1847383Y533662D02*
Y522677D01*
G01X1856220Y521630D02*
Y530630D01*
G01X1859490Y518360D02*
X1856220Y521630D01*
G01X1861870Y518360D02*
X1859490D01*
G01X1871800Y508430D02*
X1861870Y518360D01*
G01X1871800Y494600D02*
Y508430D01*
G01X1883717Y482683D02*
X1871800Y494600D01*
G01X1861850Y474350D02*
X1854020Y466520D01*
G01X1861850Y477650D02*
Y474350D01*
G01X1860800Y478700D02*
X1861850Y477650D01*
G01X1860800Y485500D02*
Y478700D01*
G01X1868348Y493048D02*
X1860800Y485500D01*
G01X1868348Y507856D02*
Y493048D01*
G01X1864808Y511396D02*
X1868348Y507856D01*
G01X1860294Y511396D02*
X1864808D01*
G01X1849474Y522216D02*
X1860294Y511396D01*
G01X1849474Y537465D02*
Y522216D01*
G01X1839250Y504320D02*
Y504300D01*
G01X1842450Y507520D02*
X1839250Y504320D01*
G01X1845475Y535570D02*
X1847383Y533662D01*
G01X1845475Y550146D02*
Y535570D01*
G01X1845676Y550347D02*
X1845475Y550146D01*
G01X1845676Y551653D02*
Y550347D01*
G01X1845475Y551854D02*
X1845676Y551653D01*
G01X1845475Y553188D02*
Y551854D01*
G01X1843966Y554697D02*
X1845475Y553188D01*
G01X1843966Y568034D02*
Y554697D01*
G01X1842120Y569880D02*
X1843966Y568034D01*
G01X1836035Y580821D02*
X1837534Y579322D01*
G01X1857326Y549890D02*
X1857108Y550108D01*
G01X1857326Y547347D02*
Y549890D01*
G01X1856924Y546945D02*
X1857326Y547347D01*
G01X1856924Y531334D02*
Y546945D01*
G01X1856220Y530630D02*
X1856924Y531334D01*
G01X1891985Y586365D02*
X1895523D01*
G01X1880015Y574395D02*
X1891985Y586365D01*
G01X1878212Y574395D02*
X1880015D01*
G01X1861062Y557245D02*
X1878212Y574395D01*
G01X1857812Y557245D02*
X1861062D01*
G01X1852938Y554900D02*
X1852400D01*
G01X1855805Y557767D02*
X1852938Y554900D01*
G01X1855805Y575766D02*
Y557767D01*
G01X1856573Y576534D02*
X1855805Y575766D01*
G01X1847117Y539822D02*
X1849474Y537465D01*
G01X1847117Y557083D02*
Y539822D01*
G01X1845118Y559082D02*
X1847117Y557083D01*
G01X1845118Y579682D02*
Y559082D01*
G01X1841446Y583354D02*
X1845118Y579682D01*
G01X1839126Y583354D02*
X1841446D01*
G01X1838750Y532806D02*
X1836744Y530800D01*
G01X1838750Y540498D02*
Y532806D01*
G01X1842510Y544258D02*
X1838750Y540498D01*
G01X1842510Y561990D02*
Y544258D01*
G01X1840700Y563800D02*
X1842510Y561990D01*
G01X1852684Y591665D02*
X1840139Y604210D01*
G01X1853095Y591665D02*
X1852684D01*
G01X1856040Y588720D02*
X1853095Y591665D01*
G01X1856040Y588704D02*
Y588720D01*
G01X1947203Y149097D02*
X1944600Y151700D01*
G01X1953600Y149097D02*
X1947203D01*
G01X1955379Y147318D02*
X1953600Y149097D01*
G01X1964382Y147318D02*
X1955379D01*
G01X1928787Y152186D02*
X1934000Y157399D01*
G01X1928787Y140545D02*
Y152186D01*
G01X1931789Y137543D02*
X1928787Y140545D01*
G01X1931789Y124960D02*
Y137543D01*
G01X1929870Y123041D02*
X1931789Y124960D01*
G01X1929870Y116140D02*
Y123041D01*
G01X1936447Y109563D02*
X1929870Y116140D01*
G01X1936447Y104505D02*
Y109563D01*
G01X1935000Y103058D02*
X1936447Y104505D01*
G01X1935000Y100203D02*
Y103058D01*
G01X1934256Y99459D02*
X1935000Y100203D01*
G01X1930900Y150229D02*
X1940047Y159376D01*
G01X1930900Y141857D02*
Y150229D01*
G01X1933893Y138864D02*
X1930900Y141857D01*
G01X1933893Y132307D02*
Y138864D01*
G01X1936300Y129900D02*
X1933893Y132307D01*
G01X1936300Y125283D02*
Y129900D01*
G01X1932998Y121981D02*
X1936300Y125283D01*
G01X1932998Y119438D02*
Y121981D01*
G01X1951593Y145300D02*
X1970824D01*
G01X1951587Y145306D02*
X1951593Y145300D01*
G01X1950281Y145306D02*
X1951587D01*
G01X1950275Y145300D02*
X1950281Y145306D01*
G01X1948493Y145300D02*
X1950275D01*
G01X1944609Y149184D02*
X1948493Y145300D01*
G01X1936152Y98278D02*
X1933914Y96040D01*
G01X1936152Y102580D02*
Y98278D01*
G01X1937599Y104027D02*
X1936152Y102580D01*
G01X1937599Y110041D02*
Y104027D01*
G01X1931022Y116618D02*
X1937599Y110041D01*
G01X1931022Y122563D02*
Y116618D01*
G01X1932941Y124482D02*
X1931022Y122563D01*
G01X1932941Y138164D02*
Y124482D01*
G01X1929939Y141166D02*
X1932941Y138164D01*
G01X1929939Y151439D02*
Y141166D01*
G01X1935600Y157100D02*
X1929939Y151439D01*
G01X1905530Y194627D02*
X1912336D01*
G01X1902327Y197830D02*
X1905530Y194627D01*
G01X1932837Y180307D02*
Y186700D01*
G01X1934000Y179144D02*
X1932837Y180307D01*
G01X1934000Y157399D02*
Y179144D01*
G01X1932358Y212255D02*
X1909739Y234874D01*
G01X1937288Y212255D02*
X1932358D01*
G01X1946387Y203156D02*
X1937288Y212255D01*
G01X1946387Y165111D02*
Y203156D01*
G01X1940652Y159376D02*
X1946387Y165111D01*
G01X1940047Y159376D02*
X1940652D01*
G01X1912894Y193875D02*
X1915294Y191475D01*
G01X1904825Y193875D02*
X1912894D01*
G01X1901622Y197078D02*
X1904825Y193875D01*
G01X1935600Y176300D02*
Y157100D01*
G01X1907511Y233631D02*
X1902959Y238183D01*
G01X1907511Y221040D02*
Y233631D01*
G01X1905318Y218847D02*
X1907511Y221040D01*
G01X1901390Y234156D02*
X1899626Y232392D01*
G01X1905215Y234156D02*
X1901390D01*
G01X1906250Y233121D02*
X1905215Y234156D01*
G01X1906250Y221550D02*
Y233121D01*
G01X1904800Y220100D02*
X1906250Y221550D01*
G01X1908066Y234874D02*
X1903805Y239135D01*
G01X1909739Y234874D02*
X1908066D01*
G01X1903032Y228332D02*
X1899600Y224900D01*
G01X1903032Y228368D02*
Y228332D01*
G01X1900797Y223553D02*
X1903020Y225776D01*
G01X1944328Y228458D02*
X1944463D01*
G01X1937721Y221851D02*
X1944328Y228458D01*
G01X1931631Y221851D02*
X1937721D01*
G01X1916487Y236995D02*
X1931631Y221851D01*
G01X1909016Y236995D02*
X1916487D01*
G01X1903609Y242402D02*
X1909016Y236995D01*
G01X1944924Y226001D02*
X1944925D01*
G01X1944924Y226000D02*
Y226001D01*
G01X1943500Y226000D02*
X1944924D01*
G01X1938199Y220699D02*
X1943500Y226000D01*
G01X1930321Y220699D02*
X1938199D01*
G01X1915194Y235826D02*
X1930321Y220699D01*
G01X1908461Y235826D02*
X1915194D01*
G01X1903037Y241250D02*
X1908461Y235826D01*
G01X1944400Y510784D02*
Y526700D01*
G01X1942328Y508712D02*
X1944400Y510784D01*
G01X1908100Y539800D02*
X1899800Y548100D01*
G01X1931300Y539800D02*
X1908100D01*
G01X1944400Y526700D02*
X1931300Y539800D01*
G01X1970824Y145300D02*
X1973004Y143120D01*
G54D14*
G01X125550Y-47300D02*
X120500Y-42250D01*
G01X144200Y-47300D02*
X125550D01*
G01X145585Y-45915D02*
X144200Y-47300D01*
G01X443147Y-45915D02*
X145585D01*
G01X146299Y-42355D02*
X443147D01*
G01X160431Y-8347D02*
Y-9901D01*
G01X162678Y-6100D02*
X160431Y-8347D01*
G01X163902Y-6100D02*
X162678D01*
G01X165478Y-4524D02*
X163902Y-6100D01*
G01X165478Y-2900D02*
Y-4524D01*
G01X164703Y-2125D02*
X165478Y-2900D01*
G01X164703Y10888D02*
Y-2125D01*
G01X163477Y12114D02*
X164703Y10888D01*
G01X165341Y28849D02*
Y33800D01*
G01X164492Y28000D02*
X165341Y28849D01*
G01X164492Y18399D02*
Y28000D01*
G01X161592Y15499D02*
X164492Y18399D01*
G01X161592Y13999D02*
Y15499D01*
G01X163477Y12114D02*
X161592Y13999D01*
G01X152680Y29287D02*
Y34611D01*
G01X151892Y28499D02*
X152680Y29287D01*
G01X151892Y19000D02*
Y28499D01*
G01X148542Y15650D02*
X151892Y19000D01*
G01X148542Y13963D02*
Y15650D01*
G01X150391Y12114D02*
X148542Y13963D01*
G01X151780Y10725D02*
X150391Y12114D01*
G01X151780Y-2288D02*
Y10725D01*
G01X152392Y-2900D02*
X151780Y-2288D01*
G01X152392Y-4300D02*
Y-2900D01*
G01X150592Y-6100D02*
X152392Y-4300D01*
G01X149592Y-6100D02*
X150592D01*
G01X148292Y-7400D02*
X149592Y-6100D01*
G01X148292Y-8654D02*
Y-7400D01*
G01X147045Y-9901D02*
X148292Y-8654D01*
G01X146117Y16229D02*
X147045Y17157D01*
G01X146117Y13101D02*
Y16229D01*
G01X149159Y10059D02*
X146117Y13101D01*
G01X149159Y8674D02*
Y10059D01*
G01X147484Y6999D02*
X149159Y8674D01*
G01X147484Y5876D02*
Y6999D01*
G01X148984Y4376D02*
X147484Y5876D01*
G01X148984Y3024D02*
Y4376D01*
G01X147484Y1524D02*
X148984Y3024D01*
G01X147484Y301D02*
Y1524D01*
G01X148917Y-1132D02*
X147484Y301D01*
G01X148917Y-2226D02*
Y-1132D01*
G01X150391Y-3700D02*
X148917Y-2226D01*
G01X148480Y28911D02*
Y35087D01*
G01X149080Y28311D02*
X148480Y28911D01*
G01X149080Y19192D02*
Y28311D01*
G01X147045Y17157D02*
X149080Y19192D01*
G01X130313Y-7779D02*
Y-9901D01*
G01X132192Y-5900D02*
X130313Y-7779D01*
G01X133592Y-5900D02*
X132192D01*
G01X135048Y-4444D02*
X133592Y-5900D01*
G01X135048Y-3100D02*
Y-4444D01*
G01X134432Y-2484D02*
X135048Y-3100D01*
G01X134432Y10641D02*
Y-2484D01*
G01X132959Y12114D02*
X134432Y10641D01*
G01X134880Y25189D02*
Y37300D01*
G01X132380Y22689D02*
X134880Y25189D01*
G01X132380Y16688D02*
Y22689D01*
G01X130886Y15194D02*
X132380Y16688D01*
G01X130886Y14187D02*
Y15194D01*
G01X132959Y12114D02*
X130886Y14187D01*
G01X132092Y-3233D02*
X132959Y-4100D01*
G01X132092Y-932D02*
Y-3233D01*
G01X130459Y701D02*
X132092Y-932D01*
G01X130459Y2000D02*
Y701D01*
G01X131809Y3350D02*
X130459Y2000D01*
G01X131809Y4250D02*
Y3350D01*
G01X130559Y5500D02*
X131809Y4250D01*
G01X130559Y6699D02*
Y5500D01*
G01X132092Y8232D02*
X130559Y6699D01*
G01X132092Y10200D02*
Y8232D01*
G01X129192Y13100D02*
X132092Y10200D01*
G01X129192Y16036D02*
Y13100D01*
G01X130313Y17157D02*
X129192Y16036D01*
G01X131030Y29611D02*
Y34239D01*
G01X132180Y28461D02*
X131030Y29611D01*
G01X132180Y25789D02*
Y28461D01*
G01X129880Y23489D02*
X132180Y25789D01*
G01X129880Y18912D02*
Y23489D01*
G01X130313Y18479D02*
X129880Y18912D01*
G01X130313Y17157D02*
Y18479D01*
G01X162303Y-3012D02*
X163391Y-4100D01*
G01X162303Y-1132D02*
Y-3012D01*
G01X160870Y301D02*
X162303Y-1132D01*
G01X160870Y1500D02*
Y301D01*
G01X162370Y3000D02*
X160870Y1500D01*
G01X162370Y4200D02*
Y3000D01*
G01X160920Y5650D02*
X162370Y4200D01*
G01X160920Y7049D02*
Y5650D01*
G01X162303Y8432D02*
X160920Y7049D01*
G01X162303Y10301D02*
Y8432D01*
G01X159503Y13101D02*
X162303Y10301D01*
G01X159503Y16229D02*
Y13101D01*
G01X160431Y17157D02*
X159503Y16229D01*
G01X161491Y29401D02*
Y34299D01*
G01X162391Y28501D02*
X161491Y29401D01*
G01X162391Y19117D02*
Y28501D01*
G01X160431Y17157D02*
X162391Y19117D01*
G01X128392Y28156D02*
Y37400D01*
G01X125858Y16692D02*
X128392Y28156D01*
G01X124792Y15626D02*
X125858Y16692D01*
G01X124792Y13988D02*
Y15626D01*
G01X126666Y12114D02*
X124792Y13988D01*
G01X127892Y10888D02*
X126666Y12114D01*
G01X127892Y-2125D02*
Y10888D01*
G01X128667Y-2900D02*
X127892Y-2125D01*
G01X128667Y-4524D02*
Y-2900D01*
G01X127091Y-6100D02*
X128667Y-4524D01*
G01X125867Y-6100D02*
X127091D01*
G01X123620Y-8347D02*
X125867Y-6100D01*
G01X123620Y-9901D02*
Y-8347D01*
G01X154985Y-8654D02*
X153738Y-9901D01*
G01X154985Y-7400D02*
Y-8654D01*
G01X156285Y-6100D02*
X154985Y-7400D01*
G01X157285Y-6100D02*
X156285D01*
G01X159085Y-4300D02*
X157285Y-6100D01*
G01X159085Y-2900D02*
Y-4300D01*
G01X158473Y-2288D02*
X159085Y-2900D01*
G01X158473Y10725D02*
Y-2288D01*
G01X157084Y12114D02*
X158473Y10725D01*
G01X159080Y29249D02*
Y34911D01*
G01X158530Y28699D02*
X159080Y29249D01*
G01X158530Y25638D02*
Y28699D01*
G01X157392Y24500D02*
X158530Y25638D01*
G01X157392Y23200D02*
Y24500D01*
G01X158530Y22062D02*
X157392Y23200D01*
G01X158530Y18964D02*
Y22062D01*
G01X155180Y15614D02*
X158530Y18964D01*
G01X155180Y14018D02*
Y15614D01*
G01X157084Y12114D02*
X155180Y14018D01*
G01X169191Y22999D02*
X171691Y25499D01*
G01X169191Y16698D02*
Y22999D01*
G01X167697Y15204D02*
X169191Y16698D01*
G01X167697Y14187D02*
Y15204D01*
G01X169770Y12114D02*
X167697Y14187D01*
G01X169003Y-5900D02*
X170403D01*
G01X167124Y-7779D02*
X169003Y-5900D01*
G01X167124Y-9901D02*
Y-7779D01*
G01X122692Y16229D02*
X123620Y17157D01*
G01X122692Y13101D02*
Y16229D01*
G01X125492Y10301D02*
X122692Y13101D01*
G01X125492Y8432D02*
Y10301D01*
G01X124109Y7049D02*
X125492Y8432D01*
G01X124109Y5650D02*
Y7049D01*
G01X125559Y4200D02*
X124109Y5650D01*
G01X125559Y3000D02*
Y4200D01*
G01X124059Y1500D02*
X125559Y3000D01*
G01X124059Y301D02*
Y1500D01*
G01X125492Y-1132D02*
X124059Y301D01*
G01X125492Y-3012D02*
Y-1132D01*
G01X126580Y-4100D02*
X125492Y-3012D01*
G01X123620Y25127D02*
Y17157D01*
G01X125580Y27087D02*
X123620Y25127D01*
G01X125580Y28511D02*
Y27087D01*
G01X124680Y29411D02*
X125580Y28511D01*
G01X124680Y34587D02*
Y29411D01*
G01X155517Y-2133D02*
X157084Y-3700D01*
G01X155517Y-932D02*
Y-2133D01*
G01X154159Y426D02*
X155517Y-932D01*
G01X154159Y1799D02*
Y426D01*
G01X155359Y2999D02*
X154159Y1799D01*
G01X155359Y4125D02*
Y2999D01*
G01X154159Y5325D02*
X155359Y4125D01*
G01X154159Y6900D02*
Y5325D01*
G01X155959Y8700D02*
X154159Y6900D01*
G01X155959Y9758D02*
Y8700D01*
G01X152617Y13100D02*
X155959Y9758D01*
G01X152617Y16036D02*
Y13100D01*
G01X153738Y17157D02*
X152617Y16036D01*
G01X155180Y28999D02*
Y34687D01*
G01X155980Y28199D02*
X155180Y28999D01*
G01X155980Y27000D02*
Y28199D01*
G01X154692Y25712D02*
X155980Y27000D01*
G01X154692Y18111D02*
Y25712D01*
G01X153738Y17157D02*
X154692Y18111D01*
G01X167841Y29601D02*
Y34249D01*
G01X168991Y28451D02*
X167841Y29601D01*
G01X168991Y26599D02*
Y28451D01*
G01X167124Y24732D02*
X168991Y26599D01*
G01X167124Y17157D02*
Y24732D01*
G01X166003Y16036D02*
X167124Y17157D01*
G01X166003Y13100D02*
Y16036D01*
G01X168903Y10200D02*
X166003Y13100D01*
G01X168903Y8232D02*
Y10200D01*
G01X167370Y6699D02*
X168903Y8232D01*
G01X167370Y5500D02*
Y6699D01*
G01X168620Y4250D02*
X167370Y5500D01*
G01X168620Y3350D02*
Y4250D01*
G01X167270Y2000D02*
X168620Y3350D01*
G01X167270Y701D02*
Y2000D01*
G01X168903Y-932D02*
X167270Y701D01*
G01X168903Y-3233D02*
Y-932D01*
G01X169770Y-4100D02*
X168903Y-3233D01*
G01X165341Y87700D02*
Y95600D01*
G01X165289Y87266D02*
X165341Y87700D01*
G01X164991Y84800D02*
X165289Y87266D01*
G01X164991Y84100D02*
Y84800D01*
G01X165592Y83499D02*
X164991Y84100D01*
G01X165592Y76100D02*
Y83499D01*
G01X165416Y75500D02*
X165592Y76100D01*
G01X165092Y74400D02*
X165416Y75500D01*
G01X165092Y73900D02*
Y74400D01*
G01X165341Y71600D02*
X165092Y73900D01*
G01X165341Y66649D02*
Y71600D01*
G01X165091Y66399D02*
X165341Y66649D01*
G01X165091Y53864D02*
Y66399D01*
G01X165341Y53614D02*
X165091Y53864D01*
G01X165341Y49900D02*
Y53614D01*
G01X164991Y47500D02*
X165341Y49900D01*
G01X164991Y46301D02*
Y47500D01*
G01X165592Y45700D02*
X164991Y46301D01*
G01X165592Y38001D02*
Y45700D01*
G01X165192Y37601D02*
X165592Y38001D01*
G01X165192Y34822D02*
Y37601D01*
G01X165239Y34500D02*
X165192Y34822D01*
G01X165341Y33800D02*
X165239Y34500D01*
G01X151880Y91714D02*
Y104600D01*
G01X152580Y91014D02*
X151880Y91714D01*
G01X152580Y86514D02*
Y91014D01*
G01X151780Y85714D02*
X152580Y86514D01*
G01X151780Y83900D02*
Y85714D01*
G01X152292Y83388D02*
X151780Y83900D01*
G01X152292Y75300D02*
Y83388D01*
G01X151780Y74788D02*
X152292Y75300D01*
G01X151780Y73111D02*
Y74788D01*
G01X152680Y72211D02*
X151780Y73111D01*
G01X152680Y67299D02*
Y72211D01*
G01X151880Y66499D02*
X152680Y67299D01*
G01X151880Y53914D02*
Y66499D01*
G01X152580Y53214D02*
X151880Y53914D01*
G01X152580Y48714D02*
Y53214D01*
G01X151780Y47914D02*
X152580Y48714D01*
G01X151780Y46312D02*
Y47914D01*
G01X152492Y45600D02*
X151780Y46312D01*
G01X152492Y37612D02*
Y45600D01*
G01X151780Y36900D02*
X152492Y37612D01*
G01X151780Y35511D02*
Y36900D01*
G01X152680Y34611D02*
X151780Y35511D01*
G01X148880Y91614D02*
Y98812D01*
G01X148480Y91214D02*
X148880Y91614D01*
G01X148480Y86514D02*
Y91214D01*
G01X149280Y85714D02*
X148480Y86514D01*
G01X149280Y84100D02*
Y85714D01*
G01X148492Y83312D02*
X149280Y84100D01*
G01X148492Y75500D02*
Y83312D01*
G01X149280Y74712D02*
X148492Y75500D01*
G01X149280Y73487D02*
Y74712D01*
G01X148480Y72687D02*
X149280Y73487D01*
G01X148480Y66899D02*
Y72687D01*
G01X148880Y66499D02*
X148480Y66899D01*
G01X148880Y53814D02*
Y66499D01*
G01X148480Y53414D02*
X148880Y53814D01*
G01X148480Y48714D02*
Y53414D01*
G01X149280Y47914D02*
X148480Y48714D01*
G01X149280Y46300D02*
Y47914D01*
G01X148692Y45712D02*
X149280Y46300D01*
G01X148692Y37600D02*
Y45712D01*
G01X149280Y37012D02*
X148692Y37600D01*
G01X149280Y35887D02*
Y37012D01*
G01X148480Y35087D02*
X149280Y35887D01*
G01X134880Y94600D02*
X132992Y96488D01*
G01X134880Y84000D02*
Y94600D01*
G01X135492Y83388D02*
X134880Y84000D01*
G01X135492Y75600D02*
Y83388D01*
G01X134880Y74988D02*
X135492Y75600D01*
G01X134880Y46012D02*
Y74988D01*
G01X135446Y45446D02*
X134880Y46012D01*
G01X135446Y37866D02*
Y45446D01*
G01X134880Y37300D02*
X135446Y37866D01*
G01X132192Y93588D02*
X130492Y95288D01*
G01X132192Y92100D02*
Y93588D01*
G01X131030Y90938D02*
X132192Y92100D01*
G01X131030Y86714D02*
Y90938D01*
G01X132380Y85364D02*
X131030Y86714D01*
G01X132380Y84100D02*
Y85364D01*
G01X131592Y83312D02*
X132380Y84100D01*
G01X131592Y75600D02*
Y83312D01*
G01X132380Y74812D02*
X131592Y75600D01*
G01X132380Y73389D02*
Y74812D01*
G01X131030Y72039D02*
X132380Y73389D01*
G01X131030Y67411D02*
Y72039D01*
G01X132380Y66061D02*
X131030Y67411D01*
G01X132380Y54488D02*
Y66061D01*
G01X131030Y53138D02*
X132380Y54488D01*
G01X131030Y48914D02*
Y53138D01*
G01X132380Y47564D02*
X131030Y48914D01*
G01X132380Y46200D02*
Y47564D01*
G01X131792Y45612D02*
X132380Y46200D01*
G01X131792Y37500D02*
Y45612D01*
G01X132380Y36912D02*
X131792Y37500D01*
G01X132380Y35589D02*
Y36912D01*
G01X131030Y34239D02*
X132380Y35589D01*
G01X162480Y92087D02*
Y147071D01*
G01X161592Y91199D02*
X162480Y92087D01*
G01X161592Y86313D02*
Y91199D01*
G01X162292Y85613D02*
X161592Y86313D01*
G01X162292Y83900D02*
Y85613D01*
G01X161992Y83600D02*
X162292Y83900D01*
G01X161992Y75300D02*
Y83600D01*
G01X162292Y75000D02*
X161992Y75300D01*
G01X162292Y72900D02*
Y75000D01*
G01X161492Y72100D02*
X162292Y72900D01*
G01X161492Y67100D02*
Y72100D01*
G01X162292Y66300D02*
X161492Y67100D01*
G01X162292Y54215D02*
Y66300D01*
G01X161592Y53515D02*
X162292Y54215D01*
G01X161592Y48513D02*
Y53515D01*
G01X162292Y47813D02*
X161592Y48513D01*
G01X162292Y46000D02*
Y47813D01*
G01X161492Y45200D02*
X162292Y46000D01*
G01X161492Y37700D02*
Y45200D01*
G01X162292Y36900D02*
X161492Y37700D01*
G01X162292Y35100D02*
Y36900D01*
G01X161491Y34299D02*
X162292Y35100D01*
G01X127992Y93160D02*
Y153993D01*
G01X128530Y90360D02*
X127992Y93160D01*
G01X128530Y87500D02*
Y90360D01*
G01X128180Y84900D02*
X128530Y87500D01*
G01X128180Y84000D02*
Y84900D01*
G01X128392Y83788D02*
X128180Y84000D01*
G01X128392Y66144D02*
Y83788D01*
G01X128280Y64800D02*
X128392Y66144D01*
G01X128280Y53864D02*
Y64800D01*
G01X128492Y53652D02*
X128280Y53864D01*
G01X128492Y48626D02*
Y53652D01*
G01X128292Y48426D02*
X128492Y48626D01*
G01X128292Y46200D02*
Y48426D01*
G01X128792Y45700D02*
X128292Y46200D01*
G01X128792Y37800D02*
Y45700D01*
G01X128392Y37400D02*
X128792Y37800D01*
G01X158192Y94139D02*
X159188Y95135D01*
G01X158192Y92262D02*
Y94139D01*
G01X159180Y91274D02*
X158192Y92262D01*
G01X159180Y86614D02*
Y91274D01*
G01X158480Y85914D02*
X159180Y86614D01*
G01X158480Y84012D02*
Y85914D01*
G01X158892Y83600D02*
X158480Y84012D01*
G01X158892Y75612D02*
Y83600D01*
G01X158480Y75200D02*
X158892Y75612D01*
G01X158480Y73011D02*
Y75200D01*
G01X159030Y72461D02*
X158480Y73011D01*
G01X159030Y66999D02*
Y72461D01*
G01X158530Y66499D02*
X159030Y66999D01*
G01X158530Y53914D02*
Y66499D01*
G01X158991Y53453D02*
X158530Y53914D01*
G01X158991Y48575D02*
Y53453D01*
G01X158480Y48064D02*
X158991Y48575D01*
G01X158480Y46112D02*
Y48064D01*
G01X159092Y45500D02*
X158480Y46112D01*
G01X159092Y37712D02*
Y45500D01*
G01X158480Y37100D02*
X159092Y37712D01*
G01X158480Y35511D02*
Y37100D01*
G01X159080Y34911D02*
X158480Y35511D01*
G01X125680Y35587D02*
X124680Y34587D01*
G01X125680Y37112D02*
Y35587D01*
G01X124992Y37800D02*
X125680Y37112D01*
G01X124992Y45612D02*
Y37800D01*
G01X125680Y46300D02*
X124992Y45612D01*
G01X125680Y47614D02*
Y46300D01*
G01X124680Y48614D02*
X125680Y47614D01*
G01X124680Y53414D02*
Y48614D01*
G01X125580Y54314D02*
X124680Y53414D01*
G01X125580Y66211D02*
Y54314D01*
G01X124680Y67111D02*
X125580Y66211D01*
G01X124680Y72099D02*
Y67111D01*
G01X125680Y73099D02*
X124680Y72099D01*
G01X125680Y74712D02*
Y73099D01*
G01X124992Y75400D02*
X125680Y74712D01*
G01X124992Y83300D02*
Y75400D01*
G01X125680Y83988D02*
X124992Y83300D01*
G01X125680Y85414D02*
Y83988D01*
G01X124680Y86414D02*
X125680Y85414D01*
G01X124680Y91214D02*
Y86414D01*
G01X125492Y92026D02*
X124680Y91214D01*
G01X125492Y154301D02*
Y92026D01*
G01X155692Y91726D02*
Y100801D01*
G01X155080Y91114D02*
X155692Y91726D01*
G01X155080Y86414D02*
Y91114D01*
G01X155680Y85814D02*
X155080Y86414D01*
G01X155680Y84100D02*
Y85814D01*
G01X155192Y83612D02*
X155680Y84100D01*
G01X155192Y75400D02*
Y83612D01*
G01X155680Y74912D02*
X155192Y75400D01*
G01X155680Y73087D02*
Y74912D01*
G01X155180Y72587D02*
X155680Y73087D01*
G01X155180Y66799D02*
Y72587D01*
G01X156030Y65949D02*
X155180Y66799D01*
G01X156030Y54264D02*
Y65949D01*
G01X155080Y53314D02*
X156030Y54264D01*
G01X155080Y48614D02*
Y53314D01*
G01X155680Y48014D02*
X155080Y48614D01*
G01X155680Y46288D02*
Y48014D01*
G01X155092Y45700D02*
X155680Y46288D01*
G01X155092Y37388D02*
Y45700D01*
G01X155680Y36800D02*
X155092Y37388D01*
G01X155680Y35187D02*
Y36800D01*
G01X155180Y34687D02*
X155680Y35187D01*
G01X168992Y92149D02*
Y100468D01*
G01X167841Y90998D02*
X168992Y92149D01*
G01X167841Y86714D02*
Y90998D01*
G01X169191Y85364D02*
X167841Y86714D01*
G01X169191Y84300D02*
Y85364D01*
G01X168492Y83601D02*
X169191Y84300D01*
G01X168492Y75300D02*
Y83601D01*
G01X169191Y74601D02*
X168492Y75300D01*
G01X169191Y73499D02*
Y74601D01*
G01X167841Y72149D02*
X169191Y73499D01*
G01X167841Y67401D02*
Y72149D01*
G01X169191Y66051D02*
X167841Y67401D01*
G01X169191Y54598D02*
Y66051D01*
G01X167841Y53248D02*
X169191Y54598D01*
G01X167841Y48914D02*
Y53248D01*
G01X169191Y47564D02*
X167841Y48914D01*
G01X169191Y46299D02*
Y47564D01*
G01X168392Y45500D02*
X169191Y46299D01*
G01X168392Y37599D02*
Y45500D01*
G01X169191Y36800D02*
X168392Y37599D01*
G01X169191Y35599D02*
Y36800D01*
G01X167841Y34249D02*
X169191Y35599D01*
G01X165341Y146396D02*
X253387Y234442D01*
G01X165341Y99100D02*
Y146396D01*
G01X166392Y98049D02*
X165341Y99100D01*
G01X166392Y96651D02*
Y98049D01*
G01X165341Y95600D02*
X166392Y96651D01*
G01X154433Y149685D02*
X174362Y169614D01*
G01X154433Y147790D02*
Y149685D01*
G01X153873Y147230D02*
X154433Y147790D01*
G01X152152Y147230D02*
X153873D01*
G01X151592Y146670D02*
X152152Y147230D01*
G01X151592Y145230D02*
Y146670D01*
G01X152152Y144670D02*
X151592Y145230D01*
G01X153873Y144670D02*
X152152D01*
G01X154433Y144110D02*
X153873Y144670D01*
G01X154433Y142670D02*
Y144110D01*
G01X153873Y142110D02*
X154433Y142670D01*
G01X152152Y142110D02*
X153873D01*
G01X151592Y141550D02*
X152152Y142110D01*
G01X151592Y140110D02*
Y141550D01*
G01X152152Y139550D02*
X151592Y140110D01*
G01X153873Y139550D02*
X152152D01*
G01X154433Y138990D02*
X153873Y139550D01*
G01X154433Y137041D02*
Y138990D01*
G01X151592Y134200D02*
X154433Y137041D01*
G01X151592Y108360D02*
Y134200D01*
G01X151032Y107800D02*
X151592Y108360D01*
G01X146435Y107800D02*
X151032D01*
G01X145592Y106957D02*
X146435Y107800D01*
G01X145592Y105900D02*
Y106957D01*
G01X146392Y105100D02*
X145592Y105900D01*
G01X151380Y105100D02*
X146392D01*
G01X151880Y104600D02*
X151380Y105100D01*
G01X149492Y148584D02*
X164600Y163692D01*
G01X149492Y111800D02*
Y148584D01*
G01X148692Y111000D02*
X149492Y111800D01*
G01X147192Y111000D02*
X148692D01*
G01X146292Y111900D02*
X147192Y111000D01*
G01X146292Y124300D02*
Y111900D01*
G01X145492Y125100D02*
X146292Y124300D01*
G01X143892Y125100D02*
X145492D01*
G01X143092Y124300D02*
X143892Y125100D01*
G01X143092Y104600D02*
Y124300D01*
G01X148880Y98812D02*
X143092Y104600D01*
G01X136196Y154804D02*
X137791Y156400D01*
G01X132992Y151601D02*
X136196Y154804D01*
G01X132992Y96488D02*
Y151601D01*
G01X134692Y155967D02*
Y157957D01*
G01X133525Y154800D02*
X134692Y155967D01*
G01X131535Y154800D02*
X133525D01*
G01X130492Y153757D02*
X131535Y154800D01*
G01X130492Y95288D02*
Y153757D01*
G01X162480Y147071D02*
X252351Y236942D01*
G01X127992Y153993D02*
X144646Y170647D01*
G01X159188Y148130D02*
X216794Y205736D01*
G01X159188Y95135D02*
Y148130D01*
G01X237821Y266630D02*
X125492Y154301D01*
G01X156828Y149153D02*
X186503Y178828D01*
G01X156828Y131779D02*
Y149153D01*
G01X156268Y131219D02*
X156828Y131779D01*
G01X154652Y131219D02*
X156268D01*
G01X154092Y130659D02*
X154652Y131219D01*
G01X154092Y129219D02*
Y130659D01*
G01X154652Y128659D02*
X154092Y129219D01*
G01X156268Y128659D02*
X154652D01*
G01X156828Y128099D02*
X156268Y128659D01*
G01X156828Y101937D02*
Y128099D01*
G01X155692Y100801D02*
X156828Y101937D01*
G01X168241Y145760D02*
X190865Y168384D01*
G01X168241Y101219D02*
Y145760D01*
G01X168992Y100468D02*
X168241Y101219D01*
G01X168973Y174349D02*
X231274Y236650D01*
G01X168973Y168065D02*
Y174349D01*
G01X167188Y166280D02*
X168973Y168065D01*
G01X166326Y166280D02*
X167188D01*
G01X163896Y168710D02*
X166326Y166280D01*
G01X163034Y168710D02*
X163896D01*
G01X162170Y167846D02*
X163034Y168710D01*
G01X162170Y166984D02*
Y167846D01*
G01X164600Y164554D02*
X162170Y166984D01*
G01X164600Y163692D02*
Y164554D01*
G01X152332Y172061D02*
X239401Y259130D01*
G01X152332Y167341D02*
Y172061D01*
G01X149362Y164371D02*
X152332Y167341D01*
G01X147844Y164371D02*
X149362D01*
G01X139873Y156400D02*
X147844Y164371D01*
G01X137791Y156400D02*
X139873D01*
G01X150064Y173329D02*
X238365Y261630D01*
G01X150064Y167739D02*
Y173329D01*
G01X149563Y167238D02*
X150064Y167739D01*
G01X145635Y167238D02*
X149563D01*
G01X144892Y166495D02*
X145635Y167238D01*
G01X144892Y164500D02*
Y166495D01*
G01X144192Y163800D02*
X144892Y164500D01*
G01X140535Y163800D02*
X144192D01*
G01X139392Y162657D02*
X140535Y163800D01*
G01X139392Y159899D02*
Y162657D01*
G01X138493Y159000D02*
X139392Y159899D01*
G01X135735Y159000D02*
X138493D01*
G01X134692Y157957D02*
X135735Y159000D01*
G01X147496Y173497D02*
X238129Y264130D01*
G01X147496Y171207D02*
Y173497D01*
G01X146936Y170647D02*
X147496Y171207D01*
G01X144646Y170647D02*
X146936D01*
G01X167643Y396250D02*
X159792Y404101D01*
G01X189643Y396250D02*
X167643D01*
G01X169550Y400250D02*
X164092Y405708D01*
G01X191143Y400250D02*
X169550D01*
G01X168342Y398350D02*
X190243D01*
G01X161692Y405000D02*
X168342Y398350D01*
G01X134692Y464400D02*
Y499300D01*
G01X136192Y462900D02*
X134692Y464400D01*
G01X136192Y461300D02*
Y462900D01*
G01X134692Y459800D02*
X136192Y461300D01*
G01X134692Y451948D02*
Y459800D01*
G01X135252Y451388D02*
X134692Y451948D01*
G01X141232Y451388D02*
X135252D01*
G01X141792Y450828D02*
X141232Y451388D01*
G01X141792Y449388D02*
Y450828D01*
G01X141232Y448828D02*
X141792Y449388D01*
G01X135252Y448828D02*
X141232D01*
G01X134692Y448268D02*
X135252Y448828D01*
G01X134692Y445800D02*
Y448268D01*
G01X135592Y444900D02*
X134692Y445800D01*
G01X140092Y444900D02*
X135592D01*
G01X140792Y444200D02*
X140092Y444900D01*
G01X140792Y441501D02*
Y444200D01*
G01X156892Y425401D02*
X140792Y441501D01*
G01X156892Y423301D02*
Y425401D01*
G01X169700Y410493D02*
X156892Y423301D01*
G01X171542Y402150D02*
X169700Y403992D01*
G01X163292Y462556D02*
Y500100D01*
G01X232592Y393256D02*
X163292Y462556D01*
G01X168292Y464628D02*
Y492218D01*
G01X236792Y396128D02*
X168292Y464628D01*
G01X158792Y464038D02*
X159988Y465234D01*
G01X158792Y461399D02*
Y464038D01*
G01X178775Y441416D02*
X158792Y461399D01*
G01X161144Y454521D02*
X176512Y439153D01*
G01X160012Y454521D02*
X161144D01*
G01X158881Y453390D02*
X160012Y454521D01*
G01X158881Y452258D02*
Y453390D01*
G01X176350Y434789D02*
X158881Y452258D01*
G01X127192Y445003D02*
Y495384D01*
G01X134995Y437200D02*
X127192Y445003D01*
G01X136892Y437200D02*
X134995D01*
G01X150792Y423300D02*
X136892Y437200D01*
G01X150792Y420302D02*
Y423300D01*
G01X152765Y415541D02*
X150792Y420302D01*
G01X155644Y411748D02*
X152765Y415541D01*
G01X157317Y410075D02*
X155644Y411748D01*
G01X159792Y404101D02*
X157317Y410075D01*
G01X156292Y460363D02*
Y499000D01*
G01X158473Y458182D02*
X156292Y460363D01*
G01X158473Y456581D02*
Y458182D01*
G01X156292Y454400D02*
X158473Y456581D01*
G01X156292Y451311D02*
Y454400D01*
G01X176411Y431192D02*
X156292Y451311D01*
G01X153792Y450274D02*
Y498700D01*
G01X156316Y447750D02*
X153792Y450274D01*
G01X156316Y446958D02*
Y447750D01*
G01X153171Y443813D02*
X156316Y446958D01*
G01X153171Y443021D02*
Y443813D01*
G01X154190Y442002D02*
X153171Y443021D01*
G01X154982Y442002D02*
X154190D01*
G01X158127Y445147D02*
X154982Y442002D01*
G01X158919Y445147D02*
X158127D01*
G01X159938Y444128D02*
X158919Y445147D01*
G01X159938Y443336D02*
Y444128D01*
G01X156793Y440191D02*
X159938Y443336D01*
G01X156793Y439399D02*
Y440191D01*
G01X157812Y438380D02*
X156793Y439399D01*
G01X158604Y438380D02*
X157812D01*
G01X161749Y441525D02*
X158604Y438380D01*
G01X162541Y441525D02*
X161749D01*
G01X163560Y440506D02*
X162541Y441525D01*
G01X163560Y439714D02*
Y440506D01*
G01X160415Y436569D02*
X163560Y439714D01*
G01X160415Y435777D02*
Y436569D01*
G01X161434Y434758D02*
X160415Y435777D01*
G01X162226Y434758D02*
X161434D01*
G01X165371Y437903D02*
X162226Y434758D01*
G01X166163Y437903D02*
X165371D01*
G01X167182Y436884D02*
X166163Y437903D01*
G01X167182Y436092D02*
Y436884D01*
G01X164037Y432947D02*
X167182Y436092D01*
G01X164037Y432155D02*
Y432947D01*
G01X165056Y431136D02*
X164037Y432155D01*
G01X165848Y431136D02*
X165056D01*
G01X168993Y434281D02*
X165848Y431136D01*
G01X169785Y434281D02*
X168993D01*
G01X168167Y429833D02*
X170804Y432470D01*
G01X168167Y429125D02*
Y429833D01*
G01X169178Y428114D02*
X168167Y429125D01*
G01X170070Y428114D02*
X169178D01*
G01X166325Y463059D02*
Y466400D01*
G01X234492Y394892D02*
X166325Y463059D01*
G01X132192Y445395D02*
Y498800D01*
G01X135287Y442300D02*
X132192Y445395D01*
G01X137293Y442300D02*
X135287D01*
G01X154892Y424701D02*
X137293Y442300D01*
G01X154892Y422501D02*
Y424701D01*
G01X164092Y413301D02*
X154892Y422501D01*
G01X164092Y405708D02*
Y413301D01*
G01X164792Y426600D02*
X171632Y419760D01*
G01X164792Y428600D02*
Y426600D01*
G01X151292Y442100D02*
X164792Y428600D01*
G01X151292Y487604D02*
Y442100D01*
G01X161692Y412901D02*
Y405000D01*
G01X160893Y413700D02*
X161692Y412901D01*
G01X156950Y413700D02*
X160893D01*
G01X155655Y414995D02*
X156950Y413700D01*
G01X154123Y417288D02*
X155655Y414995D01*
G01X152992Y420019D02*
X154123Y417288D01*
G01X152992Y423900D02*
Y420019D01*
G01X137341Y439551D02*
X152992Y423900D01*
G01X135326Y439551D02*
X137341D01*
G01X129692Y445185D02*
X135326Y439551D01*
G01X129692Y497900D02*
Y445185D01*
G01X135392Y519400D02*
Y527500D01*
G01X134880Y518888D02*
X135392Y519400D01*
G01X134880Y508812D02*
Y518888D01*
G01X135292Y508400D02*
X134880Y508812D01*
G01X135292Y506842D02*
Y508400D01*
G01X134682Y506232D02*
X135292Y506842D01*
G01X133472Y506232D02*
X134682D01*
G01X132862Y505622D02*
X133472Y506232D01*
G01X132862Y503642D02*
Y505622D01*
G01X133472Y503032D02*
X132862Y503642D01*
G01X134682Y503032D02*
X133472D01*
G01X135292Y502422D02*
X134682Y503032D01*
G01X135292Y499900D02*
Y502422D01*
G01X134692Y499300D02*
X135292Y499900D01*
G01X162092Y519799D02*
Y527801D01*
G01X162233Y519658D02*
X162092Y519799D01*
G01X162233Y517199D02*
Y519658D01*
G01X161491Y516457D02*
X162233Y517199D01*
G01X161491Y511797D02*
Y516457D01*
G01X162163Y511125D02*
X161491Y511797D01*
G01X162163Y508971D02*
Y511125D01*
G01X160792Y507600D02*
X162163Y508971D01*
G01X160792Y502600D02*
Y507600D01*
G01X163292Y500100D02*
X160792Y502600D01*
G01X167999Y520792D02*
Y526607D01*
G01X169191Y519600D02*
X167999Y520792D01*
G01X169191Y517657D02*
Y519600D01*
G01X167841Y516307D02*
X169191Y517657D01*
G01X167841Y512057D02*
Y516307D01*
G01X168892Y511006D02*
X167841Y512057D01*
G01X168892Y508700D02*
Y511006D01*
G01X168292Y508100D02*
X168892Y508700D01*
G01X168292Y497018D02*
Y508100D01*
G01X169092Y496218D02*
X168292Y497018D01*
G01X169792Y496218D02*
X169092D01*
G01Y493018D02*
X169792D01*
G01X168292Y492218D02*
X169092Y493018D01*
G01X158192Y524156D02*
Y529478D01*
G01X159292Y523056D02*
X158192Y524156D01*
G01X159292Y521596D02*
Y523056D01*
G01X158192Y520496D02*
X159292Y521596D01*
G01X158192Y517695D02*
Y520496D01*
G01X159080Y516807D02*
X158192Y517695D01*
G01X159080Y512257D02*
Y516807D01*
G01X157795Y510972D02*
X159080Y512257D01*
G01X157795Y501397D02*
Y510972D01*
G01X159988Y499204D02*
X157795Y501397D01*
G01X159988Y497234D02*
Y499204D01*
G01X158792Y496038D02*
X159988Y497234D01*
G01X158792Y494034D02*
Y496038D01*
G01X159988Y492838D02*
X158792Y494034D01*
G01X159988Y490834D02*
Y492838D01*
G01X158792Y489638D02*
X159988Y490834D01*
G01X158792Y487634D02*
Y489638D01*
G01X159988Y486438D02*
X158792Y487634D01*
G01X159988Y484434D02*
Y486438D01*
G01X158792Y483238D02*
X159988Y484434D01*
G01X158792Y481234D02*
Y483238D01*
G01X159988Y480038D02*
X158792Y481234D01*
G01X159988Y478034D02*
Y480038D01*
G01X158792Y476838D02*
X159988Y478034D01*
G01X158792Y474834D02*
Y476838D01*
G01X159988Y473638D02*
X158792Y474834D01*
G01X159988Y471634D02*
Y473638D01*
G01X158792Y470438D02*
X159988Y471634D01*
G01X158792Y468434D02*
Y470438D01*
G01X159988Y467238D02*
X158792Y468434D01*
G01X159988Y465234D02*
Y467238D01*
G01X125580Y518256D02*
Y528650D01*
G01X124680Y516083D02*
X125580Y518256D01*
G01X124680Y512677D02*
Y516083D01*
G01X125208Y511400D02*
X124680Y512677D01*
G01X125374Y511000D02*
X125208Y511400D01*
G01X125492Y510716D02*
X125374Y511000D01*
G01X125492Y499488D02*
Y510716D01*
G01X125811Y498717D02*
X125492Y499488D01*
G01X127192Y495384D02*
X125811Y498717D01*
G01X156292Y517601D02*
Y529154D01*
G01X155180Y516489D02*
X156292Y517601D01*
G01X155180Y511657D02*
Y516489D01*
G01X155680Y511157D02*
X155180Y511657D01*
G01X155680Y508988D02*
Y511157D01*
G01X155142Y508450D02*
X155680Y508988D01*
G01X155142Y500150D02*
Y508450D01*
G01X156292Y499000D02*
X155142Y500150D01*
G01X152759Y520767D02*
Y527033D01*
G01X151475Y519483D02*
X152759Y520767D01*
G01X151475Y517418D02*
Y519483D01*
G01X152892Y516001D02*
X151475Y517418D01*
G01X152892Y512369D02*
Y516001D01*
G01X151780Y511257D02*
X152892Y512369D01*
G01X151780Y509112D02*
Y511257D01*
G01X153014Y507878D02*
X151780Y509112D01*
G01X153014Y506874D02*
Y507878D01*
G01X152404Y506264D02*
X153014Y506874D01*
G01X150343Y506264D02*
X152404D01*
G01X149733Y505654D02*
X150343Y506264D01*
G01X149733Y503674D02*
Y505654D01*
G01X150343Y503064D02*
X149733Y503674D01*
G01X152404Y503064D02*
X150343D01*
G01X153014Y502454D02*
X152404Y503064D01*
G01X153014Y499478D02*
Y502454D01*
G01X153792Y498700D02*
X153014Y499478D01*
G01X165492Y520925D02*
Y527364D01*
G01X164729Y520162D02*
X165492Y520925D01*
G01X164729Y517371D02*
Y520162D01*
G01X165809Y516291D02*
X164729Y517371D01*
G01X165809Y512215D02*
Y516291D01*
G01X165091Y511497D02*
X165809Y512215D01*
G01X165091Y509518D02*
Y511497D01*
G01X166351Y508258D02*
X165091Y509518D01*
G01X166351Y506948D02*
Y508258D01*
G01X165783Y506380D02*
X166351Y506948D01*
G01X164092Y506380D02*
X165783D01*
G01X163592Y505880D02*
X164092Y506380D01*
G01X163592Y503680D02*
Y505880D01*
G01X164092Y503180D02*
X163592Y503680D01*
G01X165522Y503180D02*
X164092D01*
G01X166325Y502377D02*
X165522Y503180D01*
G01X166325Y498832D02*
Y502377D01*
G01X165292Y497799D02*
X166325Y498832D01*
G01X165292Y496501D02*
Y497799D01*
G01X166325Y495468D02*
X165292Y496501D01*
G01X166325Y492000D02*
Y495468D01*
G01X165192Y490867D02*
X166325Y492000D01*
G01X165192Y488633D02*
Y490867D01*
G01X166325Y487500D02*
X165192Y488633D01*
G01X166325Y483300D02*
Y487500D01*
G01X165392Y482367D02*
X166325Y483300D01*
G01X165392Y481001D02*
Y482367D01*
G01X166325Y480068D02*
X165392Y481001D01*
G01X166325Y477932D02*
Y480068D01*
G01X165292Y476899D02*
X166325Y477932D01*
G01X165292Y475301D02*
Y476899D01*
G01X166325Y474268D02*
X165292Y475301D01*
G01X166325Y469800D02*
Y474268D01*
G01X165292Y468767D02*
X166325Y469800D01*
G01X165292Y467433D02*
Y468767D01*
G01X166325Y466400D02*
X165292Y467433D01*
G01X131992Y519788D02*
Y527200D01*
G01X132492Y519288D02*
X131992Y519788D01*
G01X132492Y517901D02*
Y519288D01*
G01X131159Y516568D02*
X132492Y517901D01*
G01X131159Y511932D02*
Y516568D01*
G01X132380Y510711D02*
X131159Y511932D01*
G01X132380Y509388D02*
Y510711D01*
G01X130426Y507434D02*
X132380Y509388D01*
G01X130426Y500566D02*
Y507434D01*
G01X132192Y498800D02*
X130426Y500566D01*
G01X149892Y489004D02*
X151292Y487604D01*
G01X149892Y490500D02*
Y489004D01*
G01X151292Y491900D02*
X149892Y490500D01*
G01X151292Y497400D02*
Y491900D01*
G01X147792Y500900D02*
X151292Y497400D01*
G01X147792Y508000D02*
Y500900D01*
G01X149492Y509700D02*
X147792Y508000D01*
G01X149492Y510601D02*
Y509700D01*
G01X147892Y512201D02*
X149492Y510601D01*
G01X147892Y516001D02*
Y512201D01*
G01X149435Y517544D02*
X147892Y516001D01*
G01X149435Y519045D02*
Y517544D01*
G01X148692Y519788D02*
X149435Y519045D01*
G01X148692Y527700D02*
Y519788D01*
G01X128037Y499555D02*
X129692Y497900D01*
G01X128037Y511254D02*
Y499555D01*
G01X128530Y511747D02*
X128037Y511254D01*
G01X128530Y517207D02*
Y511747D01*
G01X128280Y517457D02*
X128530Y517207D01*
G01X128280Y519400D02*
Y517457D01*
G01X128692Y519812D02*
X128280Y519400D01*
G01X128692Y527700D02*
Y519812D01*
G01X134880Y586443D02*
X132959Y588364D01*
G01X134880Y584112D02*
Y586443D01*
G01X135292Y583700D02*
X134880Y584112D01*
G01X135292Y576012D02*
Y583700D01*
G01X134880Y575600D02*
X135292Y576012D01*
G01X134880Y565912D02*
Y575600D01*
G01X135292Y565500D02*
X134880Y565912D01*
G01X135292Y556600D02*
Y565500D01*
G01X134880Y556188D02*
X135292Y556600D01*
G01X134880Y546612D02*
Y556188D01*
G01X135392Y546100D02*
X134880Y546612D01*
G01X135392Y538200D02*
Y546100D01*
G01X134880Y537688D02*
X135392Y538200D01*
G01X134880Y528012D02*
Y537688D01*
G01X135392Y527500D02*
X134880Y528012D01*
G01X162341Y586457D02*
X159191Y589607D01*
G01X162341Y584049D02*
Y586457D01*
G01X162092Y583800D02*
X162341Y584049D01*
G01X162092Y575849D02*
Y583800D01*
G01X162341Y575600D02*
X162092Y575849D01*
G01X162341Y573942D02*
Y575600D01*
G01X161343Y572944D02*
X162341Y573942D01*
G01X161343Y568249D02*
Y572944D01*
G01X162391Y567201D02*
X161343Y568249D01*
G01X162391Y565699D02*
Y567201D01*
G01X162092Y565400D02*
X162391Y565699D01*
G01X162092Y557299D02*
Y565400D01*
G01X162391Y557000D02*
X162092Y557299D01*
G01X162391Y555157D02*
Y557000D01*
G01X161491Y554257D02*
X162391Y555157D01*
G01X161491Y549557D02*
Y554257D01*
G01X162491Y548557D02*
X161491Y549557D01*
G01X162491Y546399D02*
Y548557D01*
G01X162092Y546000D02*
X162491Y546399D01*
G01X162092Y537999D02*
Y546000D01*
G01X162299Y537792D02*
X162092Y537999D01*
G01X162299Y536050D02*
Y537792D01*
G01X161491Y535242D02*
X162299Y536050D01*
G01X161491Y530402D02*
Y535242D01*
G01X162232Y529661D02*
X161491Y530402D01*
G01X162232Y527941D02*
Y529661D01*
G01X162092Y527801D02*
X162232Y527941D01*
G01X169041Y586457D02*
X165691Y589807D01*
G01X169041Y584649D02*
Y586457D01*
G01X168792Y584400D02*
X169041Y584649D01*
G01X168792Y575749D02*
Y584400D01*
G01X169041Y575500D02*
X168792Y575749D01*
G01X169041Y574349D02*
Y575500D01*
G01X167891Y573199D02*
X169041Y574349D01*
G01X167891Y568367D02*
Y573199D01*
G01X168991Y567267D02*
X167891Y568367D01*
G01X168991Y565699D02*
Y567267D01*
G01X168792Y565500D02*
X168991Y565699D01*
G01X168792Y557199D02*
Y565500D01*
G01X168991Y557000D02*
X168792Y557199D01*
G01X168991Y555257D02*
Y557000D01*
G01X167841Y554107D02*
X168991Y555257D01*
G01X167841Y549857D02*
Y554107D01*
G01X169191Y548507D02*
X167841Y549857D01*
G01X169191Y546499D02*
Y548507D01*
G01X168792Y546100D02*
X169191Y546499D01*
G01X168792Y538199D02*
Y546100D01*
G01X169191Y537800D02*
X168792Y538199D01*
G01X169191Y536700D02*
Y537800D01*
G01X167841Y535350D02*
X169191Y536700D01*
G01X167841Y530617D02*
Y535350D01*
G01X169191Y529267D02*
X167841Y530617D01*
G01X169191Y527799D02*
Y529267D01*
G01X167999Y526607D02*
X169191Y527799D01*
G01X158380Y587470D02*
X157084Y588766D01*
G01X158380Y582400D02*
Y587470D01*
G01X159292Y581488D02*
X158380Y582400D01*
G01X159292Y577712D02*
Y581488D01*
G01X158380Y576800D02*
X159292Y577712D01*
G01X158380Y574012D02*
Y576800D01*
G01X159380Y573012D02*
X158380Y574012D01*
G01X159380Y568497D02*
Y573012D01*
G01X158530Y567647D02*
X159380Y568497D01*
G01X158530Y563800D02*
Y567647D01*
G01X159692Y562638D02*
X158530Y563800D01*
G01X159692Y559962D02*
Y562638D01*
G01X158530Y558800D02*
X159692Y559962D01*
G01X158530Y555157D02*
Y558800D01*
G01X159080Y554607D02*
X158530Y555157D01*
G01X159080Y550057D02*
Y554607D01*
G01X158292Y549269D02*
X159080Y550057D01*
G01X158292Y544500D02*
Y549269D01*
G01X159492Y543300D02*
X158292Y544500D01*
G01X159492Y540800D02*
Y543300D01*
G01X158292Y539600D02*
X159492Y540800D01*
G01X158292Y536600D02*
Y539600D01*
G01X159180Y535712D02*
X158292Y536600D01*
G01X159180Y530466D02*
Y535712D01*
G01X158192Y529478D02*
X159180Y530466D01*
G01X124626Y587825D02*
X123155Y589296D01*
G01X125325Y586137D02*
X124626Y587825D01*
G01X125325Y574251D02*
Y586137D01*
G01X124755Y572875D02*
X125325Y574251D01*
G01X124755Y568552D02*
Y572875D01*
G01X125580Y566560D02*
X124755Y568552D01*
G01X125580Y555672D02*
Y566560D01*
G01X124853Y553917D02*
X125580Y555672D01*
G01X124853Y550288D02*
Y553917D01*
G01X125492Y548745D02*
X124853Y550288D01*
G01X125492Y536824D02*
Y548745D01*
G01X124680Y534863D02*
X125492Y536824D01*
G01X124680Y530824D02*
Y534863D01*
G01X125580Y528650D02*
X124680Y530824D01*
G01X155780Y586507D02*
X152380Y589907D01*
G01X155780Y584588D02*
Y586507D01*
G01X155192Y584000D02*
X155780Y584588D01*
G01X155192Y577200D02*
Y584000D01*
G01X155992Y576400D02*
X155192Y577200D01*
G01X155992Y574254D02*
Y576400D01*
G01X154880Y573142D02*
X155992Y574254D01*
G01X154880Y568397D02*
Y573142D01*
G01X156192Y567085D02*
X154880Y568397D01*
G01X156192Y565500D02*
Y567085D01*
G01X155392Y564700D02*
X156192Y565500D01*
G01X155392Y557688D02*
Y564700D01*
G01X156192Y556888D02*
X155392Y557688D01*
G01X156192Y555401D02*
Y556888D01*
G01X155180Y554389D02*
X156192Y555401D01*
G01X155180Y550013D02*
Y554389D01*
G01X156092Y549101D02*
X155180Y550013D01*
G01X156092Y547400D02*
Y549101D01*
G01X155392Y546700D02*
X156092Y547400D01*
G01X155392Y538700D02*
Y546700D01*
G01X156092Y538000D02*
X155392Y538700D01*
G01X156092Y536700D02*
Y538000D01*
G01X155080Y535688D02*
X156092Y536700D01*
G01X155080Y530366D02*
Y535688D01*
G01X156292Y529154D02*
X155080Y530366D01*
G01X151737Y587368D02*
X150391Y588714D01*
G01X151780Y587368D02*
X151737D01*
G01X151780Y584512D02*
Y587368D01*
G01X152092Y584200D02*
X151780Y584512D01*
G01X152092Y576500D02*
Y584200D01*
G01X151292Y575700D02*
X152092Y576500D01*
G01X151292Y574499D02*
Y575700D01*
G01X152692Y573099D02*
X151292Y574499D01*
G01X152692Y568409D02*
Y573099D01*
G01X151604Y567321D02*
X152692Y568409D01*
G01X151604Y566188D02*
Y567321D01*
G01X152092Y565700D02*
X151604Y566188D01*
G01X152092Y557512D02*
Y565700D01*
G01X151375Y556795D02*
X152092Y557512D01*
G01X151375Y555318D02*
Y556795D01*
G01X152792Y553901D02*
X151375Y555318D01*
G01X152792Y550069D02*
Y553901D01*
G01X151392Y548669D02*
X152792Y550069D01*
G01X151392Y546900D02*
Y548669D01*
G01X152092Y546200D02*
X151392Y546900D01*
G01X152092Y538900D02*
Y546200D01*
G01X151492Y538300D02*
X152092Y538900D01*
G01X151492Y536600D02*
Y538300D01*
G01X152892Y535200D02*
X151492Y536600D01*
G01X152892Y530854D02*
Y535200D01*
G01X151481Y529443D02*
X152892Y530854D01*
G01X151481Y528311D02*
Y529443D01*
G01X152759Y527033D02*
X151481Y528311D01*
G01X164991Y587200D02*
X163477Y588714D01*
G01X164991Y584301D02*
Y587200D01*
G01X165492Y583800D02*
X164991Y584301D01*
G01X165492Y575901D02*
Y583800D01*
G01X164991Y575400D02*
X165492Y575901D01*
G01X164991Y573256D02*
Y575400D01*
G01X165591Y572656D02*
X164991Y573256D01*
G01X165591Y568497D02*
Y572656D01*
G01X165091Y567997D02*
X165591Y568497D01*
G01X165091Y565901D02*
Y567997D01*
G01X165492Y565500D02*
X165091Y565901D01*
G01X165492Y557501D02*
Y565500D01*
G01X164617Y556626D02*
X165492Y557501D01*
G01X164617Y555141D02*
Y556626D01*
G01X165341Y554417D02*
X164617Y555141D01*
G01X165341Y548807D02*
Y554417D01*
G01X164991Y548457D02*
X165341Y548807D01*
G01X164991Y546701D02*
Y548457D01*
G01X165492Y546200D02*
X164991Y546701D01*
G01X165492Y538547D02*
Y546200D01*
G01X164759Y537814D02*
X165492Y538547D01*
G01X164759Y535774D02*
Y537814D01*
G01X165341Y535192D02*
X164759Y535774D01*
G01X165341Y530242D02*
Y535192D01*
G01X164828Y529729D02*
X165341Y530242D01*
G01X164828Y528028D02*
Y529729D01*
G01X165492Y527364D02*
X164828Y528028D01*
G01X132230Y586457D02*
X128880Y589807D01*
G01X132230Y584638D02*
Y586457D01*
G01X131992Y584400D02*
X132230Y584638D01*
G01X131992Y575838D02*
Y584400D01*
G01X132230Y575600D02*
X131992Y575838D01*
G01X132230Y574239D02*
Y575600D01*
G01X131080Y573089D02*
X132230Y574239D01*
G01X131080Y568367D02*
Y573089D01*
G01X132180Y567267D02*
X131080Y568367D01*
G01X132180Y565588D02*
Y567267D01*
G01X131992Y565400D02*
X132180Y565588D01*
G01X131992Y557288D02*
Y565400D01*
G01X132180Y557100D02*
X131992Y557288D01*
G01X132180Y555257D02*
Y557100D01*
G01X131030Y554107D02*
X132180Y555257D01*
G01X131030Y549857D02*
Y554107D01*
G01X132380Y548507D02*
X131030Y549857D01*
G01X132380Y546688D02*
Y548507D01*
G01X131992Y546300D02*
X132380Y546688D01*
G01X131992Y538088D02*
Y546300D01*
G01X132380Y537700D02*
X131992Y538088D01*
G01X132380Y536588D02*
Y537700D01*
G01X131030Y535238D02*
X132380Y536588D01*
G01X131030Y530617D02*
Y535238D01*
G01X132380Y529267D02*
X131030Y530617D01*
G01X132380Y527588D02*
Y529267D01*
G01X131992Y527200D02*
X132380Y527588D01*
G01X149291Y528299D02*
X148692Y527700D01*
G01X149291Y529431D02*
Y528299D01*
G01X147992Y530730D02*
X149291Y529431D01*
G01X147992Y535300D02*
Y530730D01*
G01X149543Y536851D02*
X147992Y535300D01*
G01X149543Y538349D02*
Y536851D01*
G01X148692Y539200D02*
X149543Y538349D01*
G01X148692Y546200D02*
Y539200D01*
G01X149280Y546788D02*
X148692Y546200D01*
G01X149280Y549057D02*
Y546788D01*
G01X148092Y550245D02*
X149280Y549057D01*
G01X148092Y553901D02*
Y550245D01*
G01X149335Y555144D02*
X148092Y553901D01*
G01X149335Y556745D02*
Y555144D01*
G01X148692Y557388D02*
X149335Y556745D01*
G01X148692Y565500D02*
Y557388D01*
G01X149268Y566076D02*
X148692Y565500D01*
G01X149268Y567209D02*
Y566076D01*
G01X147692Y568785D02*
X149268Y567209D01*
G01X147692Y572654D02*
Y568785D01*
G01X149280Y574242D02*
X147692Y572654D01*
G01X149280Y575500D02*
Y574242D01*
G01X148692Y576088D02*
X149280Y575500D01*
G01X148692Y583900D02*
Y576088D01*
G01X149592Y584800D02*
X148692Y583900D01*
G01X149592Y586045D02*
Y584800D01*
G01X146380Y589257D02*
X149592Y586045D01*
G01X128280Y528112D02*
X128692Y527700D01*
G01X128280Y529992D02*
Y528112D01*
G01X128530Y530242D02*
X128280Y529992D01*
G01X128530Y535192D02*
Y530242D01*
G01X128180Y535542D02*
X128530Y535192D01*
G01X128180Y537588D02*
Y535542D01*
G01X128692Y538100D02*
X128180Y537588D01*
G01X128692Y546500D02*
Y538100D01*
G01X128180Y547012D02*
X128692Y546500D01*
G01X128180Y548457D02*
Y547012D01*
G01X128530Y548807D02*
X128180Y548457D01*
G01X128530Y555007D02*
Y548807D01*
G01X128280Y555257D02*
X128530Y555007D01*
G01X128280Y557200D02*
Y555257D01*
G01X128692Y557612D02*
X128280Y557200D01*
G01X128692Y565200D02*
Y557612D01*
G01X128280Y565612D02*
X128692Y565200D01*
G01X128280Y567997D02*
Y565612D01*
G01X128780Y568497D02*
X128280Y567997D01*
G01X128780Y572656D02*
Y568497D01*
G01X128180Y573256D02*
X128780Y572656D01*
G01X128180Y575200D02*
Y573256D01*
G01X128692Y575712D02*
X128180Y575200D01*
G01X128692Y584000D02*
Y575712D01*
G01X128180Y584512D02*
X128692Y584000D01*
G01X128180Y587200D02*
Y584512D01*
G01X126666Y588714D02*
X128180Y587200D01*
G01X167996Y590400D02*
X169682Y588714D01*
G01X167996Y592092D02*
Y590400D01*
G01X168903Y592999D02*
X167996Y592092D01*
G01X168903Y594592D02*
Y592999D01*
G01X167759Y595736D02*
X168903Y594592D01*
G01X167759Y597156D02*
Y595736D01*
G01X168603Y598000D02*
X167759Y597156D01*
G01X168603Y599700D02*
Y598000D01*
G01X167759Y600544D02*
X168603Y599700D01*
G01X167759Y601756D02*
Y600544D01*
G01X168703Y602700D02*
X167759Y601756D01*
G01X168703Y603900D02*
Y602700D01*
G01X168104Y604499D02*
X168703Y603900D01*
G01X167124Y604499D02*
X168104D01*
G01X132959Y588364D02*
Y588714D01*
G01X131293Y604499D02*
X130313D01*
G01X131892Y603900D02*
X131293Y604499D01*
G01X131892Y602700D02*
Y603900D01*
G01X130948Y601756D02*
X131892Y602700D01*
G01X130948Y600544D02*
Y601756D01*
G01X131792Y599700D02*
X130948Y600544D01*
G01X131792Y598000D02*
Y599700D01*
G01X130948Y597156D02*
X131792Y598000D01*
G01X130948Y595736D02*
Y597156D01*
G01X132092Y594592D02*
X130948Y595736D01*
G01X132092Y592999D02*
Y594592D01*
G01X131185Y592092D02*
X132092Y592999D01*
G01X131185Y590400D02*
Y592092D01*
G01X132871Y588714D02*
X131185Y590400D01*
G01X132959Y588714D02*
X132871D01*
G01X158726Y605635D02*
X163391Y610300D01*
G01X158726Y595462D02*
Y605635D01*
G01X160431Y593757D02*
X158726Y595462D01*
G01X159191Y592517D02*
X160431Y593757D01*
G01X159191Y589607D02*
Y592517D01*
G01X165691Y592324D02*
X167124Y593757D01*
G01X165691Y589807D02*
Y592324D01*
G01X165419Y605949D02*
X169770Y610300D01*
G01X165419Y595462D02*
Y605949D01*
G01X167124Y593757D02*
X165419Y595462D01*
G01X157084Y588766D02*
Y588714D01*
G01X154810Y604499D02*
X153738D01*
G01X155510Y603799D02*
X154810Y604499D01*
G01X155510Y602525D02*
Y603799D01*
G01X154373Y601388D02*
X155510Y602525D01*
G01X154373Y600312D02*
Y601388D01*
G01X155385Y599300D02*
X154373Y600312D01*
G01X155385Y598100D02*
Y599300D01*
G01X154373Y597088D02*
X155385Y598100D01*
G01X154373Y596012D02*
Y597088D01*
G01X155485Y594900D02*
X154373Y596012D01*
G01X155485Y592267D02*
Y594900D01*
G01X155310Y592092D02*
X155485Y592267D01*
G01X155310Y590400D02*
Y592092D01*
G01X156996Y588714D02*
X155310Y590400D01*
G01X157084Y588714D02*
X156996D01*
G01X123155Y593292D02*
X123620Y593757D01*
G01X123155Y589296D02*
Y593292D01*
G01X121915Y605635D02*
X126580Y610300D01*
G01X121915Y595462D02*
Y605635D01*
G01X123620Y593757D02*
X121915Y595462D01*
G01X152033Y605649D02*
X157084Y610700D01*
G01X152033Y595462D02*
Y605649D01*
G01X153738Y593757D02*
X152033Y595462D01*
G01X152380Y592399D02*
X153738Y593757D01*
G01X152380Y589907D02*
Y592399D01*
G01X148117Y604499D02*
X147045D01*
G01X148817Y603799D02*
X148117Y604499D01*
G01X148817Y602525D02*
Y603799D01*
G01X147680Y601388D02*
X148817Y602525D01*
G01X147680Y600312D02*
Y601388D01*
G01X148692Y599300D02*
X147680Y600312D01*
G01X148692Y598100D02*
Y599300D01*
G01X147680Y597088D02*
X148692Y598100D01*
G01X147680Y596012D02*
Y597088D01*
G01X148792Y594900D02*
X147680Y596012D01*
G01X148792Y592267D02*
Y594900D01*
G01X148617Y592092D02*
X148792Y592267D01*
G01X148617Y590400D02*
Y592092D01*
G01X150303Y588714D02*
X148617Y590400D01*
G01X150391Y588714D02*
X150303D01*
G01X161503Y604499D02*
X160431D01*
G01X162103Y603899D02*
X161503Y604499D01*
G01X162103Y603001D02*
Y603899D01*
G01X161066Y601964D02*
X162103Y603001D01*
G01X161066Y600736D02*
Y601964D01*
G01X162003Y599799D02*
X161066Y600736D01*
G01X162003Y598401D02*
Y599799D01*
G01X161066Y597464D02*
X162003Y598401D01*
G01X161066Y596136D02*
Y597464D01*
G01X162203Y594999D02*
X161066Y596136D01*
G01X162203Y593100D02*
Y594999D01*
G01X161703Y592600D02*
X162203Y593100D01*
G01X161703Y590400D02*
Y592600D01*
G01X163389Y588714D02*
X161703Y590400D01*
G01X163477Y588714D02*
X163389D01*
G01X128608Y605949D02*
X132959Y610300D01*
G01X128608Y595462D02*
Y605949D01*
G01X130313Y593757D02*
X128608Y595462D01*
G01X128880Y592324D02*
X130313Y593757D01*
G01X128880Y589807D02*
Y592324D01*
G01X145340Y605649D02*
X150391Y610700D01*
G01X145340Y595462D02*
Y605649D01*
G01X147045Y593757D02*
X145340Y595462D01*
G01X146380Y593092D02*
Y589257D01*
G01X147045Y593757D02*
X146380Y593092D01*
G01X124692Y604499D02*
X123620D01*
G01X125292Y603899D02*
X124692Y604499D01*
G01X125292Y603001D02*
Y603899D01*
G01X124255Y601964D02*
X125292Y603001D01*
G01X124255Y600736D02*
Y601964D01*
G01X125192Y599799D02*
X124255Y600736D01*
G01X125192Y598401D02*
Y599799D01*
G01X124255Y597464D02*
X125192Y598401D01*
G01X124255Y596136D02*
Y597464D01*
G01X125392Y594999D02*
X124255Y596136D01*
G01X125392Y593100D02*
Y594999D01*
G01X124892Y592600D02*
X125392Y593100D01*
G01X124892Y590400D02*
Y592600D01*
G01X126578Y588714D02*
X124892Y590400D01*
G01X126666Y588714D02*
X126578D01*
G01X191796Y-8654D02*
X190549Y-9901D01*
G01X191796Y-7400D02*
Y-8654D01*
G01X193096Y-6100D02*
X191796Y-7400D01*
G01X194096Y-6100D02*
X193096D01*
G01X195896Y-4300D02*
X194096Y-6100D01*
G01X195896Y-2900D02*
Y-4300D01*
G01X195284Y-2288D02*
X195896Y-2900D01*
G01X195284Y10725D02*
Y-2288D01*
G01X193895Y12114D02*
X195284Y10725D01*
G01X191991Y14018D02*
X193895Y12114D01*
G01X191991Y15614D02*
Y14018D01*
G01X193434Y17057D02*
X191991Y15614D01*
G01X193434Y18293D02*
Y17057D01*
G01X195341Y20200D02*
X193434Y18293D01*
G01X195341Y28699D02*
Y20200D01*
G01X195891Y29249D02*
X195341Y28699D01*
G01X195891Y34601D02*
Y29249D01*
G01X204652Y29594D02*
Y34259D01*
G01X205802Y28444D02*
X204652Y29594D01*
G01X205802Y26309D02*
Y28444D01*
G01X203935Y24442D02*
X205802Y26309D01*
G01X203935Y17157D02*
Y24442D01*
G01X202814Y16036D02*
X203935Y17157D01*
G01X202814Y13100D02*
Y16036D01*
G01X205714Y10200D02*
X202814Y13100D01*
G01X205714Y8232D02*
Y10200D01*
G01X204181Y6699D02*
X205714Y8232D01*
G01X204181Y5500D02*
Y6699D01*
G01X205431Y4250D02*
X204181Y5500D01*
G01X205431Y3350D02*
Y4250D01*
G01X204081Y2000D02*
X205431Y3350D01*
G01X204081Y701D02*
Y2000D01*
G01X205714Y-932D02*
X204081Y701D01*
G01X205714Y-3233D02*
Y-932D01*
G01X206581Y-4100D02*
X205714Y-3233D01*
G01X191991Y28999D02*
Y34899D01*
G01X192791Y28199D02*
X191991Y28999D01*
G01X192791Y21499D02*
Y28199D01*
G01X190549Y19257D02*
X192791Y21499D01*
G01X190549Y17157D02*
Y19257D01*
G01X189428Y16036D02*
X190549Y17157D01*
G01X189428Y13100D02*
Y16036D01*
G01X192770Y9758D02*
X189428Y13100D01*
G01X192770Y8700D02*
Y9758D01*
G01X190970Y6900D02*
X192770Y8700D01*
G01X190970Y5325D02*
Y6900D01*
G01X192170Y4125D02*
X190970Y5325D01*
G01X192170Y2999D02*
Y4125D01*
G01X190970Y1799D02*
X192170Y2999D01*
G01X190970Y426D02*
Y1799D01*
G01X192328Y-932D02*
X190970Y426D01*
G01X192328Y-2133D02*
Y-932D01*
G01X193895Y-3700D02*
X192328Y-2133D01*
G01X229139D02*
X230706Y-3700D01*
G01X229139Y-932D02*
Y-2133D01*
G01X227781Y426D02*
X229139Y-932D01*
G01X227781Y1799D02*
Y426D01*
G01X228981Y2999D02*
X227781Y1799D01*
G01X228981Y4125D02*
Y2999D01*
G01X227781Y5325D02*
X228981Y4125D01*
G01X227781Y6900D02*
Y5325D01*
G01X229581Y8700D02*
X227781Y6900D01*
G01X229581Y9758D02*
Y8700D01*
G01X226239Y13100D02*
X229581Y9758D01*
G01X226239Y16036D02*
Y13100D01*
G01X227360Y17157D02*
X226239Y16036D01*
G01X229192Y18989D02*
X227360Y17157D01*
G01X229192Y28609D02*
Y18989D01*
G01X228892Y28909D02*
X229192Y28609D01*
G01X228892Y35001D02*
Y28909D01*
G01X185728Y-2226D02*
X187202Y-3700D01*
G01X185728Y-1132D02*
Y-2226D01*
G01X184295Y301D02*
X185728Y-1132D01*
G01X184295Y1524D02*
Y301D01*
G01X185795Y3024D02*
X184295Y1524D01*
G01X185795Y4376D02*
Y3024D01*
G01X184295Y5876D02*
X185795Y4376D01*
G01X184295Y6999D02*
Y5876D01*
G01X185970Y8674D02*
X184295Y6999D01*
G01X185970Y10059D02*
Y8674D01*
G01X182928Y13101D02*
X185970Y10059D01*
G01X182928Y16229D02*
Y13101D01*
G01X183856Y17157D02*
X182928Y16229D01*
G01X183856Y19379D02*
Y17157D01*
G01X185692Y21215D02*
X183856Y19379D01*
G01X185692Y28698D02*
Y21215D01*
G01X185291Y29099D02*
X185692Y28698D01*
G01X185291Y34899D02*
Y29099D01*
G01X197242Y-8347D02*
Y-9901D01*
G01X199489Y-6100D02*
X197242Y-8347D01*
G01X200713Y-6100D02*
X199489D01*
G01X202289Y-4524D02*
X200713Y-6100D01*
G01X202289Y-2900D02*
Y-4524D01*
G01X201514Y-2125D02*
X202289Y-2900D01*
G01X201514Y10888D02*
Y-2125D01*
G01X200288Y12114D02*
X201514Y10888D01*
G01X198302Y14100D02*
X200288Y12114D01*
G01X198302Y15514D02*
Y14100D01*
G01X201492Y18704D02*
X198302Y15514D01*
G01X201492Y28189D02*
Y18704D01*
G01X202152Y28849D02*
X201492Y28189D01*
G01X202152Y35049D02*
Y28849D01*
G01X221914Y-8654D02*
X220667Y-9901D01*
G01X221914Y-7400D02*
Y-8654D01*
G01X223214Y-6100D02*
X221914Y-7400D01*
G01X224214Y-6100D02*
X223214D01*
G01X226014Y-4300D02*
X224214Y-6100D01*
G01X226014Y-2900D02*
Y-4300D01*
G01X225402Y-2288D02*
X226014Y-2900D01*
G01X225402Y10725D02*
Y-2288D01*
G01X224013Y12114D02*
X225402Y10725D01*
G01X222202Y13925D02*
X224013Y12114D01*
G01X222202Y16014D02*
Y13925D01*
G01X225492Y19304D02*
X222202Y16014D01*
G01X225492Y28689D02*
Y19304D01*
G01X225892Y29089D02*
X225492Y28689D01*
G01X225892Y34901D02*
Y29089D01*
G01X228607Y-8654D02*
X227360Y-9901D01*
G01X228607Y-7400D02*
Y-8654D01*
G01X229907Y-6100D02*
X228607Y-7400D01*
G01X230907Y-6100D02*
X229907D01*
G01X232707Y-4300D02*
X230907Y-6100D01*
G01X230706Y12114D02*
X232095Y10725D01*
G01X228802Y14018D02*
X230706Y12114D01*
G01X228802Y15614D02*
Y14018D01*
G01X232152Y18964D02*
X228802Y15614D01*
G01X198302Y29391D02*
Y34299D01*
G01X199202Y28491D02*
X198302Y29391D01*
G01X199202Y20109D02*
Y28491D01*
G01X197242Y18149D02*
X199202Y20109D01*
G01X197242Y17157D02*
Y18149D01*
G01X196314Y16229D02*
X197242Y17157D01*
G01X196314Y13101D02*
Y16229D01*
G01X199114Y10301D02*
X196314Y13101D01*
G01X199114Y8432D02*
Y10301D01*
G01X197731Y7049D02*
X199114Y8432D01*
G01X197731Y5650D02*
Y7049D01*
G01X199181Y4200D02*
X197731Y5650D01*
G01X199181Y3000D02*
Y4200D01*
G01X197681Y1500D02*
X199181Y3000D01*
G01X197681Y301D02*
Y1500D01*
G01X199114Y-1132D02*
X197681Y301D01*
G01X199114Y-3012D02*
Y-1132D01*
G01X200202Y-4100D02*
X199114Y-3012D01*
G01X171691Y25499D02*
Y37200D01*
G01X171243Y10641D02*
X169770Y12114D01*
G01X171243Y-2484D02*
Y10641D01*
G01X171859Y-3100D02*
X171243Y-2484D01*
G01X171859Y-4444D02*
Y-3100D01*
G01X170403Y-5900D02*
X171859Y-4444D01*
G01X222539Y-2226D02*
X224013Y-3700D01*
G01X222539Y-1132D02*
Y-2226D01*
G01X221106Y301D02*
X222539Y-1132D01*
G01X221106Y1524D02*
Y301D01*
G01X222606Y3024D02*
X221106Y1524D01*
G01X222606Y4376D02*
Y3024D01*
G01X221106Y5876D02*
X222606Y4376D01*
G01X221106Y6999D02*
Y5876D01*
G01X222781Y8674D02*
X221106Y6999D01*
G01X222781Y10059D02*
Y8674D01*
G01X219739Y13101D02*
X222781Y10059D01*
G01X219739Y16229D02*
Y13101D01*
G01X220667Y17157D02*
X219739Y16229D01*
G01X222492Y18982D02*
X220667Y17157D01*
G01X222492Y28709D02*
Y18982D01*
G01X222102Y29099D02*
X222492Y28709D01*
G01X222102Y34811D02*
Y29099D01*
G01X203935Y-7779D02*
Y-9901D01*
G01X205814Y-5900D02*
X203935Y-7779D01*
G01X207214Y-5900D02*
X205814D01*
G01X208670Y-4444D02*
X207214Y-5900D01*
G01X208670Y-3100D02*
Y-4444D01*
G01X208054Y-2484D02*
X208670Y-3100D01*
G01X208054Y10641D02*
Y-2484D01*
G01X206581Y12114D02*
X208054Y10641D01*
G01X204508Y14187D02*
X206581Y12114D01*
G01X204508Y15216D02*
Y14187D01*
G01X205792Y16500D02*
X204508Y15216D01*
G01X205792Y22601D02*
Y16500D01*
G01X208502Y25311D02*
X205792Y22601D01*
G01X208502Y36810D02*
Y25311D01*
G01X185103Y-8654D02*
X183856Y-9901D01*
G01X185103Y-7400D02*
Y-8654D01*
G01X186403Y-6100D02*
X185103Y-7400D01*
G01X187403Y-6100D02*
X186403D01*
G01X189203Y-4300D02*
X187403Y-6100D01*
G01X189203Y-2900D02*
Y-4300D01*
G01X188591Y-2288D02*
X189203Y-2900D01*
G01X188591Y10725D02*
Y-2288D01*
G01X187202Y12114D02*
X188591Y10725D01*
G01X185391Y13925D02*
X187202Y12114D01*
G01X185391Y16014D02*
Y13925D01*
G01X186841Y17464D02*
X185391Y16014D01*
G01X186841Y18828D02*
Y17464D01*
G01X188691Y20678D02*
X186841Y18828D01*
G01X188691Y28699D02*
Y20678D01*
G01X189491Y29499D02*
X188691Y28699D01*
G01X189491Y34401D02*
Y29499D01*
G01X195291Y35201D02*
X195891Y34601D01*
G01X195291Y36799D02*
Y35201D01*
G01X195992Y37500D02*
X195291Y36799D01*
G01X195992Y45399D02*
Y37500D01*
G01X195291Y46100D02*
X195992Y45399D01*
G01X195291Y48114D02*
Y46100D01*
G01X195991Y48814D02*
X195291Y48114D01*
G01X195991Y53214D02*
Y48814D01*
G01X195341Y53864D02*
X195991Y53214D01*
G01X195341Y66499D02*
Y53864D01*
G01X195891Y67049D02*
X195341Y66499D01*
G01X195891Y72501D02*
Y67049D01*
G01X195291Y73101D02*
X195891Y72501D01*
G01X195291Y75199D02*
Y73101D01*
G01X195892Y75800D02*
X195291Y75199D01*
G01X195892Y83299D02*
Y75800D01*
G01X195291Y83900D02*
X195892Y83299D01*
G01X195291Y85914D02*
Y83900D01*
G01X195991Y86614D02*
X195291Y85914D01*
G01X195991Y91274D02*
Y86614D01*
G01X195391Y91874D02*
X195991Y91274D01*
G01X195391Y112100D02*
Y91874D01*
G01X205792Y92100D02*
Y108316D01*
G01X204652Y90960D02*
X205792Y92100D01*
G01X204652Y86714D02*
Y90960D01*
G01X206002Y85364D02*
X204652Y86714D01*
G01X206002Y84010D02*
Y85364D01*
G01X205192Y83200D02*
X206002Y84010D01*
G01X205192Y75400D02*
Y83200D01*
G01X206002Y74590D02*
X205192Y75400D01*
G01X206002Y73409D02*
Y74590D01*
G01X204652Y72059D02*
X206002Y73409D01*
G01X204652Y67417D02*
Y72059D01*
G01X206002Y66067D02*
X204652Y67417D01*
G01X206002Y54510D02*
Y66067D01*
G01X204652Y53160D02*
X206002Y54510D01*
G01X204652Y48914D02*
Y53160D01*
G01X206002Y47564D02*
X204652Y48914D01*
G01X206002Y46400D02*
Y47564D01*
G01X205392Y45790D02*
X206002Y46400D01*
G01X205392Y37400D02*
Y45790D01*
G01X206002Y36790D02*
X205392Y37400D01*
G01X206002Y35609D02*
Y36790D01*
G01X204652Y34259D02*
X206002Y35609D01*
G01X192366Y91589D02*
Y114674D01*
G01X191891Y91114D02*
X192366Y91589D01*
G01X191891Y86414D02*
Y91114D01*
G01X192491Y85814D02*
X191891Y86414D01*
G01X192491Y84000D02*
Y85814D01*
G01X191992Y83501D02*
X192491Y84000D01*
G01X191992Y75400D02*
Y83501D01*
G01X192491Y74901D02*
X191992Y75400D01*
G01X192491Y73099D02*
Y74901D01*
G01X191991Y72599D02*
X192491Y73099D01*
G01X191991Y66799D02*
Y72599D01*
G01X192841Y65949D02*
X191991Y66799D01*
G01X192841Y54264D02*
Y65949D01*
G01X191891Y53314D02*
X192841Y54264D01*
G01X191891Y48614D02*
Y53314D01*
G01X192491Y48014D02*
X191891Y48614D01*
G01X192491Y46300D02*
Y48014D01*
G01X191892Y45701D02*
X192491Y46300D01*
G01X191892Y37500D02*
Y45701D01*
G01X192491Y36901D02*
X191892Y37500D01*
G01X192491Y35399D02*
Y36901D01*
G01X191991Y34899D02*
X192491Y35399D01*
G01X229302Y35411D02*
X228892Y35001D01*
G01X229302Y36990D02*
Y35411D01*
G01X228736Y37556D02*
X229302Y36990D01*
G01X228736Y45534D02*
Y37556D01*
G01X229302Y46100D02*
X228736Y45534D01*
G01X229302Y48014D02*
Y46100D01*
G01X228702Y48614D02*
X229302Y48014D01*
G01X228702Y53314D02*
Y48614D01*
G01X229652Y54264D02*
X228702Y53314D01*
G01X229652Y65949D02*
Y54264D01*
G01X228802Y66799D02*
X229652Y65949D01*
G01X228802Y72611D02*
Y66799D01*
G01X229302Y73111D02*
X228802Y72611D01*
G01X229302Y74990D02*
Y73111D01*
G01X228892Y75400D02*
X229302Y74990D01*
G01X228892Y83590D02*
Y75400D01*
G01X229302Y84000D02*
X228892Y83590D01*
G01X229302Y85814D02*
Y84000D01*
G01X228702Y86414D02*
X229302Y85814D01*
G01X228702Y91114D02*
Y86414D01*
G01X229353Y91765D02*
X228702Y91114D01*
G01X229353Y109611D02*
Y91765D01*
G01X186091Y35699D02*
X185291Y34899D01*
G01X186091Y37000D02*
Y35699D01*
G01X185292Y37799D02*
X186091Y37000D01*
G01X185292Y45500D02*
Y37799D01*
G01X186091Y46299D02*
X185292Y45500D01*
G01X186091Y47914D02*
Y46299D01*
G01X185291Y48714D02*
X186091Y47914D01*
G01X185291Y53414D02*
Y48714D01*
G01X185691Y53814D02*
X185291Y53414D01*
G01X185691Y66499D02*
Y53814D01*
G01X185291Y66899D02*
X185691Y66499D01*
G01X185291Y72599D02*
Y66899D01*
G01X186091Y73399D02*
X185291Y72599D01*
G01X186091Y74901D02*
Y73399D01*
G01X185492Y75500D02*
X186091Y74901D01*
G01X185492Y83601D02*
Y75500D01*
G01X186091Y84200D02*
X185492Y83601D01*
G01X186091Y85714D02*
Y84200D01*
G01X185291Y86514D02*
X186091Y85714D01*
G01X185291Y91214D02*
Y86514D01*
G01X185691Y91614D02*
X185291Y91214D01*
G01X185691Y106602D02*
Y91614D01*
G01X201802Y35399D02*
X202152Y35049D01*
G01X201802Y37310D02*
Y35399D01*
G01X202392Y37900D02*
X201802Y37310D01*
G01X202392Y45410D02*
Y37900D01*
G01X201802Y46000D02*
X202392Y45410D01*
G01X201802Y48314D02*
Y46000D01*
G01X202152Y48664D02*
X201802Y48314D01*
G01X202152Y53614D02*
Y48664D01*
G01X201902Y53864D02*
X202152Y53614D01*
G01X201902Y66399D02*
Y53864D01*
G01X202152Y66649D02*
X201902Y66399D01*
G01X202152Y72849D02*
Y66649D01*
G01X201802Y73199D02*
X202152Y72849D01*
G01X201802Y75210D02*
Y73199D01*
G01X202392Y75800D02*
X201802Y75210D01*
G01X202392Y83310D02*
Y75800D01*
G01X201802Y83900D02*
X202392Y83310D01*
G01X201802Y86114D02*
Y83900D01*
G01X202152Y86464D02*
X201802Y86114D01*
G01X202152Y91414D02*
Y86464D01*
G01X202135Y91431D02*
X202152Y91414D01*
G01X202135Y108957D02*
Y91431D01*
G01X225492Y35301D02*
X225892Y34901D01*
G01X225492Y37300D02*
Y35301D01*
G01X225792Y37600D02*
X225492Y37300D01*
G01X225792Y45900D02*
Y37600D01*
G01X225492Y46200D02*
X225792Y45900D01*
G01X225492Y48004D02*
Y46200D01*
G01X226202Y48714D02*
X225492Y48004D01*
G01X226202Y53214D02*
Y48714D01*
G01X225502Y53914D02*
X226202Y53214D01*
G01X225502Y66499D02*
Y53914D01*
G01X226302Y67299D02*
X225502Y66499D01*
G01X226302Y72191D02*
Y67299D01*
G01X225402Y73091D02*
X226302Y72191D01*
G01X225402Y74810D02*
Y73091D01*
G01X225992Y75400D02*
X225402Y74810D01*
G01X225992Y83310D02*
Y75400D01*
G01X225402Y83900D02*
X225992Y83310D01*
G01X225402Y85714D02*
Y83900D01*
G01X226202Y86514D02*
X225402Y85714D01*
G01X226202Y91014D02*
Y86514D01*
G01X225492Y91724D02*
X226202Y91014D01*
G01X225492Y97077D02*
Y91724D01*
G01X199592Y92504D02*
Y110528D01*
G01X198302Y91214D02*
X199592Y92504D01*
G01X198302Y86414D02*
Y91214D01*
G01X199302Y85414D02*
X198302Y86414D01*
G01X199302Y84200D02*
Y85414D01*
G01X198592Y83490D02*
X199302Y84200D01*
G01X198592Y75500D02*
Y83490D01*
G01X199302Y74790D02*
X198592Y75500D01*
G01X199302Y73099D02*
Y74790D01*
G01X198302Y72099D02*
X199302Y73099D01*
G01X198302Y67191D02*
Y72099D01*
G01X199202Y66291D02*
X198302Y67191D01*
G01X199202Y54314D02*
Y66291D01*
G01X198302Y53414D02*
X199202Y54314D01*
G01X198302Y48614D02*
Y53414D01*
G01X199302Y47614D02*
X198302Y48614D01*
G01X199302Y46310D02*
Y47614D01*
G01X198592Y45600D02*
X199302Y46310D01*
G01X198592Y37910D02*
Y45600D01*
G01X199302Y37200D02*
X198592Y37910D01*
G01X199302Y35299D02*
Y37200D01*
G01X198302Y34299D02*
X199302Y35299D01*
G01X171691Y83800D02*
Y101516D01*
G01X172292Y83199D02*
X171691Y83800D01*
G01X172292Y75400D02*
Y83199D01*
G01X171691Y74799D02*
X172292Y75400D01*
G01X171691Y46251D02*
Y74799D01*
G01X172292Y45650D02*
X171691Y46251D01*
G01X172292Y37801D02*
Y45650D01*
G01X171691Y37200D02*
X172292Y37801D01*
G01X222492Y35201D02*
X222102Y34811D01*
G01X222492Y37300D02*
Y35201D01*
G01X222092Y37700D02*
X222492Y37300D01*
G01X222092Y45600D02*
Y37700D01*
G01X222492Y46000D02*
X222092Y45600D01*
G01X222492Y48324D02*
Y46000D01*
G01X222102Y48714D02*
X222492Y48324D01*
G01X222102Y53414D02*
Y48714D01*
G01X222502Y53814D02*
X222102Y53414D01*
G01X222502Y66499D02*
Y53814D01*
G01X222102Y66899D02*
X222502Y66499D01*
G01X222102Y72611D02*
Y66899D01*
G01X222902Y73411D02*
X222102Y72611D01*
G01X222902Y74790D02*
Y73411D01*
G01X222192Y75500D02*
X222902Y74790D01*
G01X222192Y83490D02*
Y75500D01*
G01X222902Y84200D02*
X222192Y83490D01*
G01X222902Y85714D02*
Y84200D01*
G01X222102Y86514D02*
X222902Y85714D01*
G01X222102Y91214D02*
Y86514D01*
G01X222492Y91604D02*
X222102Y91214D01*
G01X222492Y96556D02*
Y91604D01*
G01X209192Y37500D02*
X208502Y36810D01*
G01X209192Y45510D02*
Y37500D01*
G01X208502Y46200D02*
X209192Y45510D01*
G01X208502Y74810D02*
Y46200D01*
G01X209092Y75400D02*
X208502Y74810D01*
G01X209092Y83462D02*
Y75400D01*
G01X208502Y84052D02*
X209092Y83462D01*
G01X208502Y94290D02*
Y84052D01*
G01X207892Y94900D02*
X208502Y94290D01*
G01X188591Y35301D02*
X189491Y34401D01*
G01X188591Y37300D02*
Y35301D01*
G01X188992Y37701D02*
X188591Y37300D01*
G01X188992Y45700D02*
Y37701D01*
G01X188591Y46101D02*
X188992Y45700D01*
G01X188591Y47914D02*
Y46101D01*
G01X189391Y48714D02*
X188591Y47914D01*
G01X189391Y53214D02*
Y48714D01*
G01X188691Y53914D02*
X189391Y53214D01*
G01X188691Y66499D02*
Y53914D01*
G01X189491Y67299D02*
X188691Y66499D01*
G01X189491Y72301D02*
Y67299D01*
G01X188591Y73201D02*
X189491Y72301D01*
G01X188591Y74899D02*
Y73201D01*
G01X189192Y75500D02*
X188591Y74899D01*
G01X189192Y83499D02*
Y75500D01*
G01X188591Y84100D02*
X189192Y83499D01*
G01X188591Y85714D02*
Y84100D01*
G01X189391Y86514D02*
X188591Y85714D01*
G01X189391Y91014D02*
Y86514D01*
G01X188691Y91714D02*
X189391Y91014D01*
G01X188691Y108102D02*
Y91714D01*
G01X199510Y116219D02*
X195391Y112100D01*
G01X199510Y140819D02*
Y116219D01*
G01X207992Y149301D02*
X199510Y140819D01*
G01X207992Y152065D02*
Y149301D01*
G01X209128Y153201D02*
X207992Y152065D01*
G01X209920Y153201D02*
X209128D01*
G01X210960Y152161D02*
X209920Y153201D01*
G01X211752Y152162D02*
X210960Y152161D01*
G01X212771Y153181D02*
X211752Y152162D01*
G01X212771Y153973D02*
Y153181D01*
G01X211731Y155013D02*
X212771Y153973D01*
G01X211730Y155803D02*
X211731Y155013D01*
G01X212750Y156823D02*
X211730Y155803D01*
G01X214582Y155783D02*
X213542Y156823D01*
G01X215374Y155784D02*
X214582Y155783D01*
G01X216393Y156803D02*
X215374Y155784D01*
G01X208592Y135532D02*
X252834Y179774D01*
G01X208592Y111116D02*
Y135532D01*
G01X205792Y108316D02*
X208592Y111116D01*
G01X203883Y151033D02*
X224773Y171923D01*
G01X203883Y150241D02*
Y151033D01*
G01X204462Y149662D02*
X203883Y150241D01*
G01X204462Y148870D02*
Y149662D01*
G01X203443Y147851D02*
X204462Y148870D01*
G01X202651Y147851D02*
X203443D01*
G01X202072Y148430D02*
X202651Y147851D01*
G01X201280Y148430D02*
X202072D01*
G01X200261Y147411D02*
X201280Y148430D01*
G01X200261Y146619D02*
Y147411D01*
G01X200840Y146040D02*
X200261Y146619D01*
G01X200840Y145248D02*
Y146040D01*
G01X199821Y144229D02*
X200840Y145248D01*
G01X199029Y144229D02*
X199821D01*
G01X198450Y144808D02*
X199029Y144229D01*
G01X197658Y144808D02*
X198450D01*
G01X195092Y142242D02*
X197658Y144808D01*
G01X195092Y117400D02*
Y142242D01*
G01X192366Y114674D02*
X195092Y117400D01*
G01X228853Y110111D02*
X229353Y109611D01*
G01X227476Y110111D02*
X228853D01*
G01X226402Y111185D02*
X227476Y110111D01*
G01X226402Y112221D02*
Y111185D01*
G01X227012Y112831D02*
X226402Y112221D01*
G01X228764Y112831D02*
X227012D01*
G01X229374Y113441D02*
X228764Y112831D01*
G01X229374Y114416D02*
Y113441D01*
G01X228764Y115026D02*
X229374Y114416D01*
G01X227012Y115026D02*
X228764D01*
G01X226402Y115636D02*
X227012Y115026D01*
G01X226402Y116565D02*
Y115636D01*
G01X227012Y117175D02*
X226402Y116565D01*
G01X228764Y117175D02*
X227012D01*
G01X229374Y117785D02*
X228764Y117175D01*
G01X229374Y119034D02*
Y117785D01*
G01X228764Y119644D02*
X229374Y119034D01*
G01X227012Y119644D02*
X228764D01*
G01X226402Y120254D02*
X227012Y119644D01*
G01X226402Y125010D02*
Y120254D01*
G01X243425Y142033D02*
X226402Y125010D01*
G01X183884Y108409D02*
X185691Y106602D01*
G01X180757Y108409D02*
X183884D01*
G01X179957Y109209D02*
X180757Y108409D01*
G01X179957Y110809D02*
Y109209D01*
G01X180757Y111609D02*
X179957Y110809D01*
G01X183292Y111609D02*
X180757D01*
G01X184092Y112409D02*
X183292Y111609D01*
G01X184092Y114009D02*
Y112409D01*
G01X183292Y114809D02*
X184092Y114009D01*
G01X180757Y114809D02*
X183292D01*
G01X179957Y115609D02*
X180757Y114809D01*
G01X179957Y117209D02*
Y115609D01*
G01X180757Y118009D02*
X179957Y117209D01*
G01X183192Y118009D02*
X180757D01*
G01X183892Y118709D02*
X183192Y118009D01*
G01X183892Y142500D02*
Y118709D01*
G01X184692Y143300D02*
X183892Y142500D01*
G01X186292Y143300D02*
X184692D01*
G01X187092Y142500D02*
X186292Y143300D01*
G01X187092Y135500D02*
Y142500D01*
G01X187892Y134700D02*
X187092Y135500D01*
G01X189492Y134700D02*
X187892D01*
G01X190292Y135500D02*
X189492Y134700D01*
G01X190292Y145214D02*
Y135500D01*
G01X193163Y148085D02*
X190292Y145214D01*
G01X193163Y148877D02*
Y148085D01*
G01X191862Y150178D02*
X193163Y148877D01*
G01X191862Y150970D02*
Y150178D01*
G01X192881Y151989D02*
X191862Y150970D01*
G01X193673Y151989D02*
X192881D01*
G01X194974Y150688D02*
X193673Y151989D01*
G01X195766Y150688D02*
X194974D01*
G01X214420Y169342D02*
X195766Y150688D01*
G01X206092Y112914D02*
X202135Y108957D01*
G01X206092Y136690D02*
Y112914D01*
G01X248029Y178627D02*
X206092Y136690D01*
G01X223702Y98867D02*
X225492Y97077D01*
G01X223702Y100852D02*
Y98867D01*
G01X224312Y101462D02*
X223702Y100852D01*
G01X225380Y101462D02*
X224312D01*
G01X225990Y102072D02*
X225380Y101462D01*
G01X225990Y103292D02*
Y102072D01*
G01X225380Y103902D02*
X225990Y103292D01*
G01X224312Y103902D02*
X225380D01*
G01X223702Y104512D02*
X224312Y103902D01*
G01X223702Y105732D02*
Y104512D01*
G01X224312Y106342D02*
X223702Y105732D01*
G01X225380Y106342D02*
X224312D01*
G01X225990Y106952D02*
X225380Y106342D01*
G01X225990Y108172D02*
Y106952D01*
G01X225380Y108782D02*
X225990Y108172D01*
G01X224312Y108782D02*
X225380D01*
G01X223702Y109392D02*
X224312Y108782D01*
G01X223702Y126010D02*
Y109392D01*
G01X239388Y141696D02*
X223702Y126010D01*
G01X231243Y122309D02*
X231853Y121699D01*
G01X229161Y122309D02*
X231243D01*
G01X228551Y122919D02*
X229161Y122309D01*
G01X228551Y124139D02*
Y122919D01*
G01X229161Y124749D02*
X228551Y124139D01*
G01X231243Y124749D02*
X229161D01*
G01X231853Y125359D02*
X231243Y124749D01*
G01X203592Y138304D02*
X245606Y180318D01*
G01X203592Y114528D02*
Y138304D01*
G01X199592Y110528D02*
X203592Y114528D01*
G01X170253Y144236D02*
X189817Y163800D01*
G01X170253Y102954D02*
Y144236D01*
G01X171691Y101516D02*
X170253Y102954D01*
G01X221202Y97846D02*
X222492Y96556D01*
G01X221202Y130509D02*
Y97846D01*
G01X222691Y131998D02*
X221202Y130509D01*
G01X223553Y131998D02*
X222691D01*
G01X224757Y130794D02*
X223553Y131998D01*
G01X225619Y130794D02*
X224757D01*
G01X226483Y131658D02*
X225619Y130794D01*
G01X226483Y132520D02*
Y131658D01*
G01X225279Y133724D02*
X226483Y132520D01*
G01X225279Y134586D02*
Y133724D01*
G01X226143Y135450D02*
X225279Y134586D01*
G01X227005Y135450D02*
X226143D01*
G01X228209Y134246D02*
X227005Y135450D01*
G01X229071Y134246D02*
X228209D01*
G01X229935Y135110D02*
X229071Y134246D01*
G01X229935Y135972D02*
Y135110D01*
G01X228731Y137176D02*
X229935Y135972D01*
G01X228731Y138038D02*
Y137176D01*
G01X229595Y138902D02*
X228731Y138038D01*
G01X230457Y138902D02*
X229595D01*
G01X231661Y137698D02*
X230457Y138902D01*
G01X207892Y106800D02*
Y94900D01*
G01X211092Y110000D02*
X207892Y106800D01*
G01X211092Y134556D02*
Y110000D01*
G01X259597Y183061D02*
X211092Y134556D01*
G01X186392Y110401D02*
X188691Y108102D01*
G01X186392Y131100D02*
Y110401D01*
G01X187192Y131900D02*
X186392Y131100D01*
G01X188792Y131900D02*
X187192D01*
G01X189592Y131100D02*
X188792Y131900D01*
G01X189592Y120300D02*
Y131100D01*
G01X190392Y119500D02*
X189592Y120300D01*
G01X191992Y119500D02*
X190392D01*
G01X192792Y120300D02*
X191992Y119500D01*
G01X192792Y143784D02*
Y120300D01*
G01X219595Y170587D02*
X192792Y143784D01*
G01X181775Y183615D02*
X231700Y233540D01*
G01X181775Y177027D02*
Y183615D01*
G01X180402Y175654D02*
X181775Y177027D01*
G01X179540Y175654D02*
X180402D01*
G01X177385Y177809D02*
X179540Y175654D01*
G01X176523Y177809D02*
X177385D01*
G01X175659Y176945D02*
X176523Y177809D01*
G01X175659Y176083D02*
Y176945D01*
G01X177814Y173928D02*
X175659Y176083D01*
G01X177814Y173066D02*
Y173928D01*
G01X176950Y172202D02*
X177814Y173066D01*
G01X176088Y172202D02*
X176950D01*
G01X173933Y174357D02*
X176088Y172202D01*
G01X173071Y174357D02*
X173933D01*
G01X172207Y173493D02*
X173071Y174357D01*
G01X172207Y172631D02*
Y173493D01*
G01X174362Y170476D02*
X172207Y172631D01*
G01X174362Y169614D02*
Y170476D01*
G01X213542Y156823D02*
X212750D01*
G01X216393Y157595D02*
Y156803D01*
G01X215353Y158635D02*
X216393Y157595D01*
G01X215352Y159425D02*
X215353Y158635D01*
G01X217624Y161697D02*
X215352Y159425D01*
G01X218486Y161697D02*
X217624D01*
G01X220056Y160127D02*
X218486Y161697D01*
G01X220919Y160127D02*
X220056D01*
G01X221783Y160991D02*
X220919Y160127D01*
G01X221783Y161852D02*
Y160991D01*
G01X220212Y163423D02*
X221783Y161852D01*
G01X220212Y164285D02*
Y163423D01*
G01X221076Y165149D02*
X220212Y164285D01*
G01X221938Y165149D02*
X221076D01*
G01X223424Y163663D02*
X221938Y165149D01*
G01X224286Y163663D02*
X223424D01*
G01X225150Y164527D02*
X224286Y163663D01*
G01X225150Y165389D02*
Y164527D01*
G01X223664Y166875D02*
X225150Y165389D01*
G01X223664Y167737D02*
Y166875D01*
G01X224528Y168601D02*
X223664Y167737D01*
G01X225390Y168601D02*
X224528D01*
G01X226876Y167115D02*
X225390Y168601D01*
G01X227738Y167115D02*
X226876D01*
G01X228602Y167979D02*
X227738Y167115D01*
G01X228602Y168841D02*
Y167979D01*
G01X227116Y170327D02*
X228602Y168841D01*
G01X227116Y171189D02*
Y170327D01*
G01X227980Y172053D02*
X227116Y171189D01*
G01X228842Y172053D02*
X227980D01*
G01X230328Y170567D02*
X228842Y172053D01*
G01X231190Y170567D02*
X230328D01*
G01X232054Y171431D02*
X231190Y170567D01*
G01X230568Y173779D02*
X232054Y172293D01*
G01X230568Y174641D02*
Y173779D01*
G01X231432Y175505D02*
X230568Y174641D01*
G01X231026Y182930D02*
X231888D01*
G01X230162Y182066D02*
X231026Y182930D01*
G01X230162Y181204D02*
Y182066D01*
G01X231677Y179689D02*
X230162Y181204D01*
G01X230813Y177963D02*
X231677Y178827D01*
G01X229951Y177963D02*
X230813D01*
G01X228436Y179478D02*
X229951Y177963D01*
G01X227574Y179478D02*
X228436D01*
G01X226710Y178614D02*
X227574Y179478D01*
G01X226710Y177752D02*
Y178614D01*
G01X228225Y176237D02*
X226710Y177752D01*
G01X228225Y175375D02*
Y176237D01*
G01X227361Y174511D02*
X228225Y175375D01*
G01X226499Y174511D02*
X227361D01*
G01X224984Y176026D02*
X226499Y174511D01*
G01X224122Y176026D02*
X224984D01*
G01X223258Y175162D02*
X224122Y176026D01*
G01X223258Y174300D02*
Y175162D01*
G01X224773Y172785D02*
X223258Y174300D01*
G01X224773Y171923D02*
Y172785D01*
G01X214420Y174194D02*
Y169342D01*
G01X257559Y217333D02*
X214420Y174194D01*
G01X227150Y216954D02*
X224995Y219109D01*
G01X227150Y216092D02*
Y216954D01*
G01X226286Y215228D02*
X227150Y216092D01*
G01X225424Y215228D02*
X226286D01*
G01X223269Y217383D02*
X225424Y215228D01*
G01X222407Y217383D02*
X223269D01*
G01X221543Y216519D02*
X222407Y217383D01*
G01X221543Y215657D02*
Y216519D01*
G01X223698Y213502D02*
X221543Y215657D01*
G01X223698Y212640D02*
Y213502D01*
G01X222834Y211776D02*
X223698Y212640D01*
G01X221972Y211776D02*
X222834D01*
G01X219817Y213931D02*
X221972Y211776D01*
G01X218955Y213931D02*
X219817D01*
G01X218091Y213067D02*
X218955Y213931D01*
G01X218091Y212205D02*
Y213067D01*
G01X220246Y210050D02*
X218091Y212205D01*
G01X220246Y209188D02*
Y210050D01*
G01X219382Y208324D02*
X220246Y209188D01*
G01X218520Y208324D02*
X219382D01*
G01X216365Y210479D02*
X218520Y208324D01*
G01X215503Y210479D02*
X216365D01*
G01X214639Y209615D02*
X215503Y210479D01*
G01X214639Y208753D02*
Y209615D01*
G01X216794Y206598D02*
X214639Y208753D01*
G01X216794Y205736D02*
Y206598D01*
G01X200846Y174829D02*
X255059Y229042D01*
G01X200846Y170949D02*
Y174829D01*
G01X193697Y163800D02*
X200846Y170949D01*
G01X189817Y163800D02*
X193697D01*
G01X211496Y209800D02*
X232768Y231072D01*
G01X211496Y203821D02*
Y209800D01*
G01X209803Y202128D02*
X211496Y203821D01*
G01X208941Y202128D02*
X209803D01*
G01X206968Y204101D02*
X208941Y202128D01*
G01X206106Y204101D02*
X206968D01*
G01X205242Y203237D02*
X206106Y204101D01*
G01X205242Y202375D02*
Y203237D01*
G01X207215Y200402D02*
X205242Y202375D01*
G01X207215Y199540D02*
Y200402D01*
G01X206351Y198676D02*
X207215Y199540D01*
G01X205489Y198676D02*
X206351D01*
G01X203516Y200649D02*
X205489Y198676D01*
G01X202654Y200649D02*
X203516D01*
G01X201790Y199785D02*
X202654Y200649D01*
G01X201790Y198923D02*
Y199785D01*
G01X203763Y196950D02*
X201790Y198923D01*
G01X203763Y196088D02*
Y196950D01*
G01X202899Y195224D02*
X203763Y196088D01*
G01X202037Y195224D02*
X202899D01*
G01X200064Y197197D02*
X202037Y195224D01*
G01X199202Y197197D02*
X200064D01*
G01X198338Y196333D02*
X199202Y197197D01*
G01X198338Y195471D02*
Y196333D01*
G01X200311Y193498D02*
X198338Y195471D01*
G01X200311Y192636D02*
Y193498D01*
G01X199447Y191772D02*
X200311Y192636D01*
G01X198585Y191772D02*
X199447D01*
G01X196612Y193745D02*
X198585Y191772D01*
G01X195750Y193745D02*
X196612D01*
G01X194886Y192881D02*
X195750Y193745D01*
G01X194886Y192019D02*
Y192881D01*
G01X196859Y190046D02*
X194886Y192019D01*
G01X196859Y189184D02*
Y190046D01*
G01X195995Y188320D02*
X196859Y189184D01*
G01X195133Y188320D02*
X195995D01*
G01X193160Y190293D02*
X195133Y188320D01*
G01X192298Y190293D02*
X193160D01*
G01X191434Y189429D02*
X192298Y190293D01*
G01X191434Y188567D02*
Y189429D01*
G01X193407Y186594D02*
X191434Y188567D01*
G01X193407Y185732D02*
Y186594D01*
G01X192543Y184868D02*
X193407Y185732D01*
G01X191681Y184868D02*
X192543D01*
G01X189708Y186841D02*
X191681Y184868D01*
G01X188846Y186841D02*
X189708D01*
G01X187982Y185977D02*
X188846Y186841D01*
G01X187982Y185115D02*
Y185977D01*
G01X189955Y183142D02*
X187982Y185115D01*
G01X189955Y182280D02*
Y183142D01*
G01X189091Y181416D02*
X189955Y182280D01*
G01X188229Y181416D02*
X189091D01*
G01X186256Y183389D02*
X188229Y181416D01*
G01X185394Y183389D02*
X186256D01*
G01X184530Y182525D02*
X185394Y183389D01*
G01X184530Y181663D02*
Y182525D01*
G01X186503Y179690D02*
X184530Y181663D01*
G01X186503Y178828D02*
Y179690D01*
G01X196905Y174424D02*
X254023Y231542D01*
G01X196905Y173562D02*
Y174424D01*
G01X198248Y172219D02*
X196905Y173562D01*
G01X198248Y171356D02*
Y172219D01*
G01X197384Y170492D02*
X198248Y171356D01*
G01X196522Y170492D02*
X197384D01*
G01X195178Y171836D02*
X196522Y170492D01*
G01X194317Y171836D02*
X195178D01*
G01X193453Y170972D02*
X194317Y171836D01*
G01X193453Y170109D02*
Y170972D01*
G01X194746Y168816D02*
X193453Y170109D01*
G01X194746Y167954D02*
Y168816D01*
G01X193882Y167090D02*
X194746Y167954D01*
G01X193021Y167090D02*
X193882D01*
G01X191727Y168384D02*
X193021Y167090D01*
G01X190865Y168384D02*
X191727D01*
G01X219595Y175603D02*
Y170587D01*
G01X252392Y208400D02*
X219595Y175603D01*
G01X231274Y236650D02*
X233168D01*
G01X230173Y224287D02*
X232328Y222132D01*
G01X229311Y224287D02*
X230173D01*
G01X228447Y223423D02*
X229311Y224287D01*
G01X228447Y222561D02*
Y223423D01*
G01X230602Y220406D02*
X228447Y222561D01*
G01X230602Y219544D02*
Y220406D01*
G01X229738Y218680D02*
X230602Y219544D01*
G01X228876Y218680D02*
X229738D01*
G01X226721Y220835D02*
X228876Y218680D01*
G01X225859Y220835D02*
X226721D01*
G01X224995Y219971D02*
X225859Y220835D01*
G01X224995Y219109D02*
Y219971D01*
G01X192211Y402150D02*
X171542D01*
G01X205347Y389014D02*
X192211Y402150D01*
G01X205347Y386148D02*
Y389014D01*
G01X246567Y344928D02*
X205347Y386148D01*
G01X222692Y397499D02*
X182008Y438183D01*
G01X222692Y389100D02*
Y397499D01*
G01X248419Y363373D02*
X222692Y389100D01*
G01X199692Y386201D02*
X189643Y396250D01*
G01X199692Y383804D02*
Y386201D01*
G01X244896Y338600D02*
X199692Y383804D01*
G01X220092Y396562D02*
X199954Y416700D01*
G01X220092Y388600D02*
Y396562D01*
G01X247792Y360900D02*
X220092Y388600D01*
G01X217192Y395100D02*
X197492Y414800D01*
G01X217192Y388500D02*
Y395100D01*
G01X247092Y358600D02*
X217192Y388500D01*
G01X203462Y387931D02*
X191143Y400250D01*
G01X203462Y385367D02*
Y387931D01*
G01X246401Y342428D02*
X203462Y385367D01*
G01X214292Y388600D02*
X247156Y355736D01*
G01X214292Y394464D02*
Y388600D01*
G01X195956Y412800D02*
X214292Y394464D01*
G01X201577Y384585D02*
X245662Y340500D01*
G01X201577Y387016D02*
Y384585D01*
G01X190243Y398350D02*
X201577Y387016D01*
G01X172892Y463564D02*
X239092Y397364D01*
G01X172892Y465662D02*
Y463564D01*
G01X265857Y420959D02*
X214510Y472306D01*
G01X169700Y403992D02*
Y410493D01*
G01X178775Y440284D02*
Y441416D01*
G01X177644Y439153D02*
X178775Y440284D01*
G01X176512Y439153D02*
X177644D01*
G01X177482Y434789D02*
X176350D01*
G01X180876Y438183D02*
X177482Y434789D01*
G01X182008Y438183D02*
X180876D01*
G01X238101Y425342D02*
X189392Y474051D01*
G01X223120Y435797D02*
X235738Y423179D01*
G01X221988Y435797D02*
X223120D01*
G01X220857Y434666D02*
X221988Y435797D01*
G01X220857Y433534D02*
Y434666D01*
G01X251992Y402399D02*
X220857Y433534D01*
G01X177443Y431192D02*
X176411D01*
G01X180837Y434586D02*
X177443Y431192D01*
G01X182069Y434586D02*
X180837D01*
G01X195357Y421298D02*
X182069Y434586D01*
G01X195357Y420166D02*
Y421298D01*
G01X194226Y419035D02*
X195357Y420166D01*
G01X193094Y419035D02*
X194226D01*
G01X181869Y430260D02*
X193094Y419035D01*
G01X180537Y430260D02*
X181869D01*
G01X179406Y429129D02*
X180537Y430260D01*
G01X179406Y428197D02*
Y429129D01*
G01X190903Y416700D02*
X179406Y428197D01*
G01X199954Y416700D02*
X190903D01*
G01X253538Y413477D02*
X192192Y474823D01*
G01X170804Y433262D02*
X169785Y434281D01*
G01X170804Y432470D02*
Y433262D01*
G01X172615Y430659D02*
X170070Y428114D01*
G01X173407Y430659D02*
X172615D01*
G01X189266Y414800D02*
X173407Y430659D01*
G01X197492Y414800D02*
X189266D01*
G01X262087Y417657D02*
X207892Y471852D01*
G01X178592Y412800D02*
X195956D01*
G01X177857Y413535D02*
X178592Y412800D01*
G01X177857Y414327D02*
Y413535D01*
G01X182015Y418485D02*
X177857Y414327D01*
G01X182015Y419277D02*
Y418485D01*
G01X180996Y420296D02*
X182015Y419277D01*
G01X180204Y420296D02*
X180996D01*
G01X176046Y416138D02*
X180204Y420296D01*
G01X175254Y416138D02*
X176046D01*
G01X174235Y417157D02*
X175254Y416138D01*
G01X174235Y417949D02*
Y417157D01*
G01X178393Y422107D02*
X174235Y417949D01*
G01X178393Y422899D02*
Y422107D01*
G01X177374Y423918D02*
X178393Y422899D01*
G01X176582Y423918D02*
X177374D01*
G01X172424Y419760D02*
X176582Y423918D01*
G01X171632Y419760D02*
X172424D01*
G01X260202Y416006D02*
X205292Y470916D01*
G01X220552Y439291D02*
X186892Y472951D01*
G01X220552Y438159D02*
Y439291D01*
G01X219421Y437028D02*
X220552Y438159D01*
G01X218289Y437028D02*
X219421D01*
G01X206421Y448896D02*
X218289Y437028D01*
G01X205289Y448896D02*
X206421D01*
G01X204158Y447765D02*
X205289Y448896D01*
G01X204158Y446633D02*
Y447765D01*
G01X249592Y401199D02*
X204158Y446633D01*
G01X263972Y419308D02*
X210592Y472688D01*
G01X257192Y413359D02*
X201292Y469259D01*
G01X172092Y466462D02*
X172892Y465662D01*
G01X171061Y466462D02*
X172092D01*
G01X170261Y467262D02*
X171061Y466462D01*
G01X170261Y468862D02*
Y467262D01*
G01X171061Y469662D02*
X170261Y468862D01*
G01X172092Y469662D02*
X171061D01*
G01X172892Y470462D02*
X172092Y469662D01*
G01X172892Y472062D02*
Y470462D01*
G01X172092Y472862D02*
X172892Y472062D01*
G01X171145Y472862D02*
X172092D01*
G01X170345Y473662D02*
X171145Y472862D01*
G01X170345Y475262D02*
Y473662D01*
G01X171145Y476062D02*
X170345Y475262D01*
G01X172092Y476062D02*
X171145D01*
G01X172892Y476862D02*
X172092Y476062D01*
G01X172892Y478462D02*
Y476862D01*
G01X172092Y479262D02*
X172892Y478462D01*
G01X170992Y479262D02*
X172092D01*
G01X170192Y480062D02*
X170992Y479262D01*
G01X170192Y481662D02*
Y480062D01*
G01X170992Y482462D02*
X170192Y481662D01*
G01X172092Y482462D02*
X170992D01*
G01X172892Y483262D02*
X172092Y482462D01*
G01X172892Y484862D02*
Y483262D01*
G01X172092Y485662D02*
X172892Y484862D01*
G01X171061Y485662D02*
X172092D01*
G01X170317Y486406D02*
X171061Y485662D01*
G01X170317Y488006D02*
Y486406D01*
G01X171173Y488862D02*
X170317Y488006D01*
G01X172092Y488862D02*
X171173D01*
G01X172892Y489662D02*
X172092Y488862D01*
G01X172892Y501961D02*
Y489662D01*
G01X172282Y502571D02*
X172892Y501961D01*
G01X171050Y502571D02*
X172282D01*
G01X170440Y503181D02*
X171050Y502571D01*
G01X170440Y505161D02*
Y503181D01*
G01X171050Y505771D02*
X170440Y505161D01*
G01X172282Y505771D02*
X171050D01*
G01X172892Y506381D02*
X172282Y505771D01*
G01X172892Y508000D02*
Y506381D01*
G01X171092Y509800D02*
X172892Y508000D01*
G01X171092Y511100D02*
Y509800D01*
G01X171691Y511699D02*
X171092Y511100D01*
G01X171691Y518600D02*
Y511699D01*
G01X172992Y519901D02*
X171691Y518600D01*
G01X172992Y521609D02*
Y519901D01*
G01X172382Y522219D02*
X172992Y521609D01*
G01X171124Y522219D02*
X172382D01*
G01X170514Y522829D02*
X171124Y522219D01*
G01X170514Y524809D02*
Y522829D01*
G01X171124Y525419D02*
X170514Y524809D01*
G01X172382Y525419D02*
X171124D01*
G01X172992Y526029D02*
X172382Y525419D01*
G01X172992Y527100D02*
Y526029D01*
G01X209679Y526031D02*
Y527413D01*
G01X208449Y524801D02*
X209679Y526031D01*
G01X208449Y522959D02*
Y524801D01*
G01X209992Y521416D02*
X208449Y522959D01*
G01X209992Y520100D02*
Y521416D01*
G01X208449Y518557D02*
X209992Y520100D01*
G01X208449Y508763D02*
Y518557D01*
G01X209292Y507920D02*
X208449Y508763D01*
G01X209292Y499100D02*
Y507920D01*
G01X214510Y493882D02*
X209292Y499100D01*
G01X214510Y491945D02*
Y493882D01*
G01X213900Y491335D02*
X214510Y491945D01*
G01X213089Y491335D02*
X213900D01*
G01X212479Y490725D02*
X213089Y491335D01*
G01X212479Y488745D02*
Y490725D01*
G01X213089Y488135D02*
X212479Y488745D01*
G01X214096Y488135D02*
X213089D01*
G01X214706Y487525D02*
X214096Y488135D01*
G01X214706Y485545D02*
Y487525D01*
G01X214096Y484935D02*
X214706Y485545D01*
G01X213089Y484935D02*
X214096D01*
G01X212479Y484325D02*
X213089Y484935D01*
G01X212479Y482345D02*
Y484325D01*
G01X213089Y481735D02*
X212479Y482345D01*
G01X213900Y481735D02*
X213089D01*
G01X214510Y481125D02*
X213900Y481735D01*
G01X214510Y479145D02*
Y481125D01*
G01X213900Y478535D02*
X214510Y479145D01*
G01X213089Y478535D02*
X213900D01*
G01X212479Y477925D02*
X213089Y478535D01*
G01X212479Y475945D02*
Y477925D01*
G01X213089Y475335D02*
X212479Y475945D01*
G01X213900Y475335D02*
X213089D01*
G01X214510Y474725D02*
X213900Y475335D01*
G01X214510Y472306D02*
Y474725D01*
G01X170592Y495418D02*
X169792Y496218D01*
G01X170592Y493818D02*
Y495418D01*
G01X169792Y493018D02*
X170592Y493818D01*
G01X188892Y519501D02*
Y527600D01*
G01X188286Y518895D02*
X188892Y519501D01*
G01X188286Y517506D02*
Y518895D01*
G01X189491Y516301D02*
X188286Y517506D01*
G01X189491Y512157D02*
Y516301D01*
G01X188492Y511158D02*
X189491Y512157D01*
G01X188492Y509200D02*
Y511158D01*
G01X189392Y508300D02*
X188492Y509200D01*
G01X189392Y474051D02*
Y508300D01*
G01X229192Y526500D02*
X229992Y527300D01*
G01X229192Y517007D02*
Y526500D01*
G01X228492Y516307D02*
X229192Y517007D01*
G01X228492Y511967D02*
Y516307D01*
G01X229203Y511256D02*
X228492Y511967D01*
G01X229203Y482791D02*
Y511256D01*
G01X258735Y453259D02*
X229203Y482791D01*
G01X192192Y520049D02*
Y527700D01*
G01X193292Y518949D02*
X192192Y520049D01*
G01X193292Y517800D02*
Y518949D01*
G01X191991Y516499D02*
X193292Y517800D01*
G01X191991Y511657D02*
Y516499D01*
G01X192892Y510756D02*
X191991Y511657D01*
G01X192892Y509600D02*
Y510756D01*
G01X192192Y508900D02*
X192892Y509600D01*
G01X192192Y474823D02*
Y508900D01*
G01X202835Y521309D02*
Y526813D01*
G01X201634Y520108D02*
X202835Y521309D01*
G01X201634Y517725D02*
Y520108D01*
G01X202556Y516803D02*
X201634Y517725D01*
G01X202556Y512151D02*
Y516803D01*
G01X201802Y511397D02*
X202556Y512151D01*
G01X201802Y509500D02*
Y511397D01*
G01X202992Y508310D02*
X201802Y509500D01*
G01X202992Y502600D02*
Y508310D01*
G01X204192Y501400D02*
X202992Y502600D01*
G01X204192Y496700D02*
Y501400D01*
G01X207892Y493000D02*
X204192Y496700D01*
G01X207892Y471852D02*
Y493000D01*
G01X198892Y519510D02*
Y527800D01*
G01X198968Y519434D02*
X198892Y519510D01*
G01X198968Y517123D02*
Y519434D01*
G01X198503Y516658D02*
X198968Y517123D01*
G01X198503Y511596D02*
Y516658D01*
G01X199292Y510807D02*
X198503Y511596D01*
G01X199292Y501500D02*
Y510807D01*
G01X201592Y499200D02*
X199292Y501500D01*
G01X201592Y495500D02*
Y499200D01*
G01X205292Y491800D02*
X201592Y495500D01*
G01X205292Y470916D02*
Y491800D01*
G01X226653Y525895D02*
Y527131D01*
G01X226043Y525285D02*
X226653Y525895D01*
G01X225353Y525285D02*
X226043D01*
G01X224743Y524675D02*
X225353Y525285D01*
G01X224743Y522695D02*
Y524675D01*
G01X225353Y522085D02*
X224743Y522695D01*
G01X226043Y522085D02*
X225353D01*
G01X226653Y521475D02*
X226043Y522085D01*
G01X226653Y520189D02*
Y521475D01*
G01X224892Y518428D02*
X226653Y520189D01*
G01X224892Y517499D02*
Y518428D01*
G01X226192Y516199D02*
X224892Y517499D01*
G01X226192Y512047D02*
Y516199D01*
G01X225192Y511047D02*
X226192Y512047D01*
G01X225192Y509300D02*
Y511047D01*
G01X226692Y507800D02*
X225192Y509300D01*
G01X226692Y506526D02*
Y507800D01*
G01X226082Y505916D02*
X226692Y506526D01*
G01X224409Y505916D02*
X226082D01*
G01X223799Y505306D02*
X224409Y505916D01*
G01X223799Y503326D02*
Y505306D01*
G01X224409Y502716D02*
X223799Y503326D01*
G01X226082Y502716D02*
X224409D01*
G01X226692Y502106D02*
X226082Y502716D01*
G01X226692Y481700D02*
Y502106D01*
G01X263097Y445295D02*
X226692Y481700D01*
G01X185691Y517357D02*
Y529842D01*
G01X185291Y516957D02*
X185691Y517357D01*
G01X185291Y512057D02*
Y516957D01*
G01X185692Y511656D02*
X185291Y512057D01*
G01X185692Y508300D02*
Y511656D01*
G01X186892Y507100D02*
X185692Y508300D01*
G01X186892Y472951D02*
Y507100D01*
G01X205592Y519910D02*
Y527800D01*
G01X206002Y519500D02*
X205592Y519910D01*
G01X206002Y517657D02*
Y519500D01*
G01X204652Y516307D02*
X206002Y517657D01*
G01X204652Y512057D02*
Y516307D01*
G01X206002Y510707D02*
X204652Y512057D01*
G01X206002Y506990D02*
Y510707D01*
G01X206692Y506300D02*
X206002Y506990D01*
G01X206692Y498000D02*
Y506300D01*
G01X210592Y494100D02*
X206692Y498000D01*
G01X210592Y472688D02*
Y494100D01*
G01X195592Y519451D02*
Y526800D01*
G01X195341Y519200D02*
X195592Y519451D01*
G01X195341Y517357D02*
Y519200D01*
G01X196192Y516506D02*
X195341Y517357D01*
G01X196192Y512558D02*
Y516506D01*
G01X195291Y511657D02*
X196192Y512558D01*
G01X195291Y499424D02*
Y511657D01*
G01X195898Y498817D02*
X195291Y499424D01*
G01X197004Y498817D02*
X195898D01*
G01X197846Y497975D02*
X197004Y498817D01*
G01X197846Y496375D02*
Y497975D01*
G01X197088Y495617D02*
X197846Y496375D01*
G01X195476Y495617D02*
X197088D01*
G01X194892Y495033D02*
X195476Y495617D01*
G01X194892Y474931D02*
Y495033D01*
G01X195692Y474131D02*
X194892Y474931D01*
G01X197292Y474131D02*
X195692D01*
G01X198092Y474931D02*
X197292Y474131D01*
G01X198092Y490100D02*
Y474931D01*
G01X198892Y490900D02*
X198092Y490100D01*
G01X200492Y490900D02*
X198892D01*
G01X201292Y490100D02*
X200492Y490900D01*
G01X201292Y469259D02*
Y490100D01*
G01X222502Y517357D02*
Y529842D01*
G01X221692Y516547D02*
X222502Y517357D01*
G01X221692Y512467D02*
Y516547D01*
G01X222947Y511212D02*
X221692Y512467D01*
G01X222947Y509555D02*
Y511212D01*
G01X221526Y508134D02*
X222947Y509555D01*
G01X221526Y501866D02*
Y508134D01*
G01X224092Y499300D02*
X221526Y501866D01*
G01X224092Y480500D02*
Y499300D01*
G01X268569Y436023D02*
X224092Y480500D01*
G01X171691Y528401D02*
X172992Y527100D01*
G01X171691Y537700D02*
Y528401D01*
G01X172092Y538101D02*
X171691Y537700D01*
G01X172092Y545700D02*
Y538101D01*
G01X171691Y546101D02*
X172092Y545700D01*
G01X171691Y556400D02*
Y546101D01*
G01X172192Y556901D02*
X171691Y556400D01*
G01X172192Y565600D02*
Y556901D01*
G01X171691Y566101D02*
X172192Y565600D01*
G01X171691Y575500D02*
Y566101D01*
G01X172192Y576001D02*
X171691Y575500D01*
G01X172192Y584200D02*
Y576001D01*
G01X171691Y584701D02*
X172192Y584200D01*
G01X171691Y586443D02*
Y584701D01*
G01X169770Y588364D02*
X171691Y586443D01*
G01X208502D02*
X206581Y588364D01*
G01X208502Y584190D02*
Y586443D01*
G01X208992Y583700D02*
X208502Y584190D01*
G01X208992Y581700D02*
Y583700D01*
G01X207992Y580700D02*
X208992Y581700D01*
G01X207992Y579200D02*
Y580700D01*
G01X208992Y578200D02*
X207992Y579200D01*
G01X208992Y576100D02*
Y578200D01*
G01X208502Y575610D02*
X208992Y576100D01*
G01X208502Y566390D02*
Y575610D01*
G01X208992Y565900D02*
X208502Y566390D01*
G01X208992Y564400D02*
Y565900D01*
G01X207992Y563400D02*
X208992Y564400D01*
G01X207992Y560900D02*
Y563400D01*
G01X208992Y559900D02*
X207992Y560900D01*
G01X208992Y557100D02*
Y559900D01*
G01X208502Y556610D02*
X208992Y557100D01*
G01X208502Y546690D02*
Y556610D01*
G01X209455Y545737D02*
X208502Y546690D01*
G01X209455Y543800D02*
Y545737D01*
G01X208392Y542737D02*
X209455Y543800D01*
G01X208392Y541463D02*
Y542737D01*
G01X209455Y540400D02*
X208392Y541463D01*
G01X209455Y538663D02*
Y540400D01*
G01X208502Y537710D02*
X209455Y538663D01*
G01X208502Y528590D02*
Y537710D01*
G01X209679Y527413D02*
X208502Y528590D01*
G01X188548Y587368D02*
X187202Y588714D01*
G01X188591Y587368D02*
X188548D01*
G01X188591Y584600D02*
Y587368D01*
G01X188892Y584299D02*
X188591Y584600D01*
G01X188892Y576800D02*
Y584299D01*
G01X188258Y576166D02*
X188892Y576800D01*
G01X188258Y574534D02*
Y576166D01*
G01X189492Y573300D02*
X188258Y574534D01*
G01X189492Y568398D02*
Y573300D01*
G01X188159Y567065D02*
X189492Y568398D01*
G01X188159Y565933D02*
Y567065D01*
G01X188892Y565200D02*
X188159Y565933D01*
G01X188892Y557801D02*
Y565200D01*
G01X187958Y556867D02*
X188892Y557801D01*
G01X187958Y555534D02*
Y556867D01*
G01X189792Y553700D02*
X187958Y555534D01*
G01X189792Y550258D02*
Y553700D01*
G01X188192Y548658D02*
X189792Y550258D01*
G01X188192Y546900D02*
Y548658D01*
G01X188892Y546200D02*
X188192Y546900D01*
G01X188892Y538701D02*
Y546200D01*
G01X188192Y538001D02*
X188892Y538701D01*
G01X188192Y536701D02*
Y538001D01*
G01X189892Y535001D02*
X188192Y536701D01*
G01X189892Y531043D02*
Y535001D01*
G01X188237Y529388D02*
X189892Y531043D01*
G01X188237Y528255D02*
Y529388D01*
G01X188892Y527600D02*
X188237Y528255D01*
G01X227192Y588100D02*
X226002Y589290D01*
G01X228593Y588100D02*
X227192D01*
G01X229592Y587101D02*
X228593Y588100D01*
G01X229592Y585100D02*
Y587101D01*
G01X228692Y584200D02*
X229592Y585100D01*
G01X228692Y576900D02*
Y584200D01*
G01X229792Y575800D02*
X228692Y576900D01*
G01X229792Y574500D02*
Y575800D01*
G01X228502Y573210D02*
X229792Y574500D01*
G01X228502Y568397D02*
Y573210D01*
G01X229992Y566907D02*
X228502Y568397D01*
G01X229992Y565100D02*
Y566907D01*
G01X229092Y564200D02*
X229992Y565100D01*
G01X229092Y558400D02*
Y564200D01*
G01X229992Y557500D02*
X229092Y558400D01*
G01X229992Y555499D02*
Y557500D01*
G01X228802Y554309D02*
X229992Y555499D01*
G01X228802Y550089D02*
Y554309D01*
G01X229792Y549099D02*
X228802Y550089D01*
G01X229792Y547400D02*
Y549099D01*
G01X228492Y546100D02*
X229792Y547400D01*
G01X228492Y538900D02*
Y546100D01*
G01X229665Y537727D02*
X228492Y538900D01*
G01X229665Y536673D02*
Y537727D01*
G01X228392Y535400D02*
X229665Y536673D01*
G01X228392Y530700D02*
Y535400D01*
G01X229992Y529100D02*
X228392Y530700D01*
G01X229992Y527300D02*
Y529100D01*
G01X192591Y586507D02*
X189191Y589907D01*
G01X192591Y584599D02*
Y586507D01*
G01X192192Y584200D02*
X192591Y584599D01*
G01X192192Y575899D02*
Y584200D01*
G01X192591Y575500D02*
X192192Y575899D01*
G01X192591Y574042D02*
Y575500D01*
G01X191691Y573142D02*
X192591Y574042D01*
G01X191691Y568397D02*
Y573142D01*
G01X192791Y567297D02*
X191691Y568397D01*
G01X192791Y566099D02*
Y567297D01*
G01X192192Y565500D02*
X192791Y566099D01*
G01X192192Y557799D02*
Y565500D01*
G01X192791Y557200D02*
X192192Y557799D01*
G01X192791Y555657D02*
Y557200D01*
G01X191991Y554857D02*
X192791Y555657D01*
G01X191991Y549457D02*
Y554857D01*
G01X193254Y548194D02*
X191991Y549457D01*
G01X193254Y547062D02*
Y548194D01*
G01X192292Y546100D02*
X193254Y547062D01*
G01X192292Y538699D02*
Y546100D01*
G01X192904Y538087D02*
X192292Y538699D01*
G01X192904Y536611D02*
Y538087D01*
G01X191891Y535598D02*
X192904Y536611D01*
G01X191891Y530366D02*
Y535598D01*
G01X192841Y529416D02*
X191891Y530366D01*
G01X192841Y528349D02*
Y529416D01*
G01X192192Y527700D02*
X192841Y528349D01*
G01X201802Y587790D02*
X200878Y588714D01*
G01X201802Y584790D02*
Y587790D01*
G01X202992Y583600D02*
X201802Y584790D01*
G01X202992Y582500D02*
Y583600D01*
G01X201692Y581200D02*
X202992Y582500D01*
G01X201692Y579900D02*
Y581200D01*
G01X202992Y578600D02*
X201692Y579900D01*
G01X202992Y577000D02*
Y578600D01*
G01X201550Y575558D02*
X202992Y577000D01*
G01X201550Y573998D02*
Y575558D01*
G01X202402Y573146D02*
X201550Y573998D01*
G01X202402Y568497D02*
Y573146D01*
G01X201662Y567757D02*
X202402Y568497D01*
G01X201662Y565674D02*
Y567757D01*
G01X202292Y565044D02*
X201662Y565674D01*
G01X202292Y557390D02*
Y565044D01*
G01X201634Y556732D02*
X202292Y557390D01*
G01X201634Y555197D02*
Y556732D01*
G01X202528Y554303D02*
X201634Y555197D01*
G01X202528Y549183D02*
Y554303D01*
G01X201662Y548317D02*
X202528Y549183D01*
G01X201662Y546430D02*
Y548317D01*
G01X202695Y545397D02*
X201662Y546430D01*
G01X202695Y539245D02*
Y545397D01*
G01X201438Y537988D02*
X202695Y539245D01*
G01X201438Y536144D02*
Y537988D01*
G01X202388Y535194D02*
X201438Y536144D01*
G01X202388Y530478D02*
Y535194D01*
G01X201902Y529992D02*
X202388Y530478D01*
G01X201902Y527746D02*
Y529992D01*
G01X202835Y526813D02*
X201902Y527746D01*
G01X199152Y586457D02*
X196817Y588792D01*
G01X199152Y584660D02*
Y586457D01*
G01X198967Y584475D02*
X199152Y584660D01*
G01X198967Y573757D02*
Y584475D01*
G01X198407Y573197D02*
X198967Y573757D01*
G01X198407Y567984D02*
Y573197D01*
G01X199191Y567200D02*
X198407Y567984D01*
G01X199191Y566099D02*
Y567200D01*
G01X199051Y565959D02*
X199191Y566099D01*
G01X199051Y555006D02*
Y565959D01*
G01X198423Y554378D02*
X199051Y555006D01*
G01X198423Y549436D02*
Y554378D01*
G01X199203Y548656D02*
X198423Y549436D01*
G01X199203Y546511D02*
Y548656D01*
G01X198892Y546200D02*
X199203Y546511D01*
G01X198892Y538010D02*
Y546200D01*
G01X199118Y537784D02*
X198892Y538010D01*
G01X199118Y536058D02*
Y537784D01*
G01X198302Y535242D02*
X199118Y536058D01*
G01X198302Y530390D02*
Y535242D01*
G01X199094Y529598D02*
X198302Y530390D01*
G01X199094Y528002D02*
Y529598D01*
G01X198892Y527800D02*
X199094Y528002D01*
G01X224992Y587735D02*
X224013Y588714D01*
G01X224992Y585500D02*
Y587735D01*
G01X225692Y584800D02*
X224992Y585500D01*
G01X225692Y582100D02*
Y584800D01*
G01X224492Y580900D02*
X225692Y582100D01*
G01X224492Y579400D02*
Y580900D01*
G01X225692Y578200D02*
X224492Y579400D01*
G01X225692Y576600D02*
Y578200D01*
G01X224959Y575867D02*
X225692Y576600D01*
G01X224959Y574434D02*
Y575867D01*
G01X226392Y573001D02*
X224959Y574434D01*
G01X226392Y568499D02*
Y573001D01*
G01X225109Y567216D02*
X226392Y568499D01*
G01X225109Y566083D02*
Y567216D01*
G01X225692Y565500D02*
X225109Y566083D01*
G01X225692Y563000D02*
Y565500D01*
G01X224492Y561800D02*
X225692Y563000D01*
G01X224492Y560600D02*
Y561800D01*
G01X225692Y559400D02*
X224492Y560600D01*
G01X225692Y557690D02*
Y559400D01*
G01X224892Y556890D02*
X225692Y557690D01*
G01X224892Y555399D02*
Y556890D01*
G01X226392Y553899D02*
X224892Y555399D01*
G01X226392Y550047D02*
Y553899D01*
G01X225192Y548847D02*
X226392Y550047D01*
G01X225192Y546600D02*
Y548847D01*
G01X225792Y546000D02*
X225192Y546600D01*
G01X225792Y544200D02*
Y546000D01*
G01X224796Y543204D02*
X225792Y544200D01*
G01X224796Y541596D02*
Y543204D01*
G01X225792Y540600D02*
X224796Y541596D01*
G01X225792Y539300D02*
Y540600D01*
G01X225092Y538600D02*
X225792Y539300D01*
G01X225092Y536600D02*
Y538600D01*
G01X226202Y535490D02*
X225092Y536600D01*
G01X226202Y530542D02*
Y535490D01*
G01X225092Y529432D02*
X226202Y530542D01*
G01X225092Y528692D02*
Y529432D01*
G01X226653Y527131D02*
X225092Y528692D01*
G01X186091Y586357D02*
X183191Y589257D01*
G01X186091Y585099D02*
Y586357D01*
G01X185492Y584500D02*
X186091Y585099D01*
G01X185492Y575799D02*
Y584500D01*
G01X185792Y575499D02*
X185492Y575799D01*
G01X185792Y573943D02*
Y575499D01*
G01X184818Y572969D02*
X185792Y573943D01*
G01X184818Y568470D02*
Y572969D01*
G01X185891Y567397D02*
X184818Y568470D01*
G01X185891Y565899D02*
Y567397D01*
G01X185492Y565500D02*
X185891Y565899D01*
G01X185492Y557699D02*
Y565500D01*
G01X185891Y557300D02*
X185492Y557699D01*
G01X185891Y555357D02*
Y557300D01*
G01X185291Y554757D02*
X185891Y555357D01*
G01X185291Y549857D02*
Y554757D01*
G01X186091Y549057D02*
X185291Y549857D01*
G01X186091Y547099D02*
Y549057D01*
G01X185492Y546500D02*
X186091Y547099D01*
G01X185492Y537999D02*
Y546500D01*
G01X186091Y537400D02*
X185492Y537999D01*
G01X186091Y536498D02*
Y537400D01*
G01X185291Y535698D02*
X186091Y536498D01*
G01X185291Y530242D02*
Y535698D01*
G01X185691Y529842D02*
X185291Y530242D01*
G01X205852Y586457D02*
X202502Y589807D01*
G01X205852Y584560D02*
Y586457D01*
G01X205592Y584300D02*
X205852Y584560D01*
G01X205592Y575860D02*
Y584300D01*
G01X205852Y575600D02*
X205592Y575860D01*
G01X205852Y574259D02*
Y575600D01*
G01X204702Y573109D02*
X205852Y574259D01*
G01X204702Y568367D02*
Y573109D01*
G01X205802Y567267D02*
X204702Y568367D01*
G01X205802Y565910D02*
Y567267D01*
G01X205592Y565700D02*
X205802Y565910D01*
G01X205592Y557610D02*
Y565700D01*
G01X205802Y557400D02*
X205592Y557610D01*
G01X205802Y555257D02*
Y557400D01*
G01X204652Y554107D02*
X205802Y555257D01*
G01X204652Y549857D02*
Y554107D01*
G01X206002Y548507D02*
X204652Y549857D01*
G01X206002Y546510D02*
Y548507D01*
G01X205592Y546100D02*
X206002Y546510D01*
G01X205592Y538900D02*
Y546100D01*
G01X206002Y538490D02*
X205592Y538900D01*
G01X206002Y536610D02*
Y538490D01*
G01X204652Y535260D02*
X206002Y536610D01*
G01X204652Y530617D02*
Y535260D01*
G01X206002Y529267D02*
X204652Y530617D01*
G01X206002Y528210D02*
Y529267D01*
G01X205592Y527800D02*
X206002Y528210D01*
G01X195191Y587470D02*
X193895Y588766D01*
G01X195191Y584701D02*
Y587470D01*
G01X195992Y583900D02*
X195191Y584701D01*
G01X195992Y577001D02*
Y583900D01*
G01X194792Y575801D02*
X195992Y577001D01*
G01X194792Y574701D02*
Y575801D01*
G01X196191Y573302D02*
X194792Y574701D01*
G01X196191Y568497D02*
Y573302D01*
G01X194892Y567198D02*
X196191Y568497D01*
G01X194892Y565500D02*
Y567198D01*
G01X195592Y564800D02*
X194892Y565500D01*
G01X195592Y558199D02*
Y564800D01*
G01X194792Y557399D02*
X195592Y558199D01*
G01X194792Y555500D02*
Y557399D01*
G01X195891Y554401D02*
X194792Y555500D01*
G01X195891Y550057D02*
Y554401D01*
G01X195291Y549457D02*
X195891Y550057D01*
G01X195291Y547101D02*
Y549457D01*
G01X195592Y546800D02*
X195291Y547101D01*
G01X195592Y538801D02*
Y546800D01*
G01X194992Y538201D02*
X195592Y538801D01*
G01X194992Y536501D02*
Y538201D01*
G01X195991Y535502D02*
X194992Y536501D01*
G01X195991Y530466D02*
Y535502D01*
G01X194992Y529467D02*
X195991Y530466D01*
G01X194992Y527400D02*
Y529467D01*
G01X195592Y526800D02*
X194992Y527400D01*
G01X222902Y586357D02*
X220002Y589257D01*
G01X222902Y585010D02*
Y586357D01*
G01X221892Y584000D02*
X222902Y585010D01*
G01X221892Y576300D02*
Y584000D01*
G01X222860Y575332D02*
X221892Y576300D01*
G01X222860Y574200D02*
Y575332D01*
G01X221629Y572969D02*
X222860Y574200D01*
G01X221629Y568470D02*
Y572969D01*
G01X222992Y567107D02*
X221629Y568470D01*
G01X222992Y564800D02*
Y567107D01*
G01X222392Y564200D02*
X222992Y564800D01*
G01X222392Y557210D02*
Y564200D01*
G01X222892Y556710D02*
X222392Y557210D01*
G01X222892Y555399D02*
Y556710D01*
G01X221592Y554099D02*
X222892Y555399D01*
G01X221592Y550367D02*
Y554099D01*
G01X222902Y549057D02*
X221592Y550367D01*
G01X222902Y547310D02*
Y549057D01*
G01X222092Y546500D02*
X222902Y547310D01*
G01X222092Y539000D02*
Y546500D01*
G01X223092Y538000D02*
X222092Y539000D01*
G01X223092Y536700D02*
Y538000D01*
G01X222102Y535710D02*
X223092Y536700D01*
G01X222102Y530242D02*
Y535710D01*
G01X222502Y529842D02*
X222102Y530242D01*
G01X169682Y588714D02*
X169770D01*
G01D02*
Y588364D01*
G01X206581D02*
Y588714D01*
G01X204915Y604499D02*
X203935D01*
G01X205514Y603900D02*
X204915Y604499D01*
G01X205514Y602700D02*
Y603900D01*
G01X204570Y601756D02*
X205514Y602700D01*
G01X204570Y600544D02*
Y601756D01*
G01X205414Y599700D02*
X204570Y600544D01*
G01X205414Y598000D02*
Y599700D01*
G01X204570Y597156D02*
X205414Y598000D01*
G01X204570Y595736D02*
Y597156D01*
G01X205714Y594592D02*
X204570Y595736D01*
G01X205714Y592999D02*
Y594592D01*
G01X204807Y592092D02*
X205714Y592999D01*
G01X204807Y590400D02*
Y592092D01*
G01X206493Y588714D02*
X204807Y590400D01*
G01X206581Y588714D02*
X206493D01*
G01X184928Y604499D02*
X183856D01*
G01X185628Y603799D02*
X184928Y604499D01*
G01X185628Y602525D02*
Y603799D01*
G01X184491Y601388D02*
X185628Y602525D01*
G01X184491Y600312D02*
Y601388D01*
G01X185503Y599300D02*
X184491Y600312D01*
G01X185503Y598100D02*
Y599300D01*
G01X184491Y597088D02*
X185503Y598100D01*
G01X184491Y596012D02*
Y597088D01*
G01X185603Y594900D02*
X184491Y596012D01*
G01X185603Y592267D02*
Y594900D01*
G01X185428Y592092D02*
X185603Y592267D01*
G01X185428Y590400D02*
Y592092D01*
G01X187114Y588714D02*
X185428Y590400D01*
G01X187202Y588714D02*
X187114D01*
G01X225655Y605649D02*
X230706Y610700D01*
G01X225655Y595462D02*
Y605649D01*
G01X227360Y593757D02*
X225655Y595462D01*
G01X226002Y592399D02*
X227360Y593757D01*
G01X226002Y589290D02*
Y592399D01*
G01X189191D02*
X190549Y593757D01*
G01X189191Y589907D02*
Y592399D01*
G01X188844Y605649D02*
X193895Y610700D01*
G01X188844Y595462D02*
Y605649D01*
G01X190549Y593757D02*
X188844Y595462D01*
G01X198314Y604499D02*
X197242D01*
G01X198914Y603899D02*
X198314Y604499D01*
G01X198914Y603001D02*
Y603899D01*
G01X197877Y601964D02*
X198914Y603001D01*
G01X197877Y600736D02*
Y601964D01*
G01X198814Y599799D02*
X197877Y600736D01*
G01X198814Y598401D02*
Y599799D01*
G01X197877Y597464D02*
X198814Y598401D01*
G01X197877Y596136D02*
Y597464D01*
G01X199014Y594999D02*
X197877Y596136D01*
G01X199014Y593100D02*
Y594999D01*
G01X198514Y592600D02*
X199014Y593100D01*
G01X198514Y590400D02*
Y592600D01*
G01X200200Y588714D02*
X198514Y590400D01*
G01X200288Y588714D02*
X200200D01*
G01X200878D02*
X200288D01*
G01X196817Y593332D02*
X197242Y593757D01*
G01X196817Y588792D02*
Y593332D01*
G01X199214Y610300D02*
X200202D01*
G01X196159Y607245D02*
X199214Y610300D01*
G01X196159Y606057D02*
Y607245D01*
G01X195537Y605435D02*
X196159Y606057D01*
G01X195537Y595462D02*
Y605435D01*
G01X197242Y593757D02*
X195537Y595462D01*
G01X221739Y604499D02*
X220667D01*
G01X222439Y603799D02*
X221739Y604499D01*
G01X222439Y602525D02*
Y603799D01*
G01X221302Y601388D02*
X222439Y602525D01*
G01X221302Y600312D02*
Y601388D01*
G01X222314Y599300D02*
X221302Y600312D01*
G01X222314Y598100D02*
Y599300D01*
G01X221302Y597088D02*
X222314Y598100D01*
G01X221302Y596012D02*
Y597088D01*
G01X222414Y594900D02*
X221302Y596012D01*
G01X222414Y592267D02*
Y594900D01*
G01X222239Y592092D02*
X222414Y592267D01*
G01X222239Y590400D02*
Y592092D01*
G01X223925Y588714D02*
X222239Y590400D01*
G01X224013Y588714D02*
X223925D01*
G01X183191Y593092D02*
X183856Y593757D01*
G01X183191Y589257D02*
Y593092D01*
G01X182151Y605649D02*
X187202Y610700D01*
G01X182151Y595462D02*
Y605649D01*
G01X183856Y593757D02*
X182151Y595462D01*
G01X205415Y610300D02*
X206581D01*
G01X202230Y607115D02*
X205415Y610300D01*
G01X202230Y595462D02*
Y607115D01*
G01X203935Y593757D02*
X202230Y595462D01*
G01X202502Y592324D02*
X203935Y593757D01*
G01X202502Y589807D02*
Y592324D01*
G01X191621Y604499D02*
X190549D01*
G01X192321Y603799D02*
X191621Y604499D01*
G01X192321Y602525D02*
Y603799D01*
G01X191184Y601388D02*
X192321Y602525D01*
G01X191184Y600312D02*
Y601388D01*
G01X192196Y599300D02*
X191184Y600312D01*
G01X192196Y598100D02*
Y599300D01*
G01X191184Y597088D02*
X192196Y598100D01*
G01X191184Y596012D02*
Y597088D01*
G01X192296Y594900D02*
X191184Y596012D01*
G01X192296Y592267D02*
Y594900D01*
G01X192121Y592092D02*
X192296Y592267D01*
G01X192121Y590400D02*
Y592092D01*
G01X193807Y588714D02*
X192121Y590400D01*
G01X193895Y588714D02*
X193807D01*
G01X193895Y588766D02*
Y588714D01*
G01X230706Y588766D02*
Y588714D01*
G01X232002Y587470D02*
X230706Y588766D01*
G01X228432Y604499D02*
X227360D01*
G01X229132Y603799D02*
X228432Y604499D01*
G01X229132Y602525D02*
Y603799D01*
G01X227995Y601388D02*
X229132Y602525D01*
G01X227995Y600312D02*
Y601388D01*
G01X229007Y599300D02*
X227995Y600312D01*
G01X229007Y598100D02*
Y599300D01*
G01X227995Y597088D02*
X229007Y598100D01*
G01X227995Y596012D02*
Y597088D01*
G01X229107Y594900D02*
X227995Y596012D01*
G01X229107Y592267D02*
Y594900D01*
G01X228932Y592092D02*
X229107Y592267D01*
G01X228932Y590400D02*
Y592092D01*
G01X230618Y588714D02*
X228932Y590400D01*
G01X230706Y588714D02*
X230618D01*
G01X218962Y605649D02*
X224013Y610700D01*
G01X218962Y595466D02*
Y605649D01*
G01X220667Y593761D02*
X218962Y595466D01*
G01X220002Y593096D02*
X220667Y593761D01*
G01X220002Y589257D02*
Y593096D01*
G01X265418Y-8654D02*
X264171Y-9901D01*
G01X265418Y-7400D02*
Y-8654D01*
G01X266718Y-6100D02*
X265418Y-7400D01*
G01X267718Y-6100D02*
X266718D01*
G01X269518Y-4300D02*
X267718Y-6100D01*
G01X269518Y-2900D02*
Y-4300D01*
G01X268906Y-2288D02*
X269518Y-2900D01*
G01X268906Y10725D02*
Y-2288D01*
G01X267517Y12114D02*
X268906Y10725D01*
G01X265613Y14018D02*
X267517Y12114D01*
G01X265613Y15614D02*
Y14018D01*
G01X268963Y18964D02*
X265613Y15614D01*
G01X268963Y28699D02*
Y18964D01*
G01X269513Y29249D02*
X268963Y28699D01*
G01X269513Y34779D02*
Y29249D01*
G01X234053Y-8347D02*
Y-9901D01*
G01X236300Y-6100D02*
X234053Y-8347D01*
G01X237524Y-6100D02*
X236300D01*
G01X239100Y-4524D02*
X237524Y-6100D01*
G01X239100Y-2900D02*
Y-4524D01*
G01X238325Y-2125D02*
X239100Y-2900D01*
G01X238325Y10888D02*
Y-2125D01*
G01X237099Y12114D02*
X238325Y10888D01*
G01X235113Y14100D02*
X237099Y12114D01*
G01X235113Y15514D02*
Y14100D01*
G01X238392Y18793D02*
X235113Y15514D01*
G01X238392Y28278D02*
Y18793D01*
G01X238946Y28832D02*
X238392Y28278D01*
G01X238946Y36796D02*
Y28832D01*
G01X241592Y29465D02*
Y34400D01*
G01X242613Y28444D02*
X241592Y29465D01*
G01X242613Y26921D02*
Y28444D01*
G01X240746Y25054D02*
X242613Y26921D01*
G01X240746Y17157D02*
Y25054D01*
G01X239625Y16036D02*
X240746Y17157D01*
G01X239625Y13100D02*
Y16036D01*
G01X242525Y10200D02*
X239625Y13100D01*
G01X242525Y8232D02*
Y10200D01*
G01X240992Y6699D02*
X242525Y8232D01*
G01X240992Y5500D02*
Y6699D01*
G01X242242Y4250D02*
X240992Y5500D01*
G01X242242Y3350D02*
Y4250D01*
G01X240892Y2000D02*
X242242Y3350D01*
G01X240892Y701D02*
Y2000D01*
G01X242525Y-932D02*
X240892Y701D01*
G01X242525Y-3233D02*
Y-932D01*
G01X243392Y-4100D02*
X242525Y-3233D01*
G01X258725Y-8654D02*
X257478Y-9901D01*
G01X258725Y-7400D02*
Y-8654D01*
G01X260025Y-6100D02*
X258725Y-7400D01*
G01X261025Y-6100D02*
X260025D01*
G01X262825Y-4300D02*
X261025Y-6100D01*
G01X262825Y-2900D02*
Y-4300D01*
G01X262213Y-2288D02*
X262825Y-2900D01*
G01X262213Y10725D02*
Y-2288D01*
G01X260824Y12114D02*
X262213Y10725D01*
G01X259013Y13925D02*
X260824Y12114D01*
G01X259013Y16014D02*
Y13925D01*
G01X260463Y17464D02*
X259013Y16014D01*
G01X260463Y18828D02*
Y17464D01*
G01X262313Y20678D02*
X260463Y18828D01*
G01X262313Y25355D02*
Y20678D01*
G01X262013Y25655D02*
X262313Y25355D01*
G01X262013Y28399D02*
Y25655D01*
G01X263113Y29499D02*
X262013Y28399D01*
G01X263113Y34379D02*
Y29499D01*
G01X279336Y-3233D02*
X280203Y-4100D01*
G01X279336Y10200D02*
Y-3233D01*
G01X276436Y13100D02*
X279336Y10200D01*
G01X276436Y16036D02*
Y13100D01*
G01X277557Y17157D02*
X276436Y16036D01*
G01X235925Y-3012D02*
X237013Y-4100D01*
G01X235925Y-1132D02*
Y-3012D01*
G01X234492Y301D02*
X235925Y-1132D01*
G01X234492Y1500D02*
Y301D01*
G01X235992Y3000D02*
X234492Y1500D01*
G01X235992Y4200D02*
Y3000D01*
G01X234542Y5650D02*
X235992Y4200D01*
G01X234542Y7049D02*
Y5650D01*
G01X235925Y8432D02*
X234542Y7049D01*
G01X235925Y10301D02*
Y8432D01*
G01X233125Y13101D02*
X235925Y10301D01*
G01X233125Y16229D02*
Y13101D01*
G01X234053Y17157D02*
X233125Y16229D01*
G01X236013Y19117D02*
X234053Y17157D01*
G01X236013Y28479D02*
Y19117D01*
G01X235113Y29379D02*
X236013Y28479D01*
G01X235113Y34299D02*
Y29379D01*
G01X272736Y-3012D02*
X273824Y-4100D01*
G01X272736Y10301D02*
Y-3012D01*
G01X269936Y13101D02*
X272736Y10301D01*
G01X269936Y16229D02*
Y13101D01*
G01X270864Y17157D02*
X269936Y16229D01*
G01X270864Y-8347D02*
Y-9901D01*
G01X273111Y-6100D02*
X270864Y-8347D01*
G01X274335Y-6100D02*
X273111D01*
G01X275911Y-4524D02*
X274335Y-6100D01*
G01X275911Y-2900D02*
Y-4524D01*
G01X275136Y-2125D02*
X275911Y-2900D01*
G01X275136Y10888D02*
Y-2125D01*
G01X273910Y12114D02*
X275136Y10888D01*
G01X274335Y31700D02*
X275911Y33276D01*
G01X273111Y31700D02*
X274335D01*
G01X271992Y30581D02*
X273111Y31700D01*
G01X271992Y29027D02*
Y30581D01*
G01X270864Y27899D02*
X271992Y29027D01*
G01X293036Y14150D02*
X296036Y11150D01*
G01X293036Y15904D02*
Y14150D01*
G01X294289Y17157D02*
X293036Y15904D01*
G01X232707Y-2900D02*
Y-4300D01*
G01X232095Y-2288D02*
X232707Y-2900D01*
G01X232095Y10725D02*
Y-2288D01*
G01X232152Y28699D02*
Y18964D01*
G01X232702Y29249D02*
X232152Y28699D01*
G01X232702Y34691D02*
Y29249D01*
G01X265613Y28999D02*
Y34821D01*
G01X266413Y28199D02*
X265613Y28999D01*
G01X266413Y20015D02*
Y28199D01*
G01X264171Y17773D02*
X266413Y20015D01*
G01X264171Y17157D02*
Y17773D01*
G01X263050Y16036D02*
X264171Y17157D01*
G01X263050Y13100D02*
Y16036D01*
G01X266392Y9758D02*
X263050Y13100D01*
G01X266392Y8700D02*
Y9758D01*
G01X264592Y6900D02*
X266392Y8700D01*
G01X264592Y5325D02*
Y6900D01*
G01X265792Y4125D02*
X264592Y5325D01*
G01X265792Y2999D02*
Y4125D01*
G01X264592Y1799D02*
X265792Y2999D01*
G01X264592Y426D02*
Y1799D01*
G01X265950Y-932D02*
X264592Y426D01*
G01X265950Y-2133D02*
Y-932D01*
G01X267517Y-3700D02*
X265950Y-2133D01*
G01X280836Y31900D02*
X282292Y33356D01*
G01X279436Y31900D02*
X280836D01*
G01X277557Y30021D02*
X279436Y31900D01*
G01X277557Y27899D02*
Y30021D01*
G01Y-7779D02*
Y-9901D01*
G01X279436Y-5900D02*
X277557Y-7779D01*
G01X280836Y-5900D02*
X279436D01*
G01X282292Y-4444D02*
X280836Y-5900D01*
G01X282292Y-3100D02*
Y-4444D01*
G01X281676Y-2484D02*
X282292Y-3100D01*
G01X281676Y10641D02*
Y-2484D01*
G01X280203Y12114D02*
X281676Y10641D01*
G01X240746Y-7779D02*
Y-9901D01*
G01X242625Y-5900D02*
X240746Y-7779D01*
G01X244025Y-5900D02*
X242625D01*
G01X245481Y-4444D02*
X244025Y-5900D01*
G01X245481Y-3100D02*
Y-4444D01*
G01X244865Y-2484D02*
X245481Y-3100D01*
G01X244865Y10641D02*
Y-2484D01*
G01X243392Y12114D02*
X244865Y10641D01*
G01X241319Y14187D02*
X243392Y12114D01*
G01X241319Y15228D02*
Y14187D01*
G01X242813Y16722D02*
X241319Y15228D01*
G01X242813Y23421D02*
Y16722D01*
G01X245313Y25921D02*
X242813Y23421D01*
G01X245313Y37221D02*
Y25921D01*
G01X258913Y29099D02*
Y34721D01*
G01X259513Y28499D02*
X258913Y29099D01*
G01X259513Y21414D02*
Y28499D01*
G01X257478Y19379D02*
X259513Y21414D01*
G01X257478Y17157D02*
Y19379D01*
G01X256550Y16229D02*
X257478Y17157D01*
G01X256550Y13101D02*
Y16229D01*
G01X259592Y10059D02*
X256550Y13101D01*
G01X259592Y8674D02*
Y10059D01*
G01X257917Y6999D02*
X259592Y8674D01*
G01X257917Y5876D02*
Y6999D01*
G01X259417Y4376D02*
X257917Y5876D01*
G01X259417Y3024D02*
Y4376D01*
G01X257917Y1524D02*
X259417Y3024D01*
G01X257917Y301D02*
Y1524D01*
G01X259350Y-1132D02*
X257917Y301D01*
G01X259350Y-2226D02*
Y-1132D01*
G01X260824Y-3700D02*
X259350Y-2226D01*
G01X268913Y35379D02*
X269513Y34779D01*
G01X268913Y36900D02*
Y35379D01*
G01X269592Y37579D02*
X268913Y36900D01*
G01X269592Y45500D02*
Y37579D01*
G01X268913Y46179D02*
X269592Y45500D01*
G01X268913Y48114D02*
Y46179D01*
G01X269292Y48493D02*
X268913Y48114D01*
G01X269292Y53535D02*
Y48493D01*
G01X268963Y53864D02*
X269292Y53535D01*
G01X268963Y66499D02*
Y53864D01*
G01X269513Y67049D02*
X268963Y66499D01*
G01X269513Y72579D02*
Y67049D01*
G01X268913Y73179D02*
X269513Y72579D01*
G01X268913Y74621D02*
Y73179D01*
G01X269592Y75300D02*
X268913Y74621D01*
G01X269592Y83221D02*
Y75300D01*
G01X268913Y83900D02*
X269592Y83221D01*
G01X268913Y85914D02*
Y83900D01*
G01X269613Y86614D02*
X268913Y85914D01*
G01X269613Y91274D02*
Y86614D01*
G01X269013Y91874D02*
X269613Y91274D01*
G01X269013Y105420D02*
Y91874D01*
G01X240092Y37942D02*
X238946Y36796D01*
G01X240092Y44721D02*
Y37942D01*
G01X238613Y46200D02*
X240092Y44721D01*
G01X238613Y48314D02*
Y46200D01*
G01X238963Y48664D02*
X238613Y48314D01*
G01X238963Y53614D02*
Y48664D01*
G01X238713Y53864D02*
X238963Y53614D01*
G01X238713Y64521D02*
Y53864D01*
G01X238892Y64700D02*
X238713Y64521D01*
G01X238892Y74899D02*
Y64700D01*
G01X239392Y75399D02*
X238892Y74899D01*
G01X239392Y83300D02*
Y75399D01*
G01X238792Y83900D02*
X239392Y83300D01*
G01X238792Y86293D02*
Y83900D01*
G01X238942Y86443D02*
X238792Y86293D01*
G01X238942Y103350D02*
Y86443D01*
G01X242813Y92322D02*
Y104827D01*
G01X241463Y90972D02*
X242813Y92322D01*
G01X241463Y86714D02*
Y90972D01*
G01X242813Y85364D02*
X241463Y86714D01*
G01X242813Y84100D02*
Y85364D01*
G01X242292Y83579D02*
X242813Y84100D01*
G01X242292Y75100D02*
Y83579D01*
G01X242813Y74579D02*
X242292Y75100D01*
G01X242813Y73333D02*
Y74579D01*
G01X241492Y72012D02*
X242813Y73333D01*
G01X241492Y67388D02*
Y72012D01*
G01X242692Y66188D02*
X241492Y67388D01*
G01X242692Y54401D02*
Y66188D01*
G01X241463Y53172D02*
X242692Y54401D01*
G01X241463Y48914D02*
Y53172D01*
G01X242592Y47785D02*
X241463Y48914D01*
G01X242592Y46300D02*
Y47785D01*
G01X242192Y45900D02*
X242592Y46300D01*
G01X242192Y37600D02*
Y45900D01*
G01X242592Y37200D02*
X242192Y37600D01*
G01X242592Y35400D02*
Y37200D01*
G01X241592Y34400D02*
X242592Y35400D01*
G01X262213Y35279D02*
X263113Y34379D01*
G01X262213Y37121D02*
Y35279D01*
G01X262792Y37700D02*
X262213Y37121D01*
G01X262792Y45621D02*
Y37700D01*
G01X262213Y46200D02*
X262792Y45621D01*
G01X262213Y47914D02*
Y46200D01*
G01X263013Y48714D02*
X262213Y47914D01*
G01X263013Y53214D02*
Y48714D01*
G01X262313Y53914D02*
X263013Y53214D01*
G01X262313Y66499D02*
Y53914D01*
G01X263113Y67299D02*
X262313Y66499D01*
G01X263113Y72279D02*
Y67299D01*
G01X262213Y73179D02*
X263113Y72279D01*
G01X262213Y75121D02*
Y73179D01*
G01X262792Y75700D02*
X262213Y75121D01*
G01X262792Y83221D02*
Y75700D01*
G01X262213Y83800D02*
X262792Y83221D01*
G01X262213Y85714D02*
Y83800D01*
G01X263013Y86514D02*
X262213Y85714D01*
G01X263013Y91014D02*
Y86514D01*
G01X262313Y91714D02*
X263013Y91014D01*
G01X262313Y105121D02*
Y91714D01*
G01X277557Y62850D02*
Y54957D01*
G01X279466Y64759D02*
X277557Y62850D01*
G01X279466Y66225D02*
Y64759D01*
G01X278498Y67193D02*
X279466Y66225D01*
G01X278498Y67195D02*
Y67193D01*
G01X278366Y67327D02*
X278498Y67195D01*
G01X278366Y72275D02*
Y67327D01*
G01X279366Y73275D02*
X278366Y72275D01*
G01X279366Y75126D02*
Y73275D01*
G01X278892Y75600D02*
X279366Y75126D01*
G01X278892Y83526D02*
Y75600D01*
G01X279366Y84000D02*
X278892Y83526D01*
G01X279366Y85474D02*
Y84000D01*
G01X277966Y86874D02*
X279366Y85474D01*
G01X277966Y90674D02*
Y86874D01*
G01X279366Y92074D02*
X277966Y90674D01*
G01X279366Y104874D02*
Y92074D01*
G01X279336Y34567D02*
X280203Y33700D01*
G01X279336Y48000D02*
Y34567D01*
G01X276592Y50744D02*
X279336Y48000D01*
G01X276592Y53992D02*
Y50744D01*
G01X277557Y54957D02*
X276592Y53992D01*
G01X272092Y53729D02*
X270864Y54957D01*
G01X272092Y48745D02*
Y53729D01*
G01X272736Y48101D02*
X272092Y48745D01*
G01X272736Y34788D02*
Y48101D01*
G01X273824Y33700D02*
X272736Y34788D01*
G01X272766Y91774D02*
Y105074D01*
G01X271966Y90974D02*
X272766Y91774D01*
G01X271966Y86374D02*
Y90974D01*
G01X272766Y85574D02*
X271966Y86374D01*
G01X272766Y84000D02*
Y85574D01*
G01X272192Y83426D02*
X272766Y84000D01*
G01X272192Y75300D02*
Y83426D01*
G01X272766Y74726D02*
X272192Y75300D01*
G01X272766Y72959D02*
Y74726D01*
G01X271966Y72159D02*
X272766Y72959D01*
G01X271966Y67027D02*
Y72159D01*
G01X272766Y66227D02*
X271966Y67027D01*
G01X272766Y56859D02*
Y66227D01*
G01X270864Y54957D02*
X272766Y56859D01*
G01X236113Y35299D02*
X235113Y34299D01*
G01X236113Y36779D02*
Y35299D01*
G01X235592Y37300D02*
X236113Y36779D01*
G01X235592Y45679D02*
Y37300D01*
G01X236113Y46200D02*
X235592Y45679D01*
G01X236113Y47614D02*
Y46200D01*
G01X235113Y48614D02*
X236113Y47614D01*
G01X235113Y53414D02*
Y48614D01*
G01X236013Y54314D02*
X235113Y53414D01*
G01X236013Y66179D02*
Y54314D01*
G01X235113Y67079D02*
X236013Y66179D01*
G01X235113Y72099D02*
Y67079D01*
G01X236113Y73099D02*
X235113Y72099D01*
G01X236113Y74679D02*
Y73099D01*
G01X235592Y75200D02*
X236113Y74679D01*
G01X235592Y83499D02*
Y75200D01*
G01X236113Y84020D02*
X235592Y83499D01*
G01X236113Y85414D02*
Y84020D01*
G01X235113Y86414D02*
X236113Y85414D01*
G01X235113Y91214D02*
Y86414D01*
G01X236013Y92114D02*
X235113Y91214D01*
G01X236013Y105027D02*
Y92114D01*
G01X275566Y91474D02*
Y105628D01*
G01X275866Y91174D02*
X275566Y91474D01*
G01X275866Y86474D02*
Y91174D01*
G01X275466Y86074D02*
X275866Y86474D01*
G01X275466Y84100D02*
Y86074D01*
G01X276192Y83374D02*
X275466Y84100D01*
G01X276192Y75900D02*
Y83374D01*
G01X275466Y75174D02*
X276192Y75900D01*
G01X275466Y72959D02*
Y75174D01*
G01X275766Y72659D02*
X275466Y72959D01*
G01X275766Y67359D02*
Y72659D01*
G01X275392Y66985D02*
X275766Y67359D01*
G01X275392Y55500D02*
Y66985D01*
G01X274592Y54700D02*
X275392Y55500D01*
G01X274592Y50596D02*
Y54700D01*
G01X273910Y49914D02*
X274592Y50596D01*
G01X275136Y48688D02*
X273910Y49914D01*
G01X275136Y35675D02*
Y48688D01*
G01X275911Y34900D02*
X275136Y35675D01*
G01X275911Y33276D02*
Y34900D01*
G01X232102Y35291D02*
X232702Y34691D01*
G01X232102Y36910D02*
Y35291D01*
G01X232792Y37600D02*
X232102Y36910D01*
G01X232792Y45610D02*
Y37600D01*
G01X232102Y46300D02*
X232792Y45610D01*
G01X232102Y48064D02*
Y46300D01*
G01X232613Y48575D02*
X232102Y48064D01*
G01X232613Y53453D02*
Y48575D01*
G01X232152Y53914D02*
X232613Y53453D01*
G01X232152Y66499D02*
Y53914D01*
G01X232652Y66999D02*
X232152Y66499D01*
G01X232652Y72541D02*
Y66999D01*
G01X232102Y73091D02*
X232652Y72541D01*
G01X232102Y74610D02*
Y73091D01*
G01X232492Y75000D02*
X232102Y74610D01*
G01X232492Y83610D02*
Y75000D01*
G01X232102Y84000D02*
X232492Y83610D01*
G01X232102Y85914D02*
Y84000D01*
G01X232802Y86614D02*
X232102Y85914D01*
G01X232802Y91274D02*
Y86614D01*
G01X231853Y92223D02*
X232802Y91274D01*
G01X231853Y121699D02*
Y92223D01*
G01X266066Y91667D02*
Y104974D01*
G01X265513Y91114D02*
X266066Y91667D01*
G01X265513Y86414D02*
Y91114D01*
G01X266113Y85814D02*
X265513Y86414D01*
G01X266113Y84000D02*
Y85814D01*
G01X265392Y83279D02*
X266113Y84000D01*
G01X265392Y75400D02*
Y83279D01*
G01X266113Y74679D02*
X265392Y75400D01*
G01X266113Y73121D02*
Y74679D01*
G01X265613Y72621D02*
X266113Y73121D01*
G01X265613Y66799D02*
Y72621D01*
G01X266463Y65949D02*
X265613Y66799D01*
G01X266463Y54264D02*
Y65949D01*
G01X265513Y53314D02*
X266463Y54264D01*
G01X265513Y48614D02*
Y53314D01*
G01X266113Y48014D02*
X265513Y48614D01*
G01X266113Y46200D02*
Y48014D01*
G01X265546Y45633D02*
X266113Y46200D01*
G01X265546Y37746D02*
Y45633D01*
G01X266113Y37179D02*
X265546Y37746D01*
G01X266113Y35321D02*
Y37179D01*
G01X265613Y34821D02*
X266113Y35321D01*
G01X282066Y84000D02*
Y105071D01*
G01X282792Y83274D02*
X282066Y84000D01*
G01X282792Y75600D02*
Y83274D01*
G01X282066Y74874D02*
X282792Y75600D01*
G01X282066Y64259D02*
Y74874D01*
G01X279616Y61809D02*
X282066Y64259D01*
G01X279616Y54474D02*
Y61809D01*
G01X278492Y53350D02*
X279616Y54474D01*
G01X278492Y51625D02*
Y53350D01*
G01X280203Y49914D02*
X278492Y51625D01*
G01X281676Y48441D02*
X280203Y49914D01*
G01X281676Y35316D02*
Y48441D01*
G01X282292Y34700D02*
X281676Y35316D01*
G01X282292Y33356D02*
Y34700D01*
G01X245892Y37800D02*
X245313Y37221D01*
G01X245892Y45521D02*
Y37800D01*
G01X245313Y46100D02*
X245892Y45521D01*
G01X245313Y74821D02*
Y46100D01*
G01X245892Y75400D02*
X245313Y74821D01*
G01X245892Y83401D02*
Y75400D01*
G01X245313Y83980D02*
X245892Y83401D01*
G01X245313Y114796D02*
Y83980D01*
G01X259313Y91614D02*
Y105627D01*
G01X258913Y91214D02*
X259313Y91614D01*
G01X258913Y86514D02*
Y91214D01*
G01X259713Y85714D02*
X258913Y86514D01*
G01X259713Y84120D02*
Y85714D01*
G01X259092Y83499D02*
X259713Y84120D01*
G01X259092Y75600D02*
Y83499D01*
G01X259713Y74979D02*
X259092Y75600D01*
G01X259713Y73321D02*
Y74979D01*
G01X258913Y72521D02*
X259713Y73321D01*
G01X258913Y66899D02*
Y72521D01*
G01X259313Y66499D02*
X258913Y66899D01*
G01X259313Y53814D02*
Y66499D01*
G01X258913Y53414D02*
X259313Y53814D01*
G01X258913Y48714D02*
Y53414D01*
G01X259713Y47914D02*
X258913Y48714D01*
G01X259713Y46400D02*
Y47914D01*
G01X258992Y45679D02*
X259713Y46400D01*
G01X258992Y37700D02*
Y45679D01*
G01X259713Y36979D02*
X258992Y37700D01*
G01X259713Y35521D02*
Y36979D01*
G01X258913Y34721D02*
X259713Y35521D01*
G01X293036Y53704D02*
X294289Y54957D01*
G01X293036Y51950D02*
Y53704D01*
G01X296036Y48950D02*
X293036Y51950D01*
G01X269534Y105941D02*
X269013Y105420D01*
G01X269534Y110606D02*
Y105941D01*
G01X268866Y111274D02*
X269534Y110606D01*
G01X268866Y113374D02*
Y111274D01*
G01X304092Y148600D02*
X268866Y113374D01*
G01X238713Y103579D02*
X238942Y103350D01*
G01X238713Y105621D02*
Y103579D01*
G01X238966Y105874D02*
X238713Y105621D01*
G01X238966Y111174D02*
Y105874D01*
G01X238366Y111774D02*
X238966Y111174D01*
G01X238366Y124246D02*
Y111774D01*
G01X305092Y190972D02*
X238366Y124246D01*
G01X266486Y148830D02*
X307992Y190336D01*
G01X266486Y146238D02*
Y148830D01*
G01X246835Y126587D02*
X266486Y146238D01*
G01X246835Y125879D02*
Y126587D01*
G01X249281Y123433D02*
X246835Y125879D01*
G01X249281Y122300D02*
Y123433D01*
G01X248045Y121064D02*
X249281Y122300D01*
G01X246916Y121064D02*
X248045D01*
G01X244990Y122990D02*
X246916Y121064D01*
G01X244282Y122990D02*
X244990D01*
G01X242727Y121435D02*
X244282Y122990D01*
G01X242727Y120727D02*
Y121435D01*
G01X244652Y118802D02*
X242727Y120727D01*
G01X244652Y117671D02*
Y118802D01*
G01X242566Y115585D02*
X244652Y117671D01*
G01X242566Y111474D02*
Y115585D01*
G01X241466Y110374D02*
X242566Y111474D01*
G01X241466Y106174D02*
Y110374D01*
G01X242813Y104827D02*
X241466Y106174D01*
G01X262966Y105774D02*
X262313Y105121D01*
G01X262966Y110674D02*
Y105774D01*
G01X262166Y111474D02*
X262966Y110674D01*
G01X262166Y113746D02*
Y111474D01*
G01X291092Y142672D02*
X262166Y113746D01*
G01X291092Y152029D02*
Y142672D01*
G01X330718Y191655D02*
X291092Y152029D01*
G01X243425Y142825D02*
Y142033D01*
G01X242467Y143783D02*
X243425Y142825D01*
G01X242467Y144575D02*
Y143783D01*
G01X243486Y145594D02*
X242467Y144575D01*
G01X244278Y145594D02*
X243486D01*
G01X245236Y144636D02*
X244278Y145594D01*
G01X246028Y144636D02*
X245236D01*
G01X252320Y150928D02*
X246028Y144636D01*
G01X252320Y151790D02*
Y150928D01*
G01X250813Y153297D02*
X252320Y151790D01*
G01X250813Y154159D02*
Y153297D01*
G01X251677Y155023D02*
X250813Y154159D01*
G01X252539Y155023D02*
X251677D01*
G01X254046Y153516D02*
X252539Y155023D01*
G01X254908Y153516D02*
X254046D01*
G01X255772Y154380D02*
X254908Y153516D01*
G01X255772Y155242D02*
Y154380D01*
G01X254265Y156749D02*
X255772Y155242D01*
G01X278266Y105974D02*
X279366Y104874D01*
G01X278266Y111618D02*
Y105974D01*
G01X277557Y112327D02*
X278266Y111618D01*
G01X271966Y111225D02*
X270864Y112327D01*
G01X271966Y105874D02*
Y111225D01*
G01X272766Y105074D02*
X271966Y105874D01*
G01X235166D02*
X236013Y105027D01*
G01X235166Y110674D02*
Y105874D01*
G01X235853Y111361D02*
X235166Y110674D01*
G01X235853Y125269D02*
Y111361D01*
G01X272834Y162250D02*
X235853Y125269D01*
G01X239388Y145495D02*
Y141696D01*
G01X244981Y151088D02*
X239388Y145495D01*
G01X245844Y151088D02*
X244981D01*
G01X246371Y150561D02*
X245844Y151088D01*
G01X247079Y150561D02*
X246371D01*
G01X248097Y151579D02*
X247079Y150561D01*
G01X248097Y152287D02*
Y151579D01*
G01X247569Y152815D02*
X248097Y152287D01*
G01X247569Y153676D02*
Y152815D01*
G01X279493Y185600D02*
X247569Y153676D01*
G01X275566Y105628D02*
X273910Y107284D01*
G01X231853Y126926D02*
Y125359D01*
G01X268376Y163449D02*
X231853Y126926D01*
G01X266066Y114110D02*
X293592Y141636D01*
G01X266066Y111174D02*
Y114110D01*
G01X265466Y110574D02*
X266066Y111174D01*
G01X265466Y105574D02*
Y110574D01*
G01X266066Y104974D02*
X265466Y105574D01*
G01X282066Y105071D02*
X280203Y106934D01*
G01X251192Y120675D02*
X245313Y114796D01*
G01X251192Y127654D02*
Y120675D01*
G01X268894Y145356D02*
X251192Y127654D01*
G01X268894Y147702D02*
Y145356D01*
G01X310892Y189700D02*
X268894Y147702D01*
G01X232523Y137698D02*
X231661D01*
G01X233387Y138562D02*
X232523Y137698D01*
G01X233387Y139424D02*
Y138562D01*
G01X232183Y140628D02*
X233387Y139424D01*
G01X232183Y141490D02*
Y140628D01*
G01X271861Y181168D02*
X232183Y141490D01*
G01X284692Y149165D02*
X328392Y192865D01*
G01X284692Y147250D02*
Y149165D01*
G01X288021Y143921D02*
X284692Y147250D01*
G01X288021Y143129D02*
Y143921D01*
G01X287087Y142195D02*
X288021Y143129D01*
G01X286295Y142195D02*
X287087D01*
G01X283030Y145460D02*
X286295Y142195D01*
G01X282168Y145460D02*
X283030D01*
G01X281304Y144596D02*
X282168Y145460D01*
G01X281304Y143734D02*
Y144596D01*
G01X284530Y140508D02*
X281304Y143734D01*
G01X284530Y139646D02*
Y140508D01*
G01X259566Y114682D02*
X284530Y139646D01*
G01X259566Y111474D02*
Y114682D01*
G01X258566Y110474D02*
X259566Y111474D01*
G01X258566Y106374D02*
Y110474D01*
G01X259313Y105627D02*
X258566Y106374D01*
G01X232054Y172293D02*
Y171431D01*
G01X232294Y175505D02*
X231432D01*
G01X233780Y174019D02*
X232294Y175505D01*
G01X234642Y174019D02*
X233780D01*
G01X235506Y174883D02*
X234642Y174019D01*
G01X235506Y175745D02*
Y174883D01*
G01X234020Y177231D02*
X235506Y175745D01*
G01X234020Y178093D02*
Y177231D01*
G01X234884Y178957D02*
X234020Y178093D01*
G01X235746Y178957D02*
X234884D01*
G01X237232Y177471D02*
X235746Y178957D01*
G01X238094Y177471D02*
X237232D01*
G01X238958Y178335D02*
X238094Y177471D01*
G01X238958Y179197D02*
Y178335D01*
G01X237472Y180683D02*
X238958Y179197D01*
G01X237472Y181545D02*
Y180683D01*
G01X238336Y182409D02*
X237472Y181545D01*
G01X239198Y182409D02*
X238336D01*
G01X240684Y180923D02*
X239198Y182409D01*
G01X241546Y180923D02*
X240684D01*
G01X242410Y181787D02*
X241546Y180923D01*
G01X242410Y182649D02*
Y181787D01*
G01X240924Y184135D02*
X242410Y182649D01*
G01X240924Y184997D02*
Y184135D01*
G01X258592Y202665D02*
X240924Y184997D01*
G01X258592Y205597D02*
Y202665D01*
G01X262828Y209833D02*
X258592Y205597D01*
G01X268487Y199831D02*
X268688D01*
G01X255720Y187064D02*
X268487Y199831D01*
G01X255720Y186272D02*
Y187064D01*
G01X257128Y184864D02*
X255720Y186272D01*
G01X257128Y184068D02*
Y184864D01*
G01X255548Y182488D02*
X257128Y184068D01*
G01X254686Y182488D02*
X255548D01*
G01X252764Y184410D02*
X254686Y182488D01*
G01X251902Y184410D02*
X252764D01*
G01X250912Y183420D02*
X251902Y184410D01*
G01X250912Y182558D02*
Y183420D01*
G01X252834Y180636D02*
X250912Y182558D01*
G01X252834Y179774D02*
Y180636D01*
G01X261981Y212333D02*
X262828D01*
G01X254659Y205011D02*
X261981Y212333D01*
G01X254659Y201809D02*
Y205011D01*
G01X252829Y199979D02*
X254659Y201809D01*
G01X251967Y199979D02*
X252829D01*
G01X250406Y201540D02*
X251967Y199979D01*
G01X249544Y201540D02*
X250406D01*
G01X248680Y200676D02*
X249544Y201540D01*
G01X248680Y199814D02*
Y200676D01*
G01X250241Y198253D02*
X248680Y199814D01*
G01X250241Y197391D02*
Y198253D01*
G01X249377Y196527D02*
X250241Y197391D01*
G01X248515Y196527D02*
X249377D01*
G01X246954Y198088D02*
X248515Y196527D01*
G01X246092Y198088D02*
X246954D01*
G01X245228Y197224D02*
X246092Y198088D01*
G01X245228Y196362D02*
Y197224D01*
G01X246789Y194801D02*
X245228Y196362D01*
G01X246789Y193939D02*
Y194801D01*
G01X245925Y193075D02*
X246789Y193939D01*
G01X245063Y193075D02*
X245925D01*
G01X243502Y194636D02*
X245063Y193075D01*
G01X242640Y194636D02*
X243502D01*
G01X241776Y193772D02*
X242640Y194636D01*
G01X241776Y192910D02*
Y193772D01*
G01X243337Y191349D02*
X241776Y192910D01*
G01X243337Y190487D02*
Y191349D01*
G01X242473Y189623D02*
X243337Y190487D01*
G01X241611Y189623D02*
X242473D01*
G01X240050Y191184D02*
X241611Y189623D01*
G01X239188Y191184D02*
X240050D01*
G01X238324Y190320D02*
X239188Y191184D01*
G01X238324Y189458D02*
Y190320D01*
G01X239885Y187897D02*
X238324Y189458D01*
G01X239885Y187035D02*
Y187897D01*
G01X239021Y186171D02*
X239885Y187035D01*
G01X238159Y186171D02*
X239021D01*
G01X236598Y187732D02*
X238159Y186171D01*
G01X235736Y187732D02*
X236598D01*
G01X234872Y186868D02*
X235736Y187732D01*
G01X234872Y186006D02*
Y186868D01*
G01X236433Y184445D02*
X234872Y186006D01*
G01X236433Y183583D02*
Y184445D01*
G01X234265Y181415D02*
X236433Y183583D01*
G01X233403Y181415D02*
X234265D01*
G01X231888Y182930D02*
X233403Y181415D01*
G01X231677Y178827D02*
Y179689D01*
G01X254265Y157611D02*
Y156749D01*
G01X255129Y158475D02*
X254265Y157611D01*
G01X255991Y158475D02*
X255129D01*
G01X257498Y156968D02*
X255991Y158475D01*
G01X258360Y156968D02*
X257498D01*
G01X259224Y157832D02*
X258360Y156968D01*
G01X259224Y158694D02*
Y157832D01*
G01X257717Y160201D02*
X259224Y158694D01*
G01X257717Y161063D02*
Y160201D01*
G01X259415Y162761D02*
X257717Y161063D01*
G01X263653Y162761D02*
X259415D01*
G01X265998Y165106D02*
X263653Y162761D01*
G01X265998Y168705D02*
Y165106D01*
G01X280193Y182900D02*
X265998Y168705D01*
G01X281961Y182900D02*
X280193D01*
G01X288531Y189470D02*
X281961Y182900D01*
G01X262828Y217333D02*
X257559D01*
G01X248029Y183737D02*
Y178627D01*
G01X268948Y204656D02*
X248029Y183737D01*
G01X268948Y204941D02*
Y204656D01*
G01X272834Y163382D02*
Y162250D01*
G01X272100Y164116D02*
X272834Y163382D01*
G01X272100Y164908D02*
Y164116D01*
G01X273571Y166379D02*
X272100Y164908D01*
G01X274363Y166379D02*
X273571D01*
G01X275097Y165645D02*
X274363Y166379D01*
G01X276229Y165645D02*
X275097D01*
G01X300092Y189508D02*
X276229Y165645D01*
G01X281125Y185600D02*
X279493D01*
G01X284962Y189437D02*
X281125Y185600D01*
G01X268376Y167884D02*
Y163449D01*
G01X270958Y170466D02*
X268376Y167884D01*
G01X273064Y170466D02*
X270958D01*
G01X278671Y176073D02*
X273064Y170466D01*
G01X279463Y176073D02*
X278671D01*
G01X280419Y175117D02*
X279463Y176073D01*
G01X281281Y175117D02*
X280419D01*
G01X282145Y175981D02*
X281281Y175117D01*
G01X282145Y176843D02*
Y175981D01*
G01X280171Y178817D02*
X282145Y176843D01*
G01X280171Y179679D02*
Y178817D01*
G01X281192Y180700D02*
X280171Y179679D01*
G01X283511Y180700D02*
X281192D01*
G01X284578Y179633D02*
X283511Y180700D01*
G01X285751Y179633D02*
X284578D01*
G01X287100Y180982D02*
X285751Y179633D01*
G01X287100Y182562D02*
Y180982D01*
G01X287600Y183062D02*
X287100Y182562D01*
G01X289180Y183062D02*
X287600D01*
G01X290312Y184194D02*
X289180Y183062D01*
G01X290312Y186920D02*
Y184194D01*
G01X267080Y206688D02*
Y206810D01*
G01X245606Y185214D02*
X267080Y206688D01*
G01X245606Y180318D02*
Y185214D01*
G01X271861Y182030D02*
Y181168D01*
G01X270513Y183378D02*
X271861Y182030D01*
G01X270513Y184240D02*
Y183378D01*
G01X271377Y185104D02*
X270513Y184240D01*
G01X272239Y185104D02*
X271377D01*
G01X273587Y183756D02*
X272239Y185104D01*
G01X274449Y183756D02*
X273587D01*
G01X275313Y184620D02*
X274449Y183756D01*
G01X275313Y185482D02*
Y184620D01*
G01X273965Y186830D02*
X275313Y185482D01*
G01X273965Y187692D02*
Y186830D01*
G01X274829Y188556D02*
X273965Y187692D01*
G01X275691Y188556D02*
X274829D01*
G01X277039Y187208D02*
X275691Y188556D01*
G01X277901Y187208D02*
X277039D01*
G01X282133Y191440D02*
X277901Y187208D01*
G01X283489Y191440D02*
X282133D01*
G01X259597Y187405D02*
Y183061D01*
G01X269523Y197331D02*
X259597Y187405D01*
G01X270337Y197331D02*
X269523D01*
G01X252392Y209500D02*
Y208400D01*
G01X257725Y214833D02*
X252392Y209500D01*
G01X262828Y214833D02*
X257725D01*
G01X253387Y234442D02*
X257448D01*
G01X246704Y245980D02*
X257772D01*
G01X234264Y233540D02*
X246704Y245980D01*
G01X231700Y233540D02*
X234264D01*
G01X245003Y248485D02*
X258506D01*
G01X233168Y236650D02*
X245003Y248485D01*
G01X239401Y259130D02*
X260086D01*
G01X238365Y261630D02*
X260369D01*
G01X252351Y236942D02*
X257250D01*
G01X238129Y264130D02*
X260368D01*
G01X252038Y240980D02*
X259087D01*
G01X236642Y225584D02*
X252038Y240980D01*
G01X235780Y225584D02*
X236642D01*
G01X233625Y227739D02*
X235780Y225584D01*
G01X232763Y227739D02*
X233625D01*
G01X231899Y226875D02*
X232763Y227739D01*
G01X231899Y226013D02*
Y226875D01*
G01X234054Y223858D02*
X231899Y226013D01*
G01X234054Y222996D02*
Y223858D01*
G01X233190Y222132D02*
X234054Y222996D01*
G01X232328Y222132D02*
X233190D01*
G01X255059Y229042D02*
X257128D01*
G01X259321Y266630D02*
X237821D01*
G01X248688Y243480D02*
X259009D01*
G01X236280Y231072D02*
X248688Y243480D01*
G01X232768Y231072D02*
X236280D01*
G01X254023Y231542D02*
X257128D01*
G01X256398Y338600D02*
X244896D01*
G01X245662Y340500D02*
X256756D01*
G01X253216Y375200D02*
X253248Y375168D01*
G01X249526Y375200D02*
X253216D01*
G01X239092Y385634D02*
X249526Y375200D01*
G01X239092Y397364D02*
Y385634D01*
G01X252989Y344928D02*
X246567D01*
G01X232592Y384136D02*
Y393256D01*
G01X249328Y367400D02*
X232592Y384136D01*
G01X254421Y367400D02*
X249328D01*
G01X254448Y367427D02*
X254421Y367400D01*
G01X236792Y385268D02*
Y396128D01*
G01X249360Y372700D02*
X236792Y385268D01*
G01X253149Y372700D02*
X249360D01*
G01X253248Y372601D02*
X253149Y372700D01*
G01X249205Y363373D02*
X248419D01*
G01X251992Y393974D02*
Y402399D01*
G01X255677Y390289D02*
X251992Y393974D01*
G01X249577Y360900D02*
X247792D01*
G01X249621Y360856D02*
X249577Y360900D01*
G01X254392Y396500D02*
Y403571D01*
G01X257592Y393300D02*
X254392Y396500D01*
G01X259491Y393300D02*
X257592D01*
G01X259499Y393292D02*
X259491Y393300D01*
G01X249072Y358600D02*
X247092D01*
G01X249436Y358236D02*
X249072Y358600D01*
G01X234492Y384902D02*
Y394892D01*
G01X249294Y370100D02*
X234492Y384902D01*
G01X253389Y370100D02*
X249294D01*
G01X253558Y369931D02*
X253389Y370100D01*
G01X267476Y401870D02*
X262087Y407259D01*
G01X252888Y342428D02*
X246401D01*
G01X247156Y355736D02*
X249457D01*
G01X265699Y400093D02*
X260202Y405590D01*
G01X249592Y391800D02*
Y401199D01*
G01X253603Y387789D02*
X249592Y391800D01*
G01X255997Y387789D02*
X253603D01*
G01X257192Y398130D02*
Y406745D01*
G01X259499Y395823D02*
X257192Y398130D01*
G01X265857Y411380D02*
Y420959D01*
G01X270872Y406365D02*
X265857Y411380D01*
G01X259681Y461835D02*
X236166Y485350D01*
G01X271057Y461835D02*
X259681D01*
G01X289992Y442900D02*
X271057Y461835D01*
G01X289992Y423900D02*
Y442900D01*
G01X304375Y409517D02*
X289992Y423900D01*
G01X238101Y424310D02*
Y425342D01*
G01X236970Y423179D02*
X238101Y424310D01*
G01X235738Y423179D02*
X236970D01*
G01X259867Y453259D02*
X258735D01*
G01X261784Y455176D02*
X259867Y453259D01*
G01X262916Y455176D02*
X261784D01*
G01X264047Y454045D02*
X262916Y455176D01*
G01X264047Y452913D02*
Y454045D01*
G01X262130Y450996D02*
X264047Y452913D01*
G01X262130Y449864D02*
Y450996D01*
G01X263049Y448945D02*
X262130Y449864D01*
G01X264179Y448945D02*
X263049D01*
G01X266014Y450781D02*
X264179Y448945D01*
G01X267144Y450781D02*
X266014D01*
G01X278645Y439280D02*
X267144Y450781D01*
G01X279775Y439280D02*
X278645D01*
G01X281128Y440632D02*
X279775Y439280D01*
G01X282258Y440632D02*
X281128D01*
G01X283391Y439499D02*
X282258Y440632D01*
G01X283391Y438369D02*
Y439499D01*
G01X282038Y437017D02*
X283391Y438369D01*
G01X282038Y435887D02*
Y437017D01*
G01X283292Y434633D02*
X282038Y435887D01*
G01X283292Y418507D02*
Y434633D01*
G01X286903Y414896D02*
X283292Y418507D01*
G01X253538Y412345D02*
Y413477D01*
G01X252407Y411214D02*
X253538Y412345D01*
G01X251275Y411214D02*
X252407D01*
G01X240107Y422382D02*
X251275Y411214D01*
G01X238975Y422382D02*
X240107D01*
G01X237844Y421251D02*
X238975Y422382D01*
G01X237844Y420119D02*
Y421251D01*
G01X254392Y403571D02*
X237844Y420119D01*
G01X262087Y407259D02*
Y417657D01*
G01X281373Y463787D02*
Y464919D01*
G01X281255Y463669D02*
X281373Y463787D01*
G01X281255Y462537D02*
Y463669D01*
G01X282386Y461406D02*
X281255Y462537D01*
G01X283518Y461406D02*
X282386D01*
G01X283636Y461524D02*
X283518Y461406D01*
G01X284768Y461524D02*
X283636D01*
G01X285899Y460393D02*
X284768Y461524D01*
G01X285899Y459261D02*
Y460393D01*
G01X285781Y459143D02*
X285899Y459261D01*
G01X285781Y458011D02*
Y459143D01*
G01X286912Y456880D02*
X285781Y458011D01*
G01X288044Y456880D02*
X286912D01*
G01X288162Y456998D02*
X288044Y456880D01*
G01X289294Y456998D02*
X288162D01*
G01X290425Y455867D02*
X289294Y456998D01*
G01X290425Y454735D02*
Y455867D01*
G01X290307Y454617D02*
X290425Y454735D01*
G01X290307Y453485D02*
Y454617D01*
G01X291438Y452354D02*
X290307Y453485D01*
G01X292570Y452354D02*
X291438D01*
G01X292688Y452472D02*
X292570Y452354D01*
G01X293820Y452472D02*
X292688D01*
G01X260202Y405590D02*
Y416006D01*
G01X262705Y463879D02*
X260124Y466460D01*
G01X272613Y463879D02*
X262705D01*
G01X292492Y444000D02*
X272613Y463879D01*
G01X292492Y425000D02*
Y444000D01*
G01X306875Y410617D02*
X292492Y425000D01*
G01X264229Y445295D02*
X263097D01*
G01X266047Y447113D02*
X264229Y445295D01*
G01X267179Y447113D02*
X266047D01*
G01X268310Y445982D02*
X267179Y447113D01*
G01X268310Y444850D02*
Y445982D01*
G01X266392Y442932D02*
X268310Y444850D01*
G01X266392Y441800D02*
Y442932D01*
G01X267523Y440669D02*
X266392Y441800D01*
G01X268655Y440669D02*
X267523D01*
G01X270573Y442587D02*
X268655Y440669D01*
G01X271705Y442587D02*
X270573D01*
G01X273067Y441225D02*
X271705Y442587D01*
G01X273067Y440093D02*
Y441225D01*
G01X272649Y439675D02*
X273067Y440093D01*
G01X272649Y438543D02*
Y439675D01*
G01X273780Y437412D02*
X272649Y438543D01*
G01X274912Y437412D02*
X273780D01*
G01X275330Y437830D02*
X274912Y437412D01*
G01X276462Y437830D02*
X275330D01*
G01X280792Y433500D02*
X276462Y437830D01*
G01X280792Y416633D02*
Y433500D01*
G01X285116Y412309D02*
X280792Y416633D01*
G01X294992Y445100D02*
X274131Y465961D01*
G01X263972Y409729D02*
Y419308D01*
G01X269104Y404597D02*
X263972Y409729D01*
G01X257192Y410631D02*
Y413359D01*
G01X256554Y409993D02*
X257192Y410631D01*
G01X253886Y409993D02*
X256554D01*
G01X253248Y409355D02*
X253886Y409993D01*
G01X253248Y407965D02*
Y409355D01*
G01X253830Y407383D02*
X253248Y407965D01*
G01X256554Y407383D02*
X253830D01*
G01X257192Y406745D02*
X256554Y407383D01*
G01X257892Y457900D02*
X231492Y484300D01*
G01X263892Y457900D02*
X257892D01*
G01X265044Y456748D02*
X263892Y457900D01*
G01X266176Y456748D02*
X265044D01*
G01X268189Y458761D02*
X266176Y456748D01*
G01X269441Y458761D02*
X268189D01*
G01X270572Y457630D02*
X269441Y458761D01*
G01X270572Y456618D02*
Y457630D01*
G01X268439Y454485D02*
X270572Y456618D01*
G01X268439Y453353D02*
Y454485D01*
G01X269709Y452083D02*
X268439Y453353D01*
G01X270841Y452083D02*
X269709D01*
G01X273081Y454323D02*
X270841Y452083D01*
G01X274262Y454323D02*
X273081D01*
G01X275393Y453192D02*
X274262Y454323D01*
G01X275393Y452109D02*
Y453192D01*
G01X273104Y449820D02*
X275393Y452109D01*
G01X273104Y448688D02*
Y449820D01*
G01X274235Y447557D02*
X273104Y448688D01*
G01X275367Y447557D02*
X274235D01*
G01X277365Y449555D02*
X275367Y447557D01*
G01X278546Y449555D02*
X277365D01*
G01X279677Y448424D02*
X278546Y449555D01*
G01X279677Y447341D02*
Y448424D01*
G01X277630Y445294D02*
X279677Y447341D01*
G01X277630Y444162D02*
Y445294D01*
G01X278761Y443031D02*
X277630Y444162D01*
G01X279893Y443031D02*
X278761D01*
G01X281311Y444449D02*
X279893Y443031D01*
G01X282443Y444449D02*
X281311D01*
G01X285892Y441000D02*
X282443Y444449D01*
G01X285892Y419443D02*
Y441000D01*
G01X288671Y416664D02*
X285892Y419443D01*
G01X269701Y436023D02*
X268569D01*
G01X270019Y436341D02*
X269701Y436023D01*
G01X271151Y436341D02*
X270019D01*
G01X272282Y435210D02*
X271151Y436341D01*
G01X272282Y434078D02*
Y435210D01*
G01X271664Y433460D02*
X272282Y434078D01*
G01X271664Y432328D02*
Y433460D01*
G01X272803Y431189D02*
X271664Y432328D01*
G01X273935Y431189D02*
X272803D01*
G01X275953Y433207D02*
X273935Y431189D01*
G01X277085Y433207D02*
X275953D01*
G01X278216Y432076D02*
X277085Y433207D01*
G01X278216Y430944D02*
Y432076D01*
G01X276498Y429226D02*
X278216Y430944D01*
G01X276498Y428094D02*
Y429226D01*
G01X278292Y426300D02*
X276498Y428094D01*
G01X278292Y415597D02*
Y426300D01*
G01X283098Y410791D02*
X278292Y415597D01*
G01X235692Y519621D02*
Y527900D01*
G01X236013Y519300D02*
X235692Y519621D01*
G01X236013Y517357D02*
Y519300D01*
G01X235113Y516457D02*
X236013Y517357D01*
G01X235113Y511797D02*
Y516457D01*
G01X236192Y510718D02*
X235113Y511797D01*
G01X236192Y509400D02*
Y510718D01*
G01X235392Y508600D02*
X236192Y509400D01*
G01X235392Y502400D02*
Y508600D01*
G01X235166Y502174D02*
X235392Y502400D01*
G01X235166Y489426D02*
Y502174D01*
G01X236166Y488426D02*
X235166Y489426D01*
G01X236166Y485350D02*
Y488426D01*
G01X262492Y519479D02*
Y527700D01*
G01X262313Y519300D02*
X262492Y519479D01*
G01X262313Y517357D02*
Y519300D01*
G01X263113Y516557D02*
X262313Y517357D01*
G01X263113Y512157D02*
Y516557D01*
G01X262213Y511257D02*
X263113Y512157D01*
G01X262213Y494879D02*
Y511257D01*
G01X262779Y494313D02*
X262213Y494879D01*
G01X262779Y489114D02*
Y494313D01*
G01X268393Y483500D02*
X262779Y489114D01*
G01X285292Y483500D02*
X268393D01*
G01X286824Y481968D02*
X285292Y483500D01*
G01X287686Y481968D02*
X286824D01*
G01X288217Y482499D02*
X287686Y481968D01*
G01X289079Y482499D02*
X288217D01*
G01X290480Y481098D02*
X289079Y482499D01*
G01X290480Y480236D02*
Y481098D01*
G01X289949Y479705D02*
X290480Y480236D01*
G01X289949Y478843D02*
Y479705D01*
G01X291350Y477442D02*
X289949Y478843D01*
G01X292212Y477442D02*
X291350D01*
G01X292743Y477973D02*
X292212Y477442D01*
G01X293605Y477973D02*
X292743D01*
G01X282592Y518900D02*
Y527800D01*
G01X282124Y518432D02*
X282592Y518900D01*
G01X282124Y505811D02*
Y518432D01*
G01X280203Y503890D02*
X282124Y505811D01*
G01X280203Y493244D02*
Y503890D01*
G01X279192Y519832D02*
Y527900D01*
G01X279424Y519600D02*
X279192Y519832D01*
G01X279424Y517457D02*
Y519600D01*
G01X278274Y516307D02*
X279424Y517457D01*
G01X278274Y512057D02*
Y516307D01*
G01X279624Y510707D02*
X278274Y512057D01*
G01X279624Y507109D02*
Y510707D01*
G01X277557Y505042D02*
X279624Y507109D01*
G01X277557Y498644D02*
Y505042D01*
G01X272592Y519532D02*
Y527700D01*
G01X272824Y519300D02*
X272592Y519532D01*
G01X272824Y517357D02*
Y519300D01*
G01X271924Y516457D02*
X272824Y517357D01*
G01X271924Y511757D02*
Y516457D01*
G01X272924Y510757D02*
X271924Y511757D01*
G01X272924Y508610D02*
Y510757D01*
G01X271092Y506778D02*
X272924Y508610D01*
G01X271092Y498644D02*
Y506778D01*
G01X275892Y519768D02*
Y527900D01*
G01X275524Y519400D02*
X275892Y519768D01*
G01X275524Y517457D02*
Y519400D01*
G01X275774Y517207D02*
X275524Y517457D01*
G01X275774Y511007D02*
Y517207D01*
G01X275592Y510825D02*
X275774Y511007D01*
G01X275592Y503400D02*
Y510825D01*
G01X275792Y503200D02*
X275592Y503400D01*
G01X275792Y495544D02*
Y503200D01*
G01X273992Y493744D02*
X275792Y495544D01*
G01X269192Y519329D02*
Y527900D01*
G01X268963Y519100D02*
X269192Y519329D01*
G01X268963Y517357D02*
Y519100D01*
G01X269513Y516807D02*
X268963Y517357D01*
G01X269513Y512257D02*
Y516807D01*
G01X268913Y511657D02*
X269513Y512257D01*
G01X268913Y497405D02*
Y511657D01*
G01X269392Y496926D02*
X268913Y497405D01*
G01X269392Y494800D02*
Y496926D01*
G01X272192Y492000D02*
X269392Y494800D01*
G01X272192Y490500D02*
Y492000D01*
G01X274092Y488600D02*
X272192Y490500D01*
G01X288479Y488600D02*
X274092D01*
G01X293605Y483474D02*
X288479Y488600D01*
G01X259192Y519421D02*
Y527600D01*
G01X259313Y519300D02*
X259192Y519421D01*
G01X259313Y517357D02*
Y519300D01*
G01X258913Y516957D02*
X259313Y517357D01*
G01X258913Y512057D02*
Y516957D01*
G01X259713Y511257D02*
X258913Y512057D01*
G01X259713Y495221D02*
Y511257D01*
G01X259092Y494600D02*
X259713Y495221D01*
G01X259092Y488900D02*
Y494600D01*
G01X266992Y481000D02*
X259092Y488900D01*
G01X284192Y481000D02*
X266992D01*
G01X301592Y463600D02*
X284192Y481000D01*
G01X245792Y518979D02*
Y528400D01*
G01X245313Y518500D02*
X245792Y518979D01*
G01X245313Y487679D02*
Y518500D01*
G01X262492Y470500D02*
X245313Y487679D01*
G01X263350Y470500D02*
X262492D01*
G01X263960Y469890D02*
X263350Y470500D01*
G01X263960Y468693D02*
Y469890D01*
G01X264570Y468083D02*
X263960Y468693D01*
G01X266550Y468083D02*
X264570D01*
G01X267160Y468693D02*
X266550Y468083D01*
G01X267160Y470518D02*
Y468693D01*
G01X267770Y471128D02*
X267160Y470518D01*
G01X269750Y471128D02*
X267770D01*
G01X270360Y470518D02*
X269750Y471128D01*
G01X270360Y468693D02*
Y470518D01*
G01X270970Y468083D02*
X270360Y468693D01*
G01X272950Y468083D02*
X270970D01*
G01X273560Y468693D02*
X272950Y468083D01*
G01X273560Y469890D02*
Y468693D01*
G01X274170Y470500D02*
X273560Y469890D01*
G01X275792Y470500D02*
X274170D01*
G01X276847Y469445D02*
X275792Y470500D01*
G01X276847Y468313D02*
Y469445D01*
G01X276729Y468195D02*
X276847Y468313D01*
G01X276729Y467063D02*
Y468195D01*
G01X277860Y465932D02*
X276729Y467063D01*
G01X278992Y465932D02*
X277860D01*
G01X279110Y466050D02*
X278992Y465932D01*
G01X280242Y466050D02*
X279110D01*
G01X281373Y464919D02*
X280242Y466050D01*
G01X239092Y519999D02*
Y527800D01*
G01X238358Y519265D02*
X239092Y519999D01*
G01X238358Y517234D02*
Y519265D01*
G01X238963Y516629D02*
X238358Y517234D01*
G01X238963Y511747D02*
Y516629D01*
G01X238392Y511176D02*
X238963Y511747D01*
G01X238392Y509600D02*
Y511176D01*
G01X239492Y508500D02*
X238392Y509600D01*
G01X239492Y504299D02*
Y508500D01*
G01X237492Y502299D02*
X239492Y504299D01*
G01X237492Y495300D02*
Y502299D01*
G01X238592Y494200D02*
X237492Y495300D01*
G01X238592Y485596D02*
Y494200D01*
G01X239960Y484228D02*
X238592Y485596D01*
G01X240822Y484228D02*
X239960D01*
G01X241158Y484564D02*
X240822Y484228D01*
G01X242020Y484564D02*
X241158D01*
G01X243421Y483163D02*
X242020Y484564D01*
G01X243421Y482301D02*
Y483163D01*
G01X243085Y481965D02*
X243421Y482301D01*
G01X243085Y481103D02*
Y481965D01*
G01X244486Y479702D02*
X243085Y481103D01*
G01X245348Y479702D02*
X244486D01*
G01X245684Y480038D02*
X245348Y479702D01*
G01X246546Y480038D02*
X245684D01*
G01X247947Y478637D02*
X246546Y480038D01*
G01X247947Y477775D02*
Y478637D01*
G01X247611Y477439D02*
X247947Y477775D01*
G01X247611Y476577D02*
Y477439D01*
G01X249012Y475176D02*
X247611Y476577D01*
G01X249874Y475176D02*
X249012D01*
G01X250210Y475512D02*
X249874Y475176D01*
G01X251072Y475512D02*
X250210D01*
G01X252473Y474111D02*
X251072Y475512D01*
G01X252473Y473249D02*
Y474111D01*
G01X252137Y472913D02*
X252473Y473249D01*
G01X252137Y472051D02*
Y472913D01*
G01X253538Y470650D02*
X252137Y472051D01*
G01X254400Y470650D02*
X253538D01*
G01X254736Y470986D02*
X254400Y470650D01*
G01X255598Y470986D02*
X254736D01*
G01X256999Y469585D02*
X255598Y470986D01*
G01X256999Y468723D02*
Y469585D01*
G01X256663Y468387D02*
X256999Y468723D01*
G01X256663Y467525D02*
Y468387D01*
G01X258064Y466124D02*
X256663Y467525D01*
G01X258926Y466124D02*
X258064D01*
G01X259262Y466460D02*
X258926Y466124D01*
G01X260124Y466460D02*
X259262D01*
G01X242631Y517539D02*
Y529449D01*
G01X241463Y516371D02*
X242631Y517539D01*
G01X241463Y512129D02*
Y516371D01*
G01X242505Y511087D02*
X241463Y512129D01*
G01X242505Y509113D02*
Y511087D01*
G01X241292Y507900D02*
X242505Y509113D01*
G01X241292Y490201D02*
Y507900D01*
G01X242813Y488680D02*
X241292Y490201D01*
G01X242813Y486580D02*
Y488680D01*
G01X263432Y465961D02*
X242813Y486580D01*
G01X274131Y465961D02*
X263432D01*
G01X265892Y519671D02*
Y527800D01*
G01X266463Y519100D02*
X265892Y519671D01*
G01X266463Y517907D02*
Y519100D01*
G01X265613Y517057D02*
X266463Y517907D01*
G01X265613Y511657D02*
Y517057D01*
G01X266113Y511157D02*
X265613Y511657D01*
G01X266113Y495321D02*
Y511157D01*
G01X265892Y495100D02*
X266113Y495321D01*
G01X265892Y489801D02*
Y495100D01*
G01X269693Y486000D02*
X265892Y489801D01*
G01X288406Y486000D02*
X269693D01*
G01X313192Y461214D02*
X288406Y486000D01*
G01X232392Y519440D02*
Y527700D01*
G01X232152Y519200D02*
X232392Y519440D01*
G01X232152Y517357D02*
Y519200D01*
G01X232702Y516807D02*
X232152Y517357D01*
G01X232702Y512257D02*
Y516807D01*
G01X232102Y511657D02*
X232702Y512257D01*
G01X232102Y509190D02*
Y511657D01*
G01X232492Y508800D02*
X232102Y509190D01*
G01X232492Y501100D02*
Y508800D01*
G01X231492Y500100D02*
X232492Y501100D01*
G01X231492Y484300D02*
Y500100D01*
G01X235963Y586457D02*
X232813Y589607D01*
G01X235963Y584171D02*
Y586457D01*
G01X235692Y583900D02*
X235963Y584171D01*
G01X235692Y575999D02*
Y583900D01*
G01X235963Y575728D02*
X235692Y575999D01*
G01X235963Y573942D02*
Y575728D01*
G01X234965Y572944D02*
X235963Y573942D01*
G01X234965Y568227D02*
Y572944D01*
G01X236013Y567179D02*
X234965Y568227D01*
G01X236013Y565721D02*
Y567179D01*
G01X235692Y565400D02*
X236013Y565721D01*
G01X235692Y557901D02*
Y565400D01*
G01X236468Y557125D02*
X235692Y557901D01*
G01X236468Y555576D02*
Y557125D01*
G01X235113Y554221D02*
X236468Y555576D01*
G01X235113Y549557D02*
Y554221D01*
G01X236113Y548557D02*
X235113Y549557D01*
G01X236113Y547021D02*
Y548557D01*
G01X235692Y546600D02*
X236113Y547021D01*
G01X235692Y538221D02*
Y546600D01*
G01X236113Y537800D02*
X235692Y538221D01*
G01X236113Y536242D02*
Y537800D01*
G01X235113Y535242D02*
X236113Y536242D01*
G01X235113Y530378D02*
Y535242D01*
G01X236275Y529216D02*
X235113Y530378D01*
G01X236275Y528483D02*
Y529216D01*
G01X235692Y527900D02*
X236275Y528483D01*
G01X262170Y587368D02*
X260824Y588714D01*
G01X262213Y587368D02*
X262170D01*
G01X262213Y584779D02*
Y587368D01*
G01X262492Y584500D02*
X262213Y584779D01*
G01X262492Y575879D02*
Y584500D01*
G01X262213Y575600D02*
X262492Y575879D01*
G01X262213Y574079D02*
Y575600D01*
G01X262879Y573413D02*
X262213Y574079D01*
G01X262879Y568163D02*
Y573413D01*
G01X262313Y567597D02*
X262879Y568163D01*
G01X262313Y565979D02*
Y567597D01*
G01X262492Y565800D02*
X262313Y565979D01*
G01X262492Y557879D02*
Y565800D01*
G01X262013Y557400D02*
X262492Y557879D01*
G01X262013Y555457D02*
Y557400D01*
G01X263113Y554357D02*
X262013Y555457D01*
G01X263113Y549957D02*
Y554357D01*
G01X262213Y549057D02*
X263113Y549957D01*
G01X262213Y546679D02*
Y549057D01*
G01X262492Y546400D02*
X262213Y546679D01*
G01X262492Y537979D02*
Y546400D01*
G01X262213Y537700D02*
X262492Y537979D01*
G01X262213Y536278D02*
Y537700D01*
G01X263013Y535478D02*
X262213Y536278D01*
G01X263013Y530542D02*
Y535478D01*
G01X262313Y529842D02*
X263013Y530542D01*
G01X262313Y527879D02*
Y529842D01*
G01X262492Y527700D02*
X262313Y527879D01*
G01X280203Y550564D02*
Y550914D01*
G01X282124Y548643D02*
X280203Y550564D01*
G01X282124Y546768D02*
Y548643D01*
G01X282592Y546300D02*
X282124Y546768D01*
G01X282592Y538168D02*
Y546300D01*
G01X282124Y537700D02*
X282592Y538168D01*
G01X282124Y528268D02*
Y537700D01*
G01X282592Y527800D02*
X282124Y528268D01*
G01X276124Y554524D02*
X277557Y555957D01*
G01X276124Y552007D02*
Y554524D01*
G01X279474Y548657D02*
X276124Y552007D01*
G01X279474Y546782D02*
Y548657D01*
G01X279192Y546500D02*
X279474Y546782D01*
G01X279192Y537982D02*
Y546500D01*
G01X279474Y537700D02*
X279192Y537982D01*
G01X279474Y536383D02*
Y537700D01*
G01X278324Y535233D02*
X279474Y536383D01*
G01X278324Y530567D02*
Y535233D01*
G01X279424Y529467D02*
X278324Y530567D01*
G01X279424Y528132D02*
Y529467D01*
G01X279192Y527900D02*
X279424Y528132D01*
G01X272774Y546782D02*
Y548657D01*
G01X272592Y546600D02*
X272774Y546782D01*
G01X272592Y538182D02*
Y546600D01*
G01X272774Y538000D02*
X272592Y538182D01*
G01X272774Y536142D02*
Y538000D01*
G01X271776Y535144D02*
X272774Y536142D01*
G01X271776Y530517D02*
Y535144D01*
G01X272824Y529469D02*
X271776Y530517D01*
G01X272824Y527932D02*
Y529469D01*
G01X272592Y527700D02*
X272824Y527932D01*
G01X275424Y549400D02*
X273910Y550914D01*
G01X275424Y546368D02*
Y549400D01*
G01X275892Y545900D02*
X275424Y546368D01*
G01X275892Y537968D02*
Y545900D01*
G01X275424Y537500D02*
X275892Y537968D01*
G01X275424Y535456D02*
Y537500D01*
G01X276024Y534856D02*
X275424Y535456D01*
G01X276024Y530697D02*
Y534856D01*
G01X275524Y530197D02*
X276024Y530697D01*
G01X275524Y528268D02*
Y530197D01*
G01X275892Y527900D02*
X275524Y528268D01*
G01X268813Y587470D02*
X267517Y588766D01*
G01X268813Y584079D02*
Y587470D01*
G01X269192Y583700D02*
X268813Y584079D01*
G01X269192Y575679D02*
Y583700D01*
G01X268813Y575300D02*
X269192Y575679D01*
G01X268813Y574178D02*
Y575300D01*
G01X269813Y573178D02*
X268813Y574178D01*
G01X269813Y568497D02*
Y573178D01*
G01X268963Y567647D02*
X269813Y568497D01*
G01X268963Y555500D02*
Y567647D01*
G01X268913Y546479D02*
Y549200D01*
G01X269192Y546200D02*
X268913Y546479D01*
G01X269192Y537879D02*
Y546200D01*
G01X268913Y537600D02*
X269192Y537879D01*
G01X268913Y536278D02*
Y537600D01*
G01X269613Y535578D02*
X268913Y536278D01*
G01X269613Y530466D02*
Y535578D01*
G01X268963Y529816D02*
X269613Y530466D01*
G01X268963Y528129D02*
Y529816D01*
G01X269192Y527900D02*
X268963Y528129D01*
G01X259713Y586379D02*
X256792Y589300D01*
G01X259713Y584921D02*
Y586379D01*
G01X259192Y584400D02*
X259713Y584921D01*
G01X259192Y576021D02*
Y584400D01*
G01X259713Y575500D02*
X259192Y576021D01*
G01X259713Y574242D02*
Y575500D01*
G01X258440Y572969D02*
X259713Y574242D01*
G01X258440Y568470D02*
Y572969D01*
G01X259513Y567397D02*
X258440Y568470D01*
G01X259513Y566121D02*
Y567397D01*
G01X259192Y565800D02*
X259513Y566121D01*
G01X259192Y557721D02*
Y565800D01*
G01X259513Y557400D02*
X259192Y557721D01*
G01X259513Y555357D02*
Y557400D01*
G01X258913Y554757D02*
X259513Y555357D01*
G01X258913Y549857D02*
Y554757D01*
G01X259713Y549057D02*
X258913Y549857D01*
G01X259713Y546521D02*
Y549057D01*
G01X259146Y545954D02*
X259713Y546521D01*
G01X259146Y538747D02*
Y545954D01*
G01X259713Y538180D02*
X259146Y538747D01*
G01X259713Y536522D02*
Y538180D01*
G01X258913Y535722D02*
X259713Y536522D01*
G01X258913Y530242D02*
Y535722D01*
G01X259313Y529842D02*
X258913Y530242D01*
G01X259313Y527721D02*
Y529842D01*
G01X259192Y527600D02*
X259313Y527721D01*
G01X245313Y586443D02*
X243392Y588364D01*
G01X245313Y584579D02*
Y586443D01*
G01X245792Y584100D02*
X245313Y584579D01*
G01X245792Y576099D02*
Y584100D01*
G01X245313Y575620D02*
X245792Y576099D01*
G01X245313Y566079D02*
Y575620D01*
G01X245792Y565600D02*
X245313Y566079D01*
G01X245792Y556979D02*
Y565600D01*
G01X245313Y556500D02*
X245792Y556979D01*
G01X245313Y546779D02*
Y556500D01*
G01X245792Y546300D02*
X245313Y546779D01*
G01X245792Y538179D02*
Y546300D01*
G01X245313Y537700D02*
X245792Y538179D01*
G01X245313Y528879D02*
Y537700D01*
G01X245792Y528400D02*
X245313Y528879D01*
G01X238613Y587200D02*
X237099Y588714D01*
G01X238613Y584379D02*
Y587200D01*
G01X239092Y583900D02*
X238613Y584379D01*
G01X239092Y576199D02*
Y583900D01*
G01X238292Y575399D02*
X239092Y576199D01*
G01X238292Y574001D02*
Y575399D01*
G01X239213Y573080D02*
X238292Y574001D01*
G01X239213Y568421D02*
Y573080D01*
G01X237992Y567200D02*
X239213Y568421D01*
G01X237992Y565300D02*
Y567200D01*
G01X239092Y564200D02*
X237992Y565300D01*
G01X239092Y557999D02*
Y564200D01*
G01X238292Y557199D02*
X239092Y557999D01*
G01X238292Y555678D02*
Y557199D01*
G01X238963Y555007D02*
X238292Y555678D01*
G01X238963Y549871D02*
Y555007D01*
G01X238092Y549000D02*
X238963Y549871D01*
G01X238092Y547100D02*
Y549000D01*
G01X239092Y546100D02*
X238092Y547100D01*
G01X239092Y537879D02*
Y546100D01*
G01X238392Y537179D02*
X239092Y537879D01*
G01X238392Y535763D02*
Y537179D01*
G01X238963Y535192D02*
X238392Y535763D01*
G01X238963Y530242D02*
Y535192D01*
G01X238713Y529992D02*
X238963Y530242D01*
G01X238713Y528179D02*
Y529992D01*
G01X239092Y527800D02*
X238713Y528179D01*
G01X242392Y586728D02*
X239711Y589409D01*
G01X242392Y575971D02*
Y586728D01*
G01X242561Y575802D02*
X242392Y575971D01*
G01X242561Y574169D02*
Y575802D01*
G01X241513Y573121D02*
X242561Y574169D01*
G01X241513Y568367D02*
Y573121D01*
G01X242613Y567267D02*
X241513Y568367D01*
G01X242613Y555257D02*
Y567267D01*
G01X241463Y554107D02*
X242613Y555257D01*
G01X241463Y549857D02*
Y554107D01*
G01X242588Y548732D02*
X241463Y549857D01*
G01X242588Y536395D02*
Y548732D01*
G01X241463Y535270D02*
X242588Y536395D01*
G01X241463Y530617D02*
Y535270D01*
G01X242631Y529449D02*
X241463Y530617D01*
G01X266213Y586507D02*
X262813Y589907D01*
G01X266213Y584821D02*
Y586507D01*
G01X265792Y584400D02*
X266213Y584821D01*
G01X265792Y575921D02*
Y584400D01*
G01X266213Y575500D02*
X265792Y575921D01*
G01X266213Y574042D02*
Y575500D01*
G01X265313Y573142D02*
X266213Y574042D01*
G01X265313Y568397D02*
Y573142D01*
G01X266413Y567297D02*
X265313Y568397D01*
G01X266413Y566221D02*
Y567297D01*
G01X265892Y565700D02*
X266413Y566221D01*
G01X265892Y557421D02*
Y565700D01*
G01X266413Y556900D02*
X265892Y557421D01*
G01X266413Y555657D02*
Y556900D01*
G01X265613Y554857D02*
X266413Y555657D01*
G01X265613Y549457D02*
Y554857D01*
G01X266113Y548957D02*
X265613Y549457D01*
G01X266113Y546621D02*
Y548957D01*
G01X265792Y546300D02*
X266113Y546621D01*
G01X265792Y538121D02*
Y546300D01*
G01X266113Y537800D02*
X265792Y538121D01*
G01X266113Y536422D02*
Y537800D01*
G01X265513Y535822D02*
X266113Y536422D01*
G01X265513Y530366D02*
Y535822D01*
G01X266419Y529460D02*
X265513Y530366D01*
G01X266419Y528327D02*
Y529460D01*
G01X265892Y527800D02*
X266419Y528327D01*
G01X232002Y584790D02*
Y587470D01*
G01X232392Y584400D02*
X232002Y584790D01*
G01X232392Y575790D02*
Y584400D01*
G01X232002Y575400D02*
X232392Y575790D01*
G01X232002Y574190D02*
Y575400D01*
G01X233002Y573190D02*
X232002Y574190D01*
G01X233002Y568497D02*
Y573190D01*
G01X232152Y567647D02*
X233002Y568497D01*
G01X232152Y565740D02*
Y567647D01*
G01X232392Y565500D02*
X232152Y565740D01*
G01X232392Y557140D02*
Y565500D01*
G01X232152Y556900D02*
X232392Y557140D01*
G01X232152Y555157D02*
Y556900D01*
G01X232702Y554607D02*
X232152Y555157D01*
G01X232702Y550057D02*
Y554607D01*
G01X232102Y549457D02*
X232702Y550057D01*
G01X232102Y546590D02*
Y549457D01*
G01X232392Y546300D02*
X232102Y546590D01*
G01X232392Y544400D02*
Y546300D01*
G01X231592Y543600D02*
X232392Y544400D01*
G01X231592Y541300D02*
Y543600D01*
G01X232392Y540500D02*
X231592Y541300D01*
G01X232392Y537790D02*
Y540500D01*
G01X232102Y537500D02*
X232392Y537790D01*
G01X232102Y536190D02*
Y537500D01*
G01X232802Y535490D02*
X232102Y536190D01*
G01X232802Y530466D02*
Y535490D01*
G01X232152Y529816D02*
X232802Y530466D01*
G01X232152Y527940D02*
Y529816D01*
G01X232392Y527700D02*
X232152Y527940D01*
G01X232813Y592517D02*
X234053Y593757D01*
G01X232813Y589607D02*
Y592517D01*
G01X232348Y605635D02*
X237013Y610300D01*
G01X232348Y595462D02*
Y605635D01*
G01X234053Y593757D02*
X232348Y595462D01*
G01X275852D02*
X277557Y593757D01*
G01X275852Y605949D02*
Y595462D01*
G01X280203Y610300D02*
X275852Y605949D01*
G01X258550Y604499D02*
X257478D01*
G01X259250Y603799D02*
X258550Y604499D01*
G01X259250Y602525D02*
Y603799D01*
G01X258113Y601388D02*
X259250Y602525D01*
G01X258113Y600312D02*
Y601388D01*
G01X259125Y599300D02*
X258113Y600312D01*
G01X259125Y598100D02*
Y599300D01*
G01X258113Y597088D02*
X259125Y598100D01*
G01X258113Y596012D02*
Y597088D01*
G01X259225Y594900D02*
X258113Y596012D01*
G01X259225Y592267D02*
Y594900D01*
G01X259050Y592092D02*
X259225Y592267D01*
G01X259050Y590400D02*
Y592092D01*
G01X260736Y588714D02*
X259050Y590400D01*
G01X260824Y588714D02*
X260736D01*
G01X269159Y595462D02*
X270864Y593757D01*
G01X269159Y605635D02*
Y595462D01*
G01X273824Y610300D02*
X269159Y605635D01*
G01X267517Y588766D02*
Y588714D01*
G01X265243Y604499D02*
X264171D01*
G01X265943Y603799D02*
X265243Y604499D01*
G01X265943Y602525D02*
Y603799D01*
G01X264806Y601388D02*
X265943Y602525D01*
G01X264806Y600312D02*
Y601388D01*
G01X265818Y599300D02*
X264806Y600312D01*
G01X265818Y598100D02*
Y599300D01*
G01X264806Y597088D02*
X265818Y598100D01*
G01X264806Y596012D02*
Y597088D01*
G01X265918Y594900D02*
X264806Y596012D01*
G01X265918Y592267D02*
Y594900D01*
G01X265743Y592092D02*
X265918Y592267D01*
G01X265743Y590400D02*
Y592092D01*
G01X267429Y588714D02*
X265743Y590400D01*
G01X267517Y588714D02*
X267429D01*
G01X256792Y593071D02*
X257478Y593757D01*
G01X256792Y589300D02*
Y593071D01*
G01X255773Y605649D02*
X260824Y610700D01*
G01X255773Y595462D02*
Y605649D01*
G01X257478Y593757D02*
X255773Y595462D01*
G01X243392Y588364D02*
Y588714D01*
G01X241726Y604499D02*
X240746D01*
G01X242325Y603900D02*
X241726Y604499D01*
G01X242325Y602700D02*
Y603900D01*
G01X241381Y601756D02*
X242325Y602700D01*
G01X241381Y600544D02*
Y601756D01*
G01X242225Y599700D02*
X241381Y600544D01*
G01X242225Y598000D02*
Y599700D01*
G01X241381Y597156D02*
X242225Y598000D01*
G01X241381Y595736D02*
Y597156D01*
G01X242525Y594592D02*
X241381Y595736D01*
G01X242525Y592999D02*
Y594592D01*
G01X241618Y592092D02*
X242525Y592999D01*
G01X241618Y590400D02*
Y592092D01*
G01X243304Y588714D02*
X241618Y590400D01*
G01X243392Y588714D02*
X243304D01*
G01X292584Y595462D02*
X294289Y593757D01*
G01X292584Y605649D02*
Y595462D01*
G01X297635Y610700D02*
X292584Y605649D01*
G01X273822Y588714D02*
X273910D01*
G01X272136Y590400D02*
X273822Y588714D01*
G01X272136Y592600D02*
Y590400D01*
G01X272636Y593100D02*
X272136Y592600D01*
G01X272636Y594999D02*
Y593100D01*
G01X271499Y596136D02*
X272636Y594999D01*
G01X271499Y597464D02*
Y596136D01*
G01X272436Y598401D02*
X271499Y597464D01*
G01X272436Y599799D02*
Y598401D01*
G01X271499Y600736D02*
X272436Y599799D01*
G01X271499Y601964D02*
Y600736D01*
G01X272536Y603001D02*
X271499Y601964D01*
G01X272536Y603899D02*
Y603001D01*
G01X271936Y604499D02*
X272536Y603899D01*
G01X270864Y604499D02*
X271936D01*
G01X235125D02*
X234053D01*
G01X235725Y603899D02*
X235125Y604499D01*
G01X235725Y603001D02*
Y603899D01*
G01X234688Y601964D02*
X235725Y603001D01*
G01X234688Y600736D02*
Y601964D01*
G01X235625Y599799D02*
X234688Y600736D01*
G01X235625Y598401D02*
Y599799D01*
G01X234688Y597464D02*
X235625Y598401D01*
G01X234688Y596136D02*
Y597464D01*
G01X235825Y594999D02*
X234688Y596136D01*
G01X235825Y593100D02*
Y594999D01*
G01X235325Y592600D02*
X235825Y593100D01*
G01X235325Y590400D02*
Y592600D01*
G01X237011Y588714D02*
X235325Y590400D01*
G01X237099Y588714D02*
X237011D01*
G01X239711Y592722D02*
X240746Y593757D01*
G01X239711Y589409D02*
Y592722D01*
G01X239041Y605949D02*
X243392Y610300D01*
G01X239041Y595462D02*
Y605949D01*
G01X240746Y593757D02*
X239041Y595462D01*
G01X278429Y590488D02*
X280203Y588714D01*
G01X278429Y592092D02*
Y590488D01*
G01X279336Y592999D02*
X278429Y592092D01*
G01X279336Y594592D02*
Y592999D01*
G01X278192Y595736D02*
X279336Y594592D01*
G01X278192Y597156D02*
Y595736D01*
G01X279036Y598000D02*
X278192Y597156D01*
G01X279036Y599700D02*
Y598000D01*
G01X278192Y600544D02*
X279036Y599700D01*
G01X278192Y601756D02*
Y600544D01*
G01X279136Y602700D02*
X278192Y601756D01*
G01X279136Y603900D02*
Y602700D01*
G01X278537Y604499D02*
X279136Y603900D01*
G01X277557Y604499D02*
X278537D01*
G01X262466Y605649D02*
X267517Y610700D01*
G01X262466Y595462D02*
Y605649D01*
G01X264171Y593757D02*
X262466Y595462D01*
G01X262813Y592399D02*
X264171Y593757D01*
G01X262813Y589907D02*
Y592399D01*
G01X295536Y29146D02*
X294289Y27899D01*
G01X295536Y30400D02*
Y29146D01*
G01X296836Y31700D02*
X295536Y30400D01*
G01X297836Y31700D02*
X296836D01*
G01X299636Y33500D02*
X297836Y31700D01*
G01X302729Y-2101D02*
X304328Y-3700D01*
G01X302729Y10706D02*
Y-2101D01*
G01X299736Y13699D02*
X302729Y10706D01*
G01X299736Y15911D02*
Y13699D01*
G01X300982Y17157D02*
X299736Y15911D01*
G01X328384Y30730D02*
Y34140D01*
G01X331100Y28014D02*
X328384Y30730D01*
G01X352892Y29900D02*
X356638Y33646D01*
G01X352892Y15968D02*
Y29900D01*
G01X350543Y13619D02*
X352892Y15968D01*
G01X346911Y13619D02*
X350543D01*
G01X345792Y12500D02*
X346911Y13619D01*
G01X337832Y12500D02*
X345792D01*
G01X334446Y9114D02*
X337832Y12500D01*
G01X334446Y6194D02*
Y9114D01*
G01X335056Y5584D02*
X334446Y6194D01*
G01X337290Y5584D02*
X335056D01*
G01X337900Y4974D02*
X337290Y5584D01*
G01X337900Y3074D02*
Y4974D01*
G01X337290Y2464D02*
X337900Y3074D01*
G01X335056Y2464D02*
X337290D01*
G01X334446Y1854D02*
X335056Y2464D01*
G01X334446Y-1742D02*
Y1854D01*
G01X334447Y-1743D02*
X334446Y-1742D01*
G01X302229Y-8654D02*
X300982Y-9901D01*
G01X302229Y-7400D02*
Y-8654D01*
G01X303529Y-6100D02*
X302229Y-7400D01*
G01X304529Y-6100D02*
X303529D01*
G01X306329Y-4300D02*
X304529Y-6100D01*
G01X306329Y-2900D02*
Y-4300D01*
G01X305717Y-2288D02*
X306329Y-2900D01*
G01X305717Y10725D02*
Y-2288D01*
G01X304328Y12114D02*
X305717Y10725D01*
G01X347492Y32900D02*
X349452Y34860D01*
G01X342792Y29120D02*
X346572Y32900D01*
G01X342792Y24708D02*
Y29120D01*
G01X340029Y21945D02*
X342792Y24708D01*
G01X335988Y21945D02*
X340029D01*
G01X331100Y17057D02*
X335988Y21945D01*
G01X329992Y15949D02*
X331100Y17057D01*
G01X329992Y10900D02*
Y15949D01*
G01X329366Y10274D02*
X329992Y10900D01*
G01X329366Y8126D02*
Y10274D01*
G01X329892Y7600D02*
X329366Y8126D01*
G01X329892Y-2300D02*
Y7600D01*
G01X329250Y-2942D02*
X329892Y-2300D01*
G01X329250Y-5589D02*
Y-2942D01*
G01X331100Y-7439D02*
X329250Y-5589D01*
G01X331100Y-9786D02*
Y-7439D01*
G01X336092Y29660D02*
X334446Y28014D01*
G01X336092Y53212D02*
Y29660D01*
G01X349567Y31275D02*
X352892Y34600D01*
G01X349567Y27050D02*
Y31275D01*
G01X342000Y19483D02*
X349567Y27050D01*
G01X336873Y19483D02*
X342000D01*
G01X334447Y17057D02*
X336873Y19483D01*
G01X334447Y15767D02*
Y17057D01*
G01X332330Y13650D02*
X334447Y15767D01*
G01X332330Y11768D02*
Y13650D01*
G01X332811Y11287D02*
X332330Y11768D01*
G01X332811Y8019D02*
Y11287D01*
G01X332592Y7800D02*
X332811Y8019D01*
G01X332592Y-3500D02*
Y7800D01*
G01X334447Y-5355D02*
X332592Y-3500D01*
G01X334447Y-7108D02*
Y-5355D01*
G01X296036Y-2101D02*
X297635Y-3700D01*
G01X296036Y11150D02*
Y-2101D01*
G01X295536Y-8654D02*
X294289Y-9901D01*
G01X295536Y-7400D02*
Y-8654D01*
G01X296836Y-6100D02*
X295536Y-7400D01*
G01X297836Y-6100D02*
X296836D01*
G01X299636Y-4300D02*
X297836Y-6100D01*
G01X299636Y-2900D02*
Y-4300D01*
G01X299024Y-2288D02*
X299636Y-2900D01*
G01X299024Y10725D02*
Y-2288D01*
G01X297635Y12114D02*
X299024Y10725D01*
G01X302229Y29146D02*
X300982Y27899D01*
G01X302229Y30400D02*
Y29146D01*
G01X303529Y31700D02*
X302229Y30400D01*
G01X304529Y31700D02*
X303529D01*
G01X306329Y33500D02*
X304529Y31700D01*
G01X339527Y30735D02*
X342879Y34087D01*
G01X339527Y27235D02*
Y30735D01*
G01X338492Y26200D02*
X339527Y27235D01*
G01X329792Y26200D02*
X338492D01*
G01X328992Y25400D02*
X329792Y26200D01*
G01X328992Y22662D02*
Y25400D01*
G01X326049Y19719D02*
X328992Y22662D01*
G01X326049Y10756D02*
Y19719D01*
G01X324407Y9114D02*
X326049Y10756D01*
G01X324407Y-4536D02*
Y9114D01*
G01X299636Y34900D02*
Y33500D01*
G01X299024Y35512D02*
X299636Y34900D01*
G01X299024Y48525D02*
Y35512D01*
G01X297635Y49914D02*
X299024Y48525D01*
G01X295930Y51619D02*
X297635Y49914D01*
G01X295930Y53321D02*
Y51619D01*
G01X298466Y55857D02*
X295930Y53321D01*
G01X298466Y65859D02*
Y55857D01*
G01X299666Y67059D02*
X298466Y65859D01*
G01X299666Y72159D02*
Y67059D01*
G01X299166Y72659D02*
X299666Y72159D01*
G01X299166Y75274D02*
Y72659D01*
G01X299492Y75600D02*
X299166Y75274D01*
G01X299492Y83600D02*
Y75600D01*
G01X299166Y83926D02*
X299492Y83600D01*
G01X299166Y86074D02*
Y83926D01*
G01X299766Y86674D02*
X299166Y86074D01*
G01X299766Y91012D02*
Y86674D01*
G01X299066Y91712D02*
X299766Y91012D01*
G01X299066Y103653D02*
Y91712D01*
G01X325277Y92215D02*
Y96685D01*
G01X326292Y91200D02*
X325277Y92215D01*
G01X326292Y89000D02*
Y91200D01*
G01X324407Y87115D02*
X326292Y89000D01*
G01X324407Y84599D02*
Y87115D01*
G01Y83513D02*
Y84599D01*
G01X325727Y82193D02*
X324407Y83513D01*
G01X325727Y75077D02*
Y82193D01*
G01X324407Y73757D02*
X325727Y75077D01*
G01X314368Y70776D02*
Y65814D01*
G01X316091Y72499D02*
X314368Y70776D01*
G01X316091Y83501D02*
Y72499D01*
G01X315826Y83766D02*
X316091Y83501D01*
G01X315826Y86034D02*
Y83766D01*
G01X316492Y86700D02*
X315826Y86034D01*
G01X316492Y88400D02*
Y86700D01*
G01X315692Y89200D02*
X316492Y88400D01*
G01X315692Y90800D02*
Y89200D01*
G01X317192Y92300D02*
X315692Y90800D01*
G01X317192Y93616D02*
Y92300D01*
G01X324276Y100700D02*
X317192Y93616D01*
G01X334447Y94369D02*
X336092Y96014D01*
G01X334447Y92757D02*
Y94369D01*
G01X335792Y91412D02*
X334447Y92757D01*
G01X335792Y89000D02*
Y91412D01*
G01X336358Y88434D02*
X335792Y89000D01*
G01X336358Y86466D02*
Y88434D01*
G01X335992Y86100D02*
X336358Y86466D01*
G01X335992Y83800D02*
Y86100D01*
G01X336174Y83618D02*
X335992Y83800D01*
G01X336174Y67542D02*
Y83618D01*
G01X334446Y65814D02*
X336174Y67542D01*
G01X342940Y91348D02*
Y101848D01*
G01X342680Y91088D02*
X342940Y91348D01*
G01X342680Y88912D02*
Y91088D01*
G01X342940Y88652D02*
X342680Y88912D01*
G01X342940Y86348D02*
Y88652D01*
G01X342192Y85600D02*
X342940Y86348D01*
G01X342192Y75400D02*
Y85600D01*
G01X342853Y74739D02*
X342192Y75400D01*
G01X342853Y72761D02*
Y74739D01*
G01X342686Y72594D02*
X342853Y72761D01*
G01X342686Y69806D02*
Y72594D01*
G01X342853Y69639D02*
X342686Y69806D01*
G01X342853Y64520D02*
Y69639D01*
G01X339577Y61244D02*
X342853Y64520D01*
G01X333436Y61244D02*
X339577D01*
G01X331100Y58908D02*
X333436Y61244D01*
G01X331100Y54857D02*
Y58908D01*
G01Y54208D02*
Y54857D01*
G01X329362Y52470D02*
X331100Y54208D01*
G01X329362Y35118D02*
Y52470D01*
G01X328384Y34140D02*
X329362Y35118D01*
G01X324407Y46914D02*
Y35957D01*
G01Y49215D02*
Y46914D01*
G01X326042Y50850D02*
X324407Y49215D01*
G01X326042Y56250D02*
Y50850D01*
G01X326543Y56751D02*
X326042Y56250D01*
G01X326543Y60804D02*
Y56751D01*
G01X329240Y63501D02*
X326543Y60804D01*
G01X338409Y63501D02*
X329240D01*
G01X339513Y64605D02*
X338409Y63501D01*
G01X339513Y66937D02*
Y64605D01*
G01X339892Y67316D02*
X339513Y66937D01*
G01X339892Y72000D02*
Y67316D01*
G01X339407Y72485D02*
X339892Y72000D01*
G01X339407Y75215D02*
Y72485D01*
G01X339892Y75700D02*
X339407Y75215D01*
G01X339892Y85800D02*
Y75700D01*
G01X339292Y86400D02*
X339892Y85800D01*
G01X339292Y88300D02*
Y86400D01*
G01X339892Y88900D02*
X339292Y88300D01*
G01X339892Y90900D02*
Y88900D01*
G01X338992Y91800D02*
X339892Y90900D01*
G01X338992Y93100D02*
Y91800D01*
G01X339492Y93600D02*
X338992Y93100D01*
G01X339492Y101900D02*
Y93600D01*
G01X351692Y49700D02*
X356332Y54340D01*
G01X350692Y49700D02*
X351692D01*
G01X349452Y48460D02*
X350692Y49700D01*
G01X349452Y34860D02*
Y48460D01*
G01X346572Y32900D02*
X347492D01*
G01X334447Y54957D02*
Y54857D01*
G01X336560Y57070D02*
X334447Y54957D01*
G01X346428Y57070D02*
X336560D01*
G01X348692Y59334D02*
X346428Y57070D01*
G01X348692Y63020D02*
Y59334D01*
G01X349553Y63881D02*
X348692Y63020D01*
G01X349553Y69539D02*
Y63881D01*
G01X349192Y69900D02*
X349553Y69539D01*
G01X349192Y72400D02*
Y69900D01*
G01X349446Y72654D02*
X349192Y72400D01*
G01X349446Y83646D02*
Y72654D01*
G01X349292Y83800D02*
X349446Y83646D01*
G01X349292Y85400D02*
Y83800D01*
G01X349692Y85800D02*
X349292Y85400D01*
G01X349692Y88600D02*
Y85800D01*
G01X349292Y89000D02*
X349692Y88600D01*
G01X349292Y91100D02*
Y89000D01*
G01X349692Y91500D02*
X349292Y91100D01*
G01X349692Y93600D02*
Y91500D01*
G01X348975Y94317D02*
X349692Y93600D01*
G01X348975Y101383D02*
Y94317D01*
G01X334447Y54857D02*
X336092Y53212D01*
G01X329992Y91072D02*
Y97300D01*
G01X331100Y89964D02*
X329992Y91072D01*
G01X331100Y87626D02*
Y89964D01*
G01X328822Y85348D02*
X331100Y87626D01*
G01X328822Y81517D02*
Y85348D01*
G01X329388Y80951D02*
X328822Y81517D01*
G01X329388Y72017D02*
Y80951D01*
G01X328778Y71407D02*
X329388Y72017D01*
G01X327224Y71407D02*
X328778D01*
G01X326614Y70797D02*
X327224Y71407D01*
G01X326614Y69407D02*
Y70797D01*
G01X327224Y68797D02*
X326614Y69407D01*
G01X330321Y68797D02*
X327224D01*
G01X331100Y68018D02*
X330321Y68797D01*
G01X331100Y65814D02*
Y68018D01*
G01X334447Y38545D02*
Y35957D01*
G01X333274Y39718D02*
X334447Y38545D01*
G01X333274Y45742D02*
Y39718D01*
G01X334446Y46914D02*
X333274Y45742D01*
G01X331745Y49615D02*
X334446Y46914D01*
G01X331745Y51303D02*
Y49615D01*
G01X332742Y52300D02*
X331745Y51303D01*
G01X332742Y57450D02*
Y52300D01*
G01X334592Y59300D02*
X332742Y57450D01*
G01X341292Y59300D02*
X334592D01*
G01X346106Y64114D02*
X341292Y59300D01*
G01X346106Y69714D02*
Y64114D01*
G01X346492Y70100D02*
X346106Y69714D01*
G01X346492Y72100D02*
Y70100D01*
G01X346192Y72400D02*
X346492Y72100D01*
G01X346192Y83900D02*
Y72400D01*
G01X346292Y84000D02*
X346192Y83900D01*
G01X346292Y85500D02*
Y84000D01*
G01X346033Y85759D02*
X346292Y85500D01*
G01X346033Y88641D02*
Y85759D01*
G01X346292Y88900D02*
X346033Y88641D01*
G01X346292Y91100D02*
Y88900D01*
G01X345992Y91400D02*
X346292Y91100D01*
G01X345992Y93461D02*
Y91400D01*
G01X346531Y94000D02*
X345992Y93461D01*
G01X346531Y119279D02*
Y94000D01*
G01X352892Y37890D02*
X359592Y44590D01*
G01X352892Y34600D02*
Y37890D01*
G01X306329Y34900D02*
Y33500D01*
G01X305717Y35512D02*
X306329Y34900D01*
G01X305717Y48525D02*
Y35512D01*
G01X304328Y49914D02*
X305717Y48525D01*
G01X302492Y51750D02*
X304328Y49914D01*
G01X302492Y53400D02*
Y51750D01*
G01X305875Y56783D02*
X302492Y53400D01*
G01X305875Y65083D02*
Y56783D01*
G01X306166Y65374D02*
X305875Y65083D01*
G01X306166Y72627D02*
Y65374D01*
G01X305566Y73227D02*
X306166Y72627D01*
G01X305566Y75159D02*
Y73227D01*
G01X306266Y75859D02*
X305566Y75159D01*
G01X306266Y90974D02*
Y75859D01*
G01X305566Y91674D02*
X306266Y90974D01*
G01X305566Y103074D02*
Y91674D01*
G01X352425Y91168D02*
Y100434D01*
G01X352935Y90658D02*
X352425Y91168D01*
G01X352935Y88383D02*
Y90658D01*
G01X352634Y88082D02*
X352935Y88383D01*
G01X352634Y86249D02*
Y88082D01*
G01X353144Y85739D02*
X352634Y86249D01*
G01X353144Y83511D02*
Y85739D01*
G01X356692Y79963D02*
X353144Y83511D01*
G01X352892Y69804D02*
X356692Y73604D01*
G01X352892Y59990D02*
Y69804D01*
G01X349572Y56670D02*
X352892Y59990D01*
G01X349572Y52860D02*
Y56670D01*
G01X348812Y52100D02*
X349572Y52860D01*
G01X347092Y52100D02*
X348812D01*
G01X342862Y47870D02*
X347092Y52100D01*
G01X342862Y45000D02*
Y47870D01*
G01X341042Y43180D02*
X342862Y45000D01*
G01X341042Y41460D02*
Y43180D01*
G01X342879Y39623D02*
X341042Y41460D01*
G01X342879Y34087D02*
Y39623D01*
G01X303466Y57441D02*
X300982Y54957D01*
G01X303466Y66059D02*
Y57441D01*
G01X302266Y67259D02*
X303466Y66059D01*
G01X302266Y72475D02*
Y67259D01*
G01X303066Y73275D02*
X302266Y72475D01*
G01X303066Y74626D02*
Y73275D01*
G01X302392Y75300D02*
X303066Y74626D01*
G01X302392Y83326D02*
Y75300D01*
G01X303066Y84000D02*
X302392Y83326D01*
G01X303066Y85774D02*
Y84000D01*
G01X302466Y86374D02*
X303066Y85774D01*
G01X302466Y91374D02*
Y86374D01*
G01X302966Y91874D02*
X302466Y91374D01*
G01X302966Y103426D02*
Y91874D01*
G01X302729Y35699D02*
X304328Y34100D01*
G01X302729Y48506D02*
Y35699D01*
G01X299736Y51499D02*
X302729Y48506D01*
G01X299736Y53711D02*
Y51499D01*
G01X300982Y54957D02*
X299736Y53711D01*
G01X333192Y88647D02*
X334447Y87392D01*
G01X333192Y91000D02*
Y88647D01*
G01X332392Y91800D02*
X333192Y91000D01*
G01X332392Y95736D02*
Y91800D01*
G01X333273Y74931D02*
X334447Y73757D01*
G01X333273Y86218D02*
Y74931D01*
G01X334447Y87392D02*
X333273Y86218D01*
G01X296036Y35699D02*
Y48950D01*
G01X297635Y34100D02*
X296036Y35699D01*
G01X296566Y92174D02*
Y103127D01*
G01X295466Y91074D02*
X296566Y92174D01*
G01X295466Y86774D02*
Y91074D01*
G01X296166Y86074D02*
X295466Y86774D01*
G01X296166Y83974D02*
Y86074D01*
G01X295592Y83400D02*
X296166Y83974D01*
G01X295592Y75374D02*
Y83400D01*
G01X296166Y74800D02*
X295592Y75374D01*
G01X296166Y72875D02*
Y74800D01*
G01X295466Y72175D02*
X296166Y72875D01*
G01X295466Y67109D02*
Y72175D01*
G01X296266Y66309D02*
X295466Y67109D01*
G01X296266Y56934D02*
Y66309D01*
G01X294289Y54957D02*
X296266Y56934D01*
G01X297635Y105084D02*
X299066Y103653D01*
G01X340988Y132957D02*
Y200519D01*
G01X325392Y117361D02*
X340988Y132957D01*
G01X325392Y109750D02*
Y117361D01*
G01X329342Y105800D02*
X325392Y109750D01*
G01X329342Y100750D02*
Y105800D01*
G01X325277Y96685D02*
X329342Y100750D01*
G01X324771Y100700D02*
X324276D01*
G01X327092Y103021D02*
X324771Y100700D01*
G01X346988Y130470D02*
Y199062D01*
G01X334192Y117674D02*
X346988Y130470D01*
G01X334192Y116369D02*
Y117674D01*
G01X334992Y115569D02*
X334192Y116369D01*
G01X339070Y115569D02*
X334992D01*
G01X339868Y114771D02*
X339070Y115569D01*
G01X339868Y112589D02*
Y114771D01*
G01X339066Y111787D02*
X339868Y112589D01*
G01X334992Y111787D02*
X339066D01*
G01X334192Y110987D02*
X334992Y111787D01*
G01X334192Y109480D02*
Y110987D01*
G01X336792Y106880D02*
X334192Y109480D01*
G01X336792Y104900D02*
Y106880D01*
G01X336092Y104200D02*
X336792Y104900D01*
G01X336092Y96014D02*
Y104200D01*
G01X304092Y157957D02*
Y148600D01*
G01X352188Y127766D02*
Y199802D01*
G01X344531Y120109D02*
X352188Y127766D01*
G01X344531Y103439D02*
Y120109D01*
G01X342940Y101848D02*
X344531Y103439D01*
G01X342492Y104900D02*
X339492Y101900D01*
G01X342492Y106301D02*
Y104900D01*
G01X341692Y107101D02*
X342492Y106301D01*
G01X341192Y107101D02*
X341692D01*
G01X340392Y107901D02*
X341192Y107101D01*
G01X340392Y109501D02*
Y107901D01*
G01X341192Y110301D02*
X340392Y109501D01*
G01X341692Y110301D02*
X341192D01*
G01X342492Y111101D02*
X341692Y110301D01*
G01X342492Y120900D02*
Y111101D01*
G01X350188Y128596D02*
X342492Y120900D01*
G01X350188Y199305D02*
Y128596D01*
G01X350218Y102626D02*
X348975Y101383D01*
G01X350218Y112026D02*
Y102626D01*
G01X351142Y112950D02*
X350218Y112026D01*
G01X351142Y114050D02*
Y112950D01*
G01X348686Y116506D02*
X351142Y114050D01*
G01X348686Y117594D02*
Y116506D01*
G01X350118Y119026D02*
X348686Y117594D01*
G01X351250Y119026D02*
X350118D01*
G01X354355Y115921D02*
X351250Y119026D01*
G01X355487Y115921D02*
X354355D01*
G01X353658Y121144D02*
X356618Y118184D01*
G01X353658Y122276D02*
Y121144D01*
G01X356188Y124806D02*
X353658Y122276D01*
G01X342988Y132128D02*
Y199608D01*
G01X329792Y118932D02*
X342988Y132128D01*
G01X329792Y108250D02*
Y118932D01*
G01X331442Y106600D02*
X329792Y108250D01*
G01X331442Y98750D02*
Y106600D01*
G01X329992Y97300D02*
X331442Y98750D01*
G01X354188Y126936D02*
X346531Y119279D01*
G01X354188Y200166D02*
Y126936D01*
G01X298055Y155457D02*
X333218Y190620D01*
G01X298055Y154665D02*
Y155457D01*
G01X301160Y151560D02*
X298055Y154665D01*
G01X301160Y150768D02*
Y151560D01*
G01X300141Y149749D02*
X301160Y150768D01*
G01X299349Y149749D02*
X300141D01*
G01X296244Y152854D02*
X299349Y149749D01*
G01X295452Y152854D02*
X296244D01*
G01X293592Y150994D02*
X295452Y152854D01*
G01X293592Y141636D02*
Y150994D01*
G01X306266Y103774D02*
X305566Y103074D01*
G01X306266Y105596D02*
Y103774D01*
G01X304178Y107684D02*
X306266Y105596D01*
G01X354049Y110655D02*
X355857D01*
G01X353418Y110024D02*
X354049Y110655D01*
G01X353418Y101427D02*
Y110024D01*
G01X352425Y100434D02*
X353418Y101427D01*
G01X300982Y105410D02*
X302966Y103426D01*
G01X300982Y109700D02*
Y105410D01*
G01X334092Y97436D02*
X332392Y95736D01*
G01X334092Y106899D02*
Y97436D01*
G01X332092Y108899D02*
X334092Y106899D01*
G01X332092Y118403D02*
Y108899D01*
G01X344988Y131299D02*
X332092Y118403D01*
G01X344988Y199498D02*
Y131299D01*
G01X295666Y110150D02*
X294889Y110927D01*
G01X295666Y104027D02*
Y110150D01*
G01X296566Y103127D02*
X295666Y104027D01*
G01X335718Y189583D02*
X304092Y157957D01*
G01X335718Y194591D02*
Y189583D01*
G01X305092Y201636D02*
Y190972D01*
G01X306392Y202936D02*
X305092Y201636D01*
G01X307992Y197503D02*
X313889Y203400D01*
G01X307992Y190336D02*
Y197503D01*
G01X330718Y195421D02*
Y191655D01*
G01X300092Y192100D02*
Y189508D01*
G01X299092Y193100D02*
X300092Y192100D01*
G01X299092Y196900D02*
Y193100D01*
G01X301892Y199700D02*
X299092Y196900D01*
G01X301892Y201980D02*
Y199700D01*
G01X304512Y204600D02*
X301892Y201980D01*
G01X333218Y190620D02*
Y194591D01*
G01X310892Y196533D02*
Y189700D01*
G01X316124Y201765D02*
X310892Y196533D01*
G01X328392Y195407D02*
X328368Y195431D01*
G01X328392Y192865D02*
Y195407D01*
G01X342354Y402187D02*
Y475304D01*
G01X342353Y402186D02*
X342354Y402187D01*
G01X342353Y401161D02*
Y402186D01*
G01X351092Y402900D02*
Y478450D01*
G01X351192Y402800D02*
X351092Y402900D01*
G01X346354Y395968D02*
Y476122D01*
G01X348354Y402138D02*
Y476840D01*
G01X349892Y400600D02*
X348354Y402138D01*
G01X349892Y399300D02*
Y400600D01*
G01X348354Y397762D02*
X349892Y399300D01*
G01X348354Y396007D02*
Y397762D01*
G01X344354Y398763D02*
Y475598D01*
G01X341892Y396301D02*
X344354Y398763D01*
G01X353554Y407821D02*
Y485738D01*
G01X304375Y403882D02*
Y409517D01*
G01X304292Y464500D02*
X303527Y465265D01*
G01X304292Y460500D02*
Y464500D01*
G01X305458Y459334D02*
X304292Y460500D01*
G01X306590Y459334D02*
X305458D01*
G01X307708Y460452D02*
X306590Y459334D01*
G01X308840Y460452D02*
X307708D01*
G01X309971Y459321D02*
X308840Y460452D01*
G01X309971Y458189D02*
Y459321D01*
G01X308853Y457071D02*
X309971Y458189D01*
G01X308853Y455939D02*
Y457071D01*
G01X310692Y454100D02*
X308853Y455939D01*
G01X310692Y432100D02*
Y454100D01*
G01X325875Y416917D02*
X310692Y432100D01*
G01X325875Y406172D02*
Y416917D01*
G01X315692Y461387D02*
X310308Y466771D01*
G01X315692Y434300D02*
Y461387D01*
G01X331248Y418744D02*
X315692Y434300D01*
G01X331248Y405851D02*
Y418744D01*
G01X301592Y459400D02*
Y463600D01*
G01X308092Y452900D02*
X301592Y459400D01*
G01X308092Y431100D02*
Y452900D01*
G01X323375Y415817D02*
X308092Y431100D01*
G01X323375Y406172D02*
Y415817D01*
G01X297592Y448700D02*
X293820Y452472D01*
G01X297592Y427100D02*
Y448700D01*
G01X312175Y412517D02*
X297592Y427100D01*
G01X312175Y404426D02*
Y412517D01*
G01X306875Y403882D02*
Y410617D01*
G01X294992Y426100D02*
Y445100D01*
G01X309675Y411417D02*
X294992Y426100D01*
G01X309675Y404426D02*
Y411417D01*
G01X313192Y433200D02*
Y461214D01*
G01X328748Y417644D02*
X313192Y433200D01*
G01X328748Y405699D02*
Y417644D01*
G01X352674Y520208D02*
X356692Y524226D01*
G01X352674Y517284D02*
Y520208D01*
G01X353277Y516681D02*
X352674Y517284D01*
G01X353277Y514513D02*
Y516681D01*
G01X352443Y513679D02*
X353277Y514513D01*
G01X352443Y511088D02*
Y513679D01*
G01X356692Y506839D02*
X352443Y511088D01*
G01X349542Y526108D02*
Y533050D01*
G01X350152Y525498D02*
X349542Y526108D01*
G01X351514Y525498D02*
X350152D01*
G01X352167Y524845D02*
X351514Y525498D01*
G01X352167Y523455D02*
Y524845D01*
G01X351600Y522888D02*
X352167Y523455D01*
G01X350296Y522888D02*
X351600D01*
G01X349692Y522284D02*
X350296Y522888D01*
G01X349692Y516800D02*
Y522284D01*
G01X349292Y516400D02*
X349692Y516800D01*
G01X349292Y514400D02*
Y516400D01*
G01X349792Y513900D02*
X349292Y514400D01*
G01X349792Y511900D02*
Y513900D01*
G01X349061Y511169D02*
X349792Y511900D01*
G01X349061Y509165D02*
Y511169D01*
G01X353668Y504558D02*
X349061Y509165D01*
G01X353668Y495324D02*
Y504558D01*
G01X359554Y489438D02*
X353668Y495324D01*
G01X316292Y524300D02*
X312752Y527840D01*
G01X316292Y520138D02*
Y524300D01*
G01X319540Y516890D02*
X316292Y520138D01*
G01X319540Y513923D02*
Y516890D01*
G01X319216Y513599D02*
X319540Y513923D01*
G01X319216Y511248D02*
Y513599D01*
G01X320598Y509866D02*
X319216Y511248D01*
G01X320598Y500394D02*
Y509866D01*
G01X323822Y497170D02*
X320598Y500394D01*
G01X326922Y497170D02*
X323822D01*
G01X305774Y517357D02*
Y529847D01*
G01X306324Y516807D02*
X305774Y517357D01*
G01X306324Y512257D02*
Y516807D01*
G01X305724Y511657D02*
X306324Y512257D01*
G01X305724Y510468D02*
Y511657D01*
G01X306566Y509626D02*
X305724Y510468D01*
G01X306566Y496874D02*
Y509626D01*
G01X304392Y494700D02*
X306566Y496874D01*
G01X322692Y519500D02*
Y530300D01*
G01X322892Y519300D02*
X322692Y519500D01*
G01X322892Y516900D02*
Y519300D01*
G01X322592Y516600D02*
X322892Y516900D01*
G01X322592Y514300D02*
Y516600D01*
G01X324407Y512485D02*
X322592Y514300D01*
G01X324407Y509999D02*
Y512485D01*
G01Y507921D02*
Y509999D01*
G01X325362Y506966D02*
X324407Y507921D01*
G01X325362Y506104D02*
Y506966D01*
G01X324413Y505155D02*
X325362Y506104D01*
G01X324413Y504276D02*
Y505155D01*
G01X325114Y503575D02*
X324413Y504276D01*
G01X325959Y503575D02*
X325114D01*
G01X326872Y504488D02*
X325959Y503575D01*
G01X327787Y504488D02*
X326872D01*
G01X328892Y503383D02*
X327787Y504488D01*
G01X328892Y488766D02*
Y503383D01*
G01X342354Y475304D02*
X328892Y488766D01*
G01X339521Y519229D02*
Y529871D01*
G01X338992Y518700D02*
X339521Y519229D01*
G01X338992Y517300D02*
Y518700D01*
G01X339892Y516400D02*
X338992Y517300D01*
G01X339892Y514500D02*
Y516400D01*
G01X339292Y513900D02*
X339892Y514500D01*
G01X339292Y511500D02*
Y513900D01*
G01X339692Y511100D02*
X339292Y511500D01*
G01X339692Y508000D02*
Y511100D01*
G01X342392Y505300D02*
X339692Y508000D01*
G01X342392Y496900D02*
Y505300D01*
G01X353554Y485738D02*
X342392Y496900D01*
G01X295006Y476572D02*
X293605Y477973D01*
G01X295006Y475710D02*
Y476572D01*
G01X294475Y475179D02*
X295006Y475710D01*
G01X294475Y474317D02*
Y475179D01*
G01X295876Y472916D02*
X294475Y474317D01*
G01X296738Y472916D02*
X295876D01*
G01X297269Y473447D02*
X296738Y472916D01*
G01X298131Y473447D02*
X297269D01*
G01X299532Y472046D02*
X298131Y473447D01*
G01X299532Y471184D02*
Y472046D01*
G01X299001Y470653D02*
X299532Y471184D01*
G01X299001Y469791D02*
Y470653D01*
G01X300402Y468390D02*
X299001Y469791D01*
G01X301264Y468390D02*
X300402D01*
G01X301795Y468921D02*
X301264Y468390D01*
G01X302657Y468921D02*
X301795D01*
G01X304058Y467520D02*
X302657Y468921D01*
G01X304058Y466658D02*
Y467520D01*
G01X303527Y466127D02*
X304058Y466658D01*
G01X303527Y465265D02*
Y466127D01*
G01X346104Y516888D02*
Y530388D01*
G01X346490Y516502D02*
X346104Y516888D01*
G01X346490Y514398D02*
Y516502D01*
G01X345929Y513837D02*
X346490Y514398D01*
G01X345929Y511663D02*
Y513837D01*
G01X346792Y510800D02*
X345929Y511663D01*
G01X346792Y509400D02*
Y510800D01*
G01X346192Y508800D02*
X346792Y509400D01*
G01X346192Y506803D02*
Y508800D01*
G01X346802Y506193D02*
X346192Y506803D01*
G01X348221Y506193D02*
X346802D01*
G01X348870Y505544D02*
X348221Y506193D01*
G01X348870Y504154D02*
Y505544D01*
G01X348299Y503583D02*
X348870Y504154D01*
G01X346802Y503583D02*
X348299D01*
G01X346192Y502973D02*
X346802Y503583D01*
G01X346192Y499814D02*
Y502973D01*
G01X347018Y498988D02*
X346192Y499814D01*
G01X348266Y498988D02*
X347018D01*
G01X349468Y500190D02*
X348266Y498988D01*
G01X350503Y500190D02*
X349468D01*
G01X351634Y499059D02*
X350503Y500190D01*
G01X351634Y497830D02*
Y499059D01*
G01X350364Y496560D02*
X351634Y497830D01*
G01X350364Y495428D02*
Y496560D01*
G01X357554Y488238D02*
X350364Y495428D01*
G01X295992Y519732D02*
Y527900D01*
G01X296324Y519400D02*
X295992Y519732D01*
G01X296324Y517557D02*
Y519400D01*
G01X295724Y516957D02*
X296324Y517557D01*
G01X295724Y512057D02*
Y516957D01*
G01X296524Y511257D02*
X295724Y512057D01*
G01X296524Y502532D02*
Y511257D01*
G01X296092Y502100D02*
X296524Y502532D01*
G01X296092Y494800D02*
Y502100D01*
G01X294392Y493100D02*
X296092Y494800D01*
G01X294467Y483474D02*
X293605D01*
G01X295911Y484920D02*
X294467Y483474D01*
G01X296774Y484920D02*
X295911D01*
G01X298175Y483519D02*
X296774Y484920D01*
G01X298175Y482658D02*
Y483519D01*
G01X296730Y481211D02*
X298175Y482658D01*
G01X296730Y480349D02*
Y481211D01*
G01X298131Y478948D02*
X296730Y480349D01*
G01X298993Y478948D02*
X298131D01*
G01X300409Y480366D02*
X298993Y478948D01*
G01X301272Y480366D02*
X300409D01*
G01X302673Y478965D02*
X301272Y480366D01*
G01X302673Y478104D02*
Y478965D01*
G01X302481Y477912D02*
X302673Y478104D01*
G01X301256Y476685D02*
X302481Y477912D01*
G01X301256Y475823D02*
Y476685D01*
G01X302657Y474422D02*
X301256Y475823D01*
G01X303519Y474422D02*
X302657D01*
G01X304753Y475658D02*
X303519Y474422D01*
G01X305616Y475658D02*
X304753D01*
G01X307017Y474257D02*
X305616Y475658D01*
G01X307017Y473396D02*
Y474257D01*
G01X305782Y472159D02*
X307017Y473396D01*
G01X305782Y471297D02*
Y472159D01*
G01X307183Y469896D02*
X305782Y471297D01*
G01X308045Y469896D02*
X307183D01*
G01X308832Y470684D02*
X308045Y469896D01*
G01X309694Y470684D02*
X308832D01*
G01X311095Y469283D02*
X309694Y470684D01*
G01X311095Y468396D02*
Y469283D01*
G01X310308Y467609D02*
X311095Y468396D01*
G01X310308Y466771D02*
Y467609D01*
G01X334447Y518157D02*
Y529013D01*
G01X335792Y516812D02*
X334447Y518157D01*
G01X335792Y514400D02*
Y516812D01*
G01X336292Y513900D02*
X335792Y514400D01*
G01X336292Y511600D02*
Y513900D01*
G01X335692Y511000D02*
X336292Y511600D01*
G01X335692Y509500D02*
Y511000D01*
G01X340032Y505160D02*
X335692Y509500D01*
G01X340032Y498834D02*
Y505160D01*
G01X337141Y495943D02*
X340032Y498834D01*
G01X337141Y494655D02*
Y495943D01*
G01X338309Y493487D02*
X337141Y494655D01*
G01X339101Y493487D02*
X338309D01*
G01X340232Y494618D02*
X339101Y493487D01*
G01X341332Y494618D02*
X340232D01*
G01X342463Y493487D02*
X341332Y494618D01*
G01X342463Y492213D02*
Y493487D01*
G01X339582Y489332D02*
X342463Y492213D01*
G01X339582Y488233D02*
Y489332D01*
G01X340713Y487102D02*
X339582Y488233D01*
G01X341878Y487102D02*
X340713D01*
G01X344713Y489937D02*
X341878Y487102D01*
G01X345992Y489937D02*
X344713D01*
G01X347123Y488806D02*
X345992Y489937D01*
G01X347123Y487821D02*
Y488806D01*
G01X343932Y484630D02*
X347123Y487821D01*
G01X343932Y483616D02*
Y484630D01*
G01X345063Y482485D02*
X343932Y483616D01*
G01X346313Y482485D02*
X345063D01*
G01X348811Y484983D02*
X346313Y482485D01*
G01X350060Y484983D02*
X348811D01*
G01X351092Y483951D02*
X350060Y484983D01*
G01X351092Y482395D02*
Y483951D01*
G01X350059Y481362D02*
X351092Y482395D01*
G01X350059Y479483D02*
Y481362D01*
G01X351092Y478450D02*
X350059Y479483D01*
G01X330737Y515727D02*
Y528651D01*
G01X331100Y515364D02*
X330737Y515727D01*
G01X331100Y513108D02*
Y515364D01*
G01X329192Y511200D02*
X331100Y513108D01*
G01X329192Y509500D02*
Y511200D01*
G01X332892Y505800D02*
X329192Y509500D01*
G01X332892Y489584D02*
Y505800D01*
G01X346354Y476122D02*
X332892Y489584D01*
G01X332792Y519400D02*
Y530402D01*
G01X332441Y519049D02*
X332792Y519400D01*
G01X332441Y516951D02*
Y519049D01*
G01X333492Y515900D02*
X332441Y516951D01*
G01X333492Y513747D02*
Y515900D01*
G01X334447Y512792D02*
X333492Y513747D01*
G01X333592Y511937D02*
X334447Y512792D01*
G01X333592Y509300D02*
Y511937D01*
G01X334892Y508000D02*
X333592Y509300D01*
G01X334892Y490302D02*
Y508000D01*
G01X348354Y476840D02*
X334892Y490302D01*
G01X299292Y519568D02*
Y527900D01*
G01X298824Y519100D02*
X299292Y519568D01*
G01X298824Y517657D02*
Y519100D01*
G01X299924Y516557D02*
X298824Y517657D01*
G01X299924Y512157D02*
Y516557D01*
G01X299024Y511257D02*
X299924Y512157D01*
G01X299024Y502532D02*
Y511257D01*
G01X298682Y502190D02*
X299024Y502532D01*
G01X298682Y499910D02*
Y502190D01*
G01X299892Y498700D02*
X298682Y499910D01*
G01X299892Y497001D02*
Y498700D01*
G01X297835Y494944D02*
X299892Y497001D01*
G01X303224Y517857D02*
Y529497D01*
G01X302424Y517057D02*
X303224Y517857D01*
G01X302424Y511657D02*
Y517057D01*
G01X302924Y511157D02*
X302424Y511657D01*
G01X302924Y502133D02*
Y511157D01*
G01X302692Y501901D02*
X302924Y502133D01*
G01X302692Y494900D02*
Y501901D01*
G01X301092Y493300D02*
X302692Y494900D01*
G01X326048Y519456D02*
Y532678D01*
G01X325692Y519100D02*
X326048Y519456D01*
G01X325692Y517100D02*
Y519100D01*
G01X327754Y515038D02*
X325692Y517100D01*
G01X327754Y512792D02*
Y515038D01*
G01X327092Y512130D02*
X327754Y512792D01*
G01X327092Y507617D02*
Y512130D01*
G01X327087Y507605D02*
X327092Y507617D01*
G01X330892Y503800D02*
X327087Y507605D01*
G01X330892Y489060D02*
Y503800D01*
G01X344354Y475598D02*
X330892Y489060D01*
G01X342792Y519600D02*
Y531808D01*
G01X342992Y519400D02*
X342792Y519600D01*
G01X342992Y517000D02*
Y519400D01*
G01X342592Y516600D02*
X342992Y517000D01*
G01X342592Y514400D02*
Y516600D01*
G01X343092Y513900D02*
X342592Y514400D01*
G01X343092Y511700D02*
Y513900D01*
G01X342592Y511200D02*
X343092Y511700D01*
G01X342592Y508800D02*
Y511200D01*
G01X344392Y507000D02*
X342592Y508800D01*
G01X344392Y498300D02*
Y507000D01*
G01X355554Y487138D02*
X344392Y498300D01*
G01X326034Y587434D02*
Y595346D01*
G01X327754Y585714D02*
X326034Y587434D01*
G01X332192Y581276D02*
X327754Y585714D01*
G01X332192Y578000D02*
Y581276D01*
G01X333192Y577000D02*
X332192Y578000D01*
G01X338519Y577000D02*
X333192D01*
G01X339433Y576086D02*
X338519Y577000D01*
G01X339433Y573759D02*
Y576086D01*
G01X343892Y569300D02*
X339433Y573759D01*
G01X344992Y569300D02*
X343892D01*
G01X346104Y568188D02*
X344992Y569300D01*
G01X346104Y560588D02*
Y568188D01*
G01X349541Y557151D02*
X346104Y560588D01*
G01X349541Y554419D02*
Y557151D01*
G01X352891Y551069D02*
X349541Y554419D01*
G01X352891Y544336D02*
Y551069D01*
G01X356154Y541073D02*
X352891Y544336D01*
G01X334447Y566813D02*
X334446Y566814D01*
G01X334447Y555857D02*
Y566813D01*
G01X336294Y554010D02*
X334447Y555857D01*
G01X338719Y554010D02*
X336294D01*
G01X339329Y553400D02*
X338719Y554010D01*
G01X339329Y552295D02*
Y553400D01*
G01X339918Y551706D02*
X339329Y552295D01*
G01X341308Y551706D02*
X339918D01*
G01X341939Y552337D02*
X341308Y551706D01*
G01X341939Y553400D02*
Y552337D01*
G01X342549Y554010D02*
X341939Y553400D01*
G01X345149Y554010D02*
X342549D01*
G01X346191Y552968D02*
X345149Y554010D01*
G01X346191Y544981D02*
Y552968D01*
G01X349454Y541718D02*
X346191Y544981D01*
G01X349454Y533138D02*
Y541718D01*
G01X349542Y533050D02*
X349454Y533138D01*
G01X312752Y535226D02*
X311021Y536957D01*
G01X312752Y527840D02*
Y535226D01*
G01X304328Y550966D02*
Y550914D01*
G01X305624Y549670D02*
X304328Y550966D01*
G01X305624Y536568D02*
Y549670D01*
G01X306266Y535926D02*
X305624Y536568D01*
G01X306266Y530339D02*
Y535926D01*
G01X305774Y529847D02*
X306266Y530339D01*
G01X324407Y534264D02*
Y536957D01*
G01X323392Y533249D02*
X324407Y534264D01*
G01X323392Y531000D02*
Y533249D01*
G01X322692Y530300D02*
X323392Y531000D01*
G01X324407Y569685D02*
Y574757D01*
G01X326034Y568058D02*
X324407Y569685D01*
G01X326034Y564343D02*
Y568058D01*
G01X326845Y563532D02*
X326034Y564343D01*
G01X326845Y558433D02*
Y563532D01*
G01X326034Y557622D02*
X326845Y558433D01*
G01X326034Y554151D02*
Y557622D01*
G01X324407Y552524D02*
X326034Y554151D01*
G01X324407Y547914D02*
Y552524D01*
G01X333021Y539300D02*
X324407Y547914D01*
G01X334566Y539300D02*
X333021D01*
G01X336113Y537753D02*
X334566Y539300D01*
G01X336113Y535421D02*
Y537753D01*
G01X337141Y534393D02*
X336113Y535421D01*
G01X337141Y532251D02*
Y534393D01*
G01X339521Y529871D02*
X337141Y532251D01*
G01X346149Y587043D02*
X344592Y588600D01*
G01X346149Y581929D02*
Y587043D01*
G01X351302Y576776D02*
X346149Y581929D01*
G01X368283Y576776D02*
X351302D01*
G01X332557Y572867D02*
X334447Y574757D01*
G01X332557Y567935D02*
Y572867D01*
G01X332792Y567700D02*
X332557Y567935D01*
G01X332792Y554913D02*
Y567700D01*
G01X332117Y554238D02*
X332792Y554913D01*
G01X332117Y550243D02*
Y554238D01*
G01X334446Y547914D02*
X332117Y550243D01*
G01X342851Y539509D02*
X334446Y547914D01*
G01X342851Y534641D02*
Y539509D01*
G01X345292Y532200D02*
X342851Y534641D01*
G01X345292Y531200D02*
Y532200D01*
G01X346104Y530388D02*
X345292Y531200D01*
G01X293624Y555292D02*
X294289Y555957D01*
G01X293624Y551457D02*
Y555292D01*
G01X296524Y548557D02*
X293624Y551457D01*
G01X296524Y546732D02*
Y548557D01*
G01X295992Y546200D02*
X296524Y546732D01*
G01X295992Y538232D02*
Y546200D01*
G01X296524Y537700D02*
X295992Y538232D01*
G01X296524Y536442D02*
Y537700D01*
G01X295251Y535169D02*
X296524Y536442D01*
G01X295251Y530670D02*
Y535169D01*
G01X296324Y529597D02*
X295251Y530670D01*
G01X296324Y528232D02*
Y529597D01*
G01X295992Y527900D02*
X296324Y528232D01*
G01X347833Y585722D02*
Y590841D01*
G01Y585116D02*
Y585722D01*
G01X351937Y581012D02*
X347833Y585116D01*
G01X366602Y581012D02*
X351937D01*
G01X334447Y529013D02*
X334446Y529014D01*
G01X332792Y587736D02*
X331100Y589428D01*
G01X341622Y587736D02*
X332792D01*
G01X342871Y586487D02*
X341622Y587736D01*
G01X342871Y584156D02*
Y586487D01*
G01X341654Y582939D02*
X342871Y584156D01*
G01X338080Y582939D02*
X341654D01*
G01X337255Y582114D02*
X338080Y582939D01*
G01X337255Y580750D02*
Y582114D01*
G01X338266Y579739D02*
X337255Y580750D01*
G01X342626Y579739D02*
X338266D01*
G01X346133Y576232D02*
X342626Y579739D01*
G01X346133Y573587D02*
Y576232D01*
G01X347920Y571800D02*
X346133Y573587D01*
G01X349301Y571800D02*
X347920D01*
G01X352818Y568283D02*
X349301Y571800D01*
G01X352818Y565959D02*
Y568283D01*
G01X353494Y565283D02*
X352818Y565959D01*
G01X353494Y564421D02*
Y565283D01*
G01X352407Y563334D02*
X353494Y564421D01*
G01X352407Y562472D02*
Y563334D01*
G01X353391Y561488D02*
X352407Y562472D01*
G01X354253Y561488D02*
X353391D01*
G01X355340Y562575D02*
X354253Y561488D01*
G01X330737Y528651D02*
X331100Y529014D01*
G01X354525Y588194D02*
X352803Y589916D01*
G01X354525Y585722D02*
Y588194D01*
G01X357625Y582622D02*
X354525Y585722D01*
G01X332540Y535050D02*
X334447Y536957D01*
G01X332540Y534272D02*
Y535050D01*
G01X331742Y533474D02*
X332540Y534272D01*
G01X329725Y533474D02*
X331742D01*
G01X329115Y532864D02*
X329725Y533474D01*
G01X329115Y531874D02*
Y532864D01*
G01X329725Y531264D02*
X329115Y531874D01*
G01X331930Y531264D02*
X329725D01*
G01X332792Y530402D02*
X331930Y531264D01*
G01X298981Y549568D02*
X297635Y550914D01*
G01X299024Y549568D02*
X298981D01*
G01X299024Y546568D02*
Y549568D01*
G01X299292Y546300D02*
X299024Y546568D01*
G01X299292Y537968D02*
Y546300D01*
G01X299024Y537700D02*
X299292Y537968D01*
G01X299024Y536167D02*
Y537700D01*
G01X299690Y535501D02*
X299024Y536167D01*
G01X299690Y530363D02*
Y535501D01*
G01X299124Y529797D02*
X299690Y530363D01*
G01X299124Y528068D02*
Y529797D01*
G01X299292Y527900D02*
X299124Y528068D01*
G01X299624Y554599D02*
X300982Y555957D01*
G01X299624Y552107D02*
Y554599D01*
G01X303024Y548707D02*
X299624Y552107D01*
G01X303024Y546532D02*
Y548707D01*
G01X302592Y546100D02*
X303024Y546532D01*
G01X302592Y538332D02*
Y546100D01*
G01X303024Y537900D02*
X302592Y538332D01*
G01X303024Y536242D02*
Y537900D01*
G01X302124Y535342D02*
X303024Y536242D01*
G01X302124Y530597D02*
Y535342D01*
G01X303224Y529497D02*
X302124Y530597D01*
G01X327754Y534384D02*
Y536957D01*
G01X326048Y532678D02*
X327754Y534384D01*
G01X331100Y555857D02*
Y566814D01*
G01X329383Y554140D02*
X331100Y555857D01*
G01X329383Y546841D02*
Y554140D01*
G01X332888Y543336D02*
X329383Y546841D01*
G01X334748Y543336D02*
X332888D01*
G01X339418Y538666D02*
X334748Y543336D01*
G01X339418Y535574D02*
Y538666D01*
G01X340392Y534600D02*
X339418Y535574D01*
G01X340392Y534208D02*
Y534600D01*
G01X342792Y531808D02*
X340392Y534208D01*
G01X327754Y610038D02*
Y612457D01*
G01X324015Y606299D02*
X327754Y610038D01*
G01X323661Y606299D02*
X324015D01*
G01X322492Y605130D02*
X323661Y606299D01*
G01X322492Y598888D02*
Y605130D01*
G01X326034Y595346D02*
X322492Y598888D01*
G01X304240Y588714D02*
X304328D01*
G01X302554Y590400D02*
X304240Y588714D01*
G01X302554Y592092D02*
Y590400D01*
G01X302729Y592267D02*
X302554Y592092D01*
G01X302729Y594900D02*
Y592267D01*
G01X301617Y596012D02*
X302729Y594900D01*
G01X301617Y597088D02*
Y596012D01*
G01X302629Y598100D02*
X301617Y597088D01*
G01X302629Y599300D02*
Y598100D01*
G01X301617Y600312D02*
X302629Y599300D01*
G01X301617Y601388D02*
Y600312D01*
G01X302754Y602525D02*
X301617Y601388D01*
G01X302754Y603799D02*
Y602525D01*
G01X302054Y604499D02*
X302754Y603799D01*
G01X300982Y604499D02*
X302054D01*
G01X334447Y593657D02*
Y607292D01*
G01X336283Y591821D02*
X334447Y593657D01*
G01X340371Y591821D02*
X336283D01*
G01X343592Y588600D02*
X340371Y591821D01*
G01X344592Y588600D02*
X343592D01*
G01X347833Y610259D02*
Y612357D01*
G01X349809Y608283D02*
X347833Y610259D01*
G01X349809Y606217D02*
Y608283D01*
G01X348592Y605000D02*
X349809Y606217D01*
G01X348592Y598424D02*
Y605000D01*
G01X346104Y595936D02*
X348592Y598424D01*
G01X346104Y592570D02*
Y595936D01*
G01X347833Y590841D02*
X346104Y592570D01*
G01X331100Y602572D02*
Y604614D01*
G01X330274Y601746D02*
X331100Y602572D01*
G01X328447Y601746D02*
X330274D01*
G01X327662Y600961D02*
X328447Y601746D01*
G01X327662Y598901D02*
Y600961D01*
G01X328322Y598241D02*
X327662Y598901D01*
G01X330552Y598241D02*
X328322D01*
G01X331100Y597693D02*
X330552Y598241D01*
G01X331100Y593657D02*
Y597693D01*
G01Y589428D02*
Y593657D01*
G01X354525Y610067D02*
Y612358D01*
G01X356329Y608263D02*
X354525Y610067D01*
G01X352803Y602711D02*
X356329Y606237D01*
G01X352803Y589916D02*
Y602711D01*
G01X299277Y595462D02*
X300982Y593757D01*
G01X299277Y605649D02*
Y595462D01*
G01X304328Y610700D02*
X299277Y605649D01*
G01X297547Y588714D02*
X297635D01*
G01X295861Y590400D02*
X297547Y588714D01*
G01X295861Y592092D02*
Y590400D01*
G01X296036Y592267D02*
X295861Y592092D01*
G01X296036Y594900D02*
Y592267D01*
G01X294924Y596012D02*
X296036Y594900D01*
G01X294924Y597088D02*
Y596012D01*
G01X295936Y598100D02*
X294924Y597088D01*
G01X295936Y599300D02*
Y598100D01*
G01X294924Y600312D02*
X295936Y599300D01*
G01X294924Y601388D02*
Y600312D01*
G01X296061Y602525D02*
X294924Y601388D01*
G01X296061Y603799D02*
Y602525D01*
G01X295361Y604499D02*
X296061Y603799D01*
G01X294289Y604499D02*
X295361D01*
G01X404723Y-4535D02*
Y9122D01*
G01X404722Y-4536D02*
X404723Y-4535D01*
G01Y11369D02*
Y9122D01*
G01X402692Y13400D02*
X404723Y11369D01*
G01X402692Y15600D02*
Y13400D01*
G01X403088Y15996D02*
X402692Y15600D01*
G01X403088Y19588D02*
Y15996D01*
G01X392542Y30134D02*
X403088Y19588D01*
G01X392542Y36550D02*
Y30134D01*
G01X404723Y9122D02*
X404722Y9121D01*
G01X413062Y26991D02*
X421456Y18597D01*
G01X413062Y29618D02*
Y26991D01*
G01X413068Y29624D02*
X413062Y29618D01*
G01X413068Y31156D02*
Y29624D01*
G01X409808Y34416D02*
X413068Y31156D01*
G01X401377Y5113D02*
Y9122D01*
G01X400767Y4503D02*
X401377Y5113D01*
G01X398545Y4503D02*
X400767D01*
G01X397962Y3920D02*
X398545Y4503D01*
G01X397962Y2020D02*
Y3920D01*
G01X398599Y1383D02*
X397962Y2020D01*
G01X400767Y1383D02*
X398599D01*
G01X401377Y773D02*
X400767Y1383D01*
G01X401377Y-1741D02*
Y773D01*
G01X401375Y-1743D02*
X401377Y-1741D01*
G01Y11790D02*
Y9122D01*
G01X400667Y12500D02*
X401377Y11790D01*
G01X400667Y14125D02*
Y12500D01*
G01X399637Y15155D02*
X400667Y14125D01*
G01X399637Y20025D02*
Y15155D01*
G01X394495Y25167D02*
X399637Y20025D01*
G01X386324Y25167D02*
X394495D01*
G01X382367Y29124D02*
X386324Y25167D01*
G01X382367Y38425D02*
Y29124D01*
G01X401377Y9122D02*
X401376Y9121D01*
G01X416392Y27058D02*
X423128Y20322D01*
G01X416392Y31400D02*
Y27058D01*
G01X413147Y34645D02*
X416392Y31400D01*
G01X406992Y38226D02*
X404723Y35957D01*
G01X406992Y43116D02*
Y38226D01*
G01X404723Y45385D02*
X406992Y43116D01*
G01X404723Y46922D02*
Y45385D01*
G01X404722Y46923D02*
X404723Y46922D01*
G01X404722Y49370D02*
Y46923D01*
G01X401892Y52200D02*
X404722Y49370D01*
G01X401392Y52200D02*
X401892D01*
G01X399661Y53931D02*
X401392Y52200D01*
G01X399661Y58602D02*
Y53931D01*
G01X392792Y65471D02*
X399661Y58602D01*
G01X392792Y74608D02*
Y65471D01*
G01X392052Y75348D02*
X392792Y74608D01*
G01X392052Y76210D02*
Y75348D01*
G01X392608Y76766D02*
X392052Y76210D01*
G01X392608Y77628D02*
Y76766D01*
G01X391624Y78612D02*
X392608Y77628D01*
G01X390762Y78612D02*
X391624D01*
G01X390206Y78056D02*
X390762Y78612D01*
G01X389344Y78056D02*
X390206D01*
G01X388300Y79100D02*
X389344Y78056D01*
G01X384464Y79100D02*
X388300D01*
G01X382692Y80872D02*
X384464Y79100D01*
G01X382692Y114374D02*
Y80872D01*
G01X372423Y89131D02*
Y96025D01*
G01X371792Y88500D02*
X372423Y89131D01*
G01X371792Y80075D02*
Y88500D01*
G01X370892Y79175D02*
X371792Y80075D01*
G01X370892Y75996D02*
Y79175D01*
G01X371792Y75096D02*
X370892Y75996D01*
G01X371792Y52400D02*
Y75096D01*
G01X373592Y50600D02*
X371792Y52400D01*
G01X373592Y46844D02*
Y50600D01*
G01X370548Y43800D02*
X373592Y46844D01*
G01X363991Y43800D02*
X370548D01*
G01X356638Y36447D02*
X363991Y43800D01*
G01X356638Y33646D02*
Y36447D01*
G01X359918Y83926D02*
Y96586D01*
G01X359026Y83034D02*
X359918Y83926D01*
G01X359026Y76020D02*
Y83034D01*
G01X361858Y73188D02*
X359026Y76020D01*
G01X361858Y67066D02*
Y73188D01*
G01X356332Y61540D02*
X361858Y67066D01*
G01X356332Y54340D02*
Y61540D01*
G01X404391Y74089D02*
X404723Y73757D01*
G01X404391Y79455D02*
Y74089D01*
G01X404147Y79699D02*
X404391Y79455D01*
G01X404147Y83155D02*
Y79699D01*
G01X404723Y83731D02*
X404147Y83155D01*
G01X404723Y84598D02*
Y83731D01*
G01X404722Y84599D02*
X404723Y84598D01*
G01X403192Y86129D02*
X404722Y84599D01*
G01X403192Y88800D02*
Y86129D01*
G01X402892Y89100D02*
X403192Y88800D01*
G01X402892Y91300D02*
Y89100D01*
G01X403192Y91600D02*
X402892Y91300D01*
G01X403192Y93500D02*
Y91600D01*
G01X402392Y94300D02*
X403192Y93500D01*
G01X402392Y98456D02*
Y94300D01*
G01X401375Y73759D02*
X401377Y73757D01*
G01X401375Y87392D02*
Y73759D01*
G01X400292Y88475D02*
X401375Y87392D01*
G01X400292Y91100D02*
Y88475D01*
G01X395692Y95700D02*
X400292Y91100D01*
G01X390888Y38204D02*
X392542Y36550D01*
G01X390888Y39066D02*
Y38204D01*
G01X392756Y40934D02*
X390888Y39066D01*
G01X392756Y41642D02*
Y40934D01*
G01X391284Y43114D02*
X392756Y41642D01*
G01X390522Y43114D02*
X391284D01*
G01X388681Y41273D02*
X390522Y43114D01*
G01X387819Y41273D02*
X388681D01*
G01X383692Y45400D02*
X387819Y41273D01*
G01X383692Y50250D02*
Y45400D01*
G01X378892Y55050D02*
X383692Y50250D01*
G01X378892Y71900D02*
Y55050D01*
G01X378092Y72700D02*
X378892Y71900D01*
G01X378092Y84500D02*
Y72700D01*
G01X377392Y85200D02*
X378092Y84500D01*
G01X377392Y98028D02*
Y85200D01*
G01X409808Y49371D02*
Y34416D01*
G01X410071Y49634D02*
X409808Y49371D01*
G01X410071Y52448D02*
Y49634D01*
G01X409689Y52830D02*
X410071Y52448D01*
G01X409689Y56155D02*
Y52830D01*
G01X406349Y59495D02*
X409689Y56155D01*
G01X406349Y69757D02*
Y59495D01*
G01X406357Y69765D02*
X406349Y69757D01*
G01X406357Y74765D02*
Y69765D01*
G01X407292Y75700D02*
X406357Y74765D01*
G01X407292Y85400D02*
Y75700D01*
G01X406192Y86500D02*
X407292Y85400D01*
G01X406192Y88334D02*
Y86500D01*
G01X410192Y92334D02*
X406192Y88334D01*
G01X410192Y106284D02*
Y92334D01*
G01X398676Y38658D02*
X401377Y35957D01*
G01X398676Y44221D02*
Y38658D01*
G01X401377Y46922D02*
X398676Y44221D01*
G01X401375Y46924D02*
X401377Y46922D01*
G01X401375Y49592D02*
Y46924D01*
G01X400667Y50300D02*
X401375Y49592D01*
G01X396392Y50300D02*
X400667D01*
G01X392692Y54000D02*
X396392Y50300D01*
G01X392692Y57800D02*
Y54000D01*
G01X389692Y60800D02*
X392692Y57800D01*
G01X386378Y60800D02*
X389692D01*
G01X382292Y64886D02*
X386378Y60800D01*
G01X382292Y73000D02*
Y64886D01*
G01X383592Y74300D02*
X382292Y73000D01*
G01X383592Y75600D02*
Y74300D01*
G01X380592Y78600D02*
X383592Y75600D01*
G01X380592Y113644D02*
Y78600D01*
G01X370567Y93186D02*
X363868Y99893D01*
G01X370567Y89716D02*
Y93186D01*
G01X369792Y88941D02*
X370567Y89716D01*
G01X369792Y81648D02*
Y88941D01*
G01X368892Y80748D02*
X369792Y81648D01*
G01X368892Y75151D02*
Y80748D01*
G01X369792Y74251D02*
X368892Y75151D01*
G01X369792Y54204D02*
Y74251D01*
G01X368688Y53100D02*
X369792Y54204D01*
G01X364848Y53100D02*
X368688D01*
G01X359592Y47844D02*
X364848Y53100D01*
G01X359592Y44590D02*
Y47844D01*
G01X416374Y70018D02*
X419820Y66572D01*
G01X416374Y75948D02*
Y70018D01*
G01X417142Y76716D02*
X416374Y75948D01*
G01X376092Y44700D02*
X382367Y38425D01*
G01X376092Y80218D02*
Y44700D01*
G01X373632Y82678D02*
X376092Y80218D01*
G01X373632Y87682D02*
Y82678D01*
G01X374533Y88583D02*
X373632Y87682D01*
G01X374533Y96744D02*
Y88583D01*
G01X356692Y73604D02*
Y79963D01*
G01X413147Y37763D02*
Y34645D01*
G01X412492Y38418D02*
X413147Y37763D01*
G01X412492Y45400D02*
Y38418D01*
G01X413125Y46033D02*
X412492Y45400D01*
G01X413125Y56440D02*
Y46033D01*
G01X413163Y56478D02*
X413125Y56440D01*
G01X413163Y61129D02*
Y56478D01*
G01X409805Y64487D02*
X413163Y61129D01*
G01X409805Y67667D02*
Y64487D01*
G01X410251Y68113D02*
X409805Y67667D01*
G01X410251Y71215D02*
Y68113D01*
G01X409782Y71684D02*
X410251Y71215D01*
G01X409782Y75010D02*
Y71684D01*
G01X409492Y75300D02*
X409782Y75010D01*
G01X409492Y85338D02*
Y75300D01*
G01X410554Y86400D02*
X409492Y85338D01*
G01X410592Y86400D02*
X410554D01*
G01X413292Y89100D02*
X410592Y86400D01*
G01X413292Y91200D02*
Y89100D01*
G01X412192Y92300D02*
X413292Y91200D01*
G01X412192Y107113D02*
Y92300D01*
G01X416374Y64243D02*
X421456Y59161D01*
G01X416374Y67149D02*
Y64243D01*
G01X413492Y70031D02*
X416374Y67149D01*
G01X413492Y72000D02*
Y70031D01*
G01X413056Y72436D02*
X413492Y72000D01*
G01X413056Y82564D02*
Y72436D01*
G01X416692Y86200D02*
X413056Y82564D01*
G01X416292Y88800D02*
X416692Y88400D01*
G01X416292Y91700D02*
Y88800D01*
G01X416792Y92200D02*
X416292Y91700D01*
G01X376118Y120948D02*
X382692Y114374D01*
G01X376118Y196930D02*
Y120948D01*
G01X400898Y137982D02*
Y191694D01*
G01X429692Y109188D02*
X400898Y137982D01*
G01X366079Y102369D02*
Y198554D01*
G01X372423Y96025D02*
X366079Y102369D01*
G01X406198Y140099D02*
X434892Y111405D01*
G01X406198Y190981D02*
Y140099D01*
G01X361818Y98486D02*
Y198627D01*
G01X359918Y96586D02*
X361818Y98486D01*
G01X399292Y101556D02*
X402392Y98456D01*
G01X399292Y105600D02*
Y101556D01*
G01X381318Y123574D02*
X399292Y105600D01*
G01X381318Y190630D02*
Y123574D01*
G01X395692Y99795D02*
Y95700D01*
G01X394892Y100595D02*
X395692Y99795D01*
G01X393026Y100595D02*
X394892D01*
G01X392256Y101365D02*
X393026Y100595D01*
G01X392256Y102965D02*
Y101365D01*
G01X393086Y103795D02*
X392256Y102965D01*
G01X394801Y103795D02*
X393086D01*
G01X395662Y104656D02*
X394801Y103795D01*
G01X395662Y105930D02*
Y104656D01*
G01X379318Y122274D02*
X395662Y105930D01*
G01X379318Y191223D02*
Y122274D01*
G01X370118Y105302D02*
X377392Y98028D01*
G01X370118Y198554D02*
Y105302D01*
G01X356618Y117052D02*
X355487Y115921D01*
G01X356618Y118184D02*
Y117052D01*
G01X356188Y200081D02*
Y124806D01*
G01X406712Y109764D02*
X410192Y106284D01*
G01X402352Y109764D02*
X406712D01*
G01X393775Y118341D02*
X402352Y109764D01*
G01X392913Y118341D02*
X393775D01*
G01X391917Y117345D02*
X392913Y118341D01*
G01X391055Y117345D02*
X391917D01*
G01X389710Y118690D02*
X391055Y117345D01*
G01X389710Y119552D02*
Y118690D01*
G01X390706Y120548D02*
X389710Y119552D01*
G01X390706Y121410D02*
Y120548D01*
G01X389361Y122755D02*
X390706Y121410D01*
G01X388499Y122755D02*
X389361D01*
G01X387503Y121759D02*
X388499Y122755D01*
G01X386641Y121759D02*
X387503D01*
G01X385296Y123104D02*
X386641Y121759D01*
G01X385296Y123966D02*
Y123104D01*
G01X386292Y124962D02*
X385296Y123966D01*
G01X386292Y125824D02*
Y124962D01*
G01X384518Y127598D02*
X386292Y125824D01*
G01X384518Y194697D02*
Y127598D01*
G01X379714Y114522D02*
X380592Y113644D01*
G01X378582Y114522D02*
X379714D01*
G01X377442Y113382D02*
X378582Y114522D01*
G01X376310Y113382D02*
X377442D01*
G01X375179Y114513D02*
X376310Y113382D01*
G01X375179Y115645D02*
Y114513D01*
G01X376319Y116785D02*
X375179Y115645D01*
G01X376319Y117917D02*
Y116785D01*
G01X374118Y120118D02*
X376319Y117917D01*
G01X374118Y197381D02*
Y120118D01*
G01X363868Y99893D02*
Y198651D01*
G01X402898Y138873D02*
X431692Y110079D01*
G01X402898Y191500D02*
Y138873D01*
G01X413454Y141638D02*
X445875Y109217D01*
G01X413454Y195238D02*
Y141638D01*
G01X397648Y136768D02*
X425754Y108662D01*
G01X397648Y190969D02*
Y136768D01*
G01X409396Y116964D02*
X419292Y107068D01*
G01X407638Y116964D02*
X409396D01*
G01X392448Y132154D02*
X407638Y116964D01*
G01X392448Y191624D02*
Y132154D01*
G01X368118Y103159D02*
X374533Y96744D01*
G01X368118Y198724D02*
Y103159D01*
G01X359818Y104434D02*
Y199064D01*
G01X359018Y103634D02*
X359818Y104434D01*
G01X357418Y103634D02*
X359018D01*
G01X356618Y104434D02*
X357418Y103634D01*
G01X356618Y109894D02*
Y104434D01*
G01X355857Y110655D02*
X356618Y109894D01*
G01X408198Y140928D02*
X440015Y109111D01*
G01X408198Y191151D02*
Y140928D01*
G01X411404Y141324D02*
Y194243D01*
G01X443192Y109536D02*
X411404Y141324D01*
G01X411423Y120164D02*
X423754Y107833D01*
G01X408965Y120164D02*
X411423D01*
G01X407962Y121167D02*
X408965Y120164D01*
G01X407962Y123625D02*
Y121167D01*
G01X406897Y124690D02*
X407962Y123625D01*
G01X404439Y124690D02*
X406897D01*
G01X403370Y125759D02*
X404439Y124690D01*
G01X403370Y128217D02*
Y125759D01*
G01X402371Y129216D02*
X403370Y128217D01*
G01X399913Y129216D02*
X402371D01*
G01X398844Y130285D02*
X399913Y129216D01*
G01X398844Y132743D02*
Y130285D01*
G01X398189Y133398D02*
X398844Y132743D01*
G01X396448Y133398D02*
X398189D01*
G01X395648Y134198D02*
X396448Y133398D01*
G01X395648Y191381D02*
Y134198D01*
G01X407541Y111764D02*
X412192Y107113D01*
G01X402505Y111764D02*
X407541D01*
G01X386518Y127751D02*
X402505Y111764D01*
G01X386518Y195037D02*
Y127751D01*
G01X408567Y114964D02*
X416792Y106739D01*
G01X403157Y114964D02*
X408567D01*
G01X402167Y115954D02*
X403157Y114964D01*
G01X402167Y117132D02*
Y115954D01*
G01X402838Y117803D02*
X402167Y117132D01*
G01X402838Y118935D02*
Y117803D01*
G01X401707Y120066D02*
X402838Y118935D01*
G01X400575Y120066D02*
X401707D01*
G01X399855Y119346D02*
X400575Y120066D01*
G01X398703Y119346D02*
X399855D01*
G01X397572Y120477D02*
X398703Y119346D01*
G01X397572Y121589D02*
Y120477D01*
G01X398312Y122329D02*
X397572Y121589D01*
G01X398312Y123461D02*
Y122329D01*
G01X397181Y124592D02*
X398312Y123461D01*
G01X396049Y124592D02*
X397181D01*
G01X395469Y124012D02*
X396049Y124592D01*
G01X394256Y124012D02*
X395469D01*
G01X393125Y125143D02*
X394256Y124012D01*
G01X393125Y126194D02*
Y125143D01*
G01X393786Y126855D02*
X393125Y126194D01*
G01X393786Y127987D02*
Y126855D01*
G01X390448Y131325D02*
X393786Y127987D01*
G01X390448Y191575D02*
Y131325D01*
G01X409292Y199400D02*
X413454Y195238D01*
G01X409292Y204801D02*
Y199400D01*
G01X405148Y208945D02*
X409292Y204801D01*
G01X405148Y233851D02*
Y208945D01*
G01X402671Y208418D02*
Y235365D01*
G01X407168Y203921D02*
X402671Y208418D01*
G01X407168Y198479D02*
Y203921D01*
G01X411404Y194243D02*
X407168Y198479D01*
G01X407706Y236409D02*
X405148Y233851D01*
G01X402671Y235365D02*
X399676Y238360D01*
G01X359392Y401500D02*
X362754Y404862D01*
G01X401092Y402600D02*
X404092Y405600D01*
G01X401092Y399700D02*
Y402600D01*
G01X396092Y394700D02*
X401092Y399700D01*
G01X396092Y392507D02*
Y394700D01*
G01X374754Y399661D02*
Y496862D01*
G01X369693Y394600D02*
X374754Y399661D01*
G01X362292Y398700D02*
X366754Y403162D01*
G01X386192Y398000D02*
Y405000D01*
G01X382476Y394284D02*
X386192Y398000D01*
G01X384642Y399873D02*
Y406150D01*
G01X379530Y394761D02*
X384642Y399873D01*
G01X389792Y396200D02*
Y403500D01*
G01X388192Y394600D02*
X389792Y396200D01*
G01X388192Y392600D02*
Y394600D01*
G01X384792Y389200D02*
X388192Y392600D01*
G01X384792Y387900D02*
Y389200D01*
G01X384292Y387400D02*
X384792Y387900D01*
G01X384292Y385700D02*
Y387400D01*
G01X384592Y385400D02*
X384292Y385700D01*
G01X384592Y383800D02*
Y385400D01*
G01X383892Y383100D02*
X384592Y383800D01*
G01X383892Y381824D02*
Y383100D01*
G01X382777Y380709D02*
X383892Y381824D01*
G01X368754Y402262D02*
Y499933D01*
G01X364146Y397654D02*
X368754Y402262D01*
G01X396192Y403101D02*
X400842Y407751D01*
G01X396192Y398800D02*
Y403101D01*
G01X393592Y396200D02*
X396192Y398800D01*
G01X393592Y393500D02*
Y396200D01*
G01X414593Y402640D02*
Y468602D01*
G01X360967Y400225D02*
X364754Y404012D01*
G01X404692Y399600D02*
Y403400D01*
G01X403592Y398500D02*
X404692Y399600D01*
G01X402692Y398500D02*
X403592D01*
G01X398092Y393900D02*
X402692Y398500D01*
G01X398092Y391600D02*
Y393900D01*
G01X370754Y401412D02*
Y499104D01*
G01X365667Y396325D02*
X370754Y401412D01*
G01X387992Y397100D02*
Y404300D01*
G01X382192Y391300D02*
X387992Y397100D01*
G01X382192Y390600D02*
Y391300D01*
G01X380892Y389300D02*
X382192Y390600D01*
G01X380892Y387700D02*
Y389300D01*
G01X381426Y387166D02*
X380892Y387700D01*
G01X381426Y386034D02*
Y387166D01*
G01X380892Y385500D02*
X381426Y386034D01*
G01X380892Y383800D02*
Y385500D01*
G01X381292Y383400D02*
X380892Y383800D01*
G01X381292Y381899D02*
Y383400D01*
G01X379397Y380004D02*
X381292Y381899D01*
G01X379397Y378760D02*
Y380004D01*
G01X372754Y400562D02*
Y498275D01*
G01X367042Y394850D02*
X372754Y400562D01*
G01X411392Y401633D02*
Y469928D01*
G01X409392Y401553D02*
Y470757D01*
G01X394292Y399342D02*
Y404100D01*
G01X392592Y397642D02*
X394292Y399342D01*
G01X392592Y393800D02*
Y397642D01*
G01X362754Y404862D02*
Y490809D01*
G01X359554Y407781D02*
Y489438D01*
G01X383154Y411204D02*
Y483891D01*
G01X404092Y405600D02*
Y475199D01*
G01X366754Y403162D02*
Y506598D01*
G01X379954Y410706D02*
Y494062D01*
G01X390354Y409162D02*
Y480807D01*
G01X386192Y405000D02*
X390354Y409162D01*
G01X357554Y407727D02*
Y488238D01*
G01X388354Y409862D02*
Y481636D01*
G01X384642Y406150D02*
X388354Y409862D01*
G01X395554Y409262D02*
Y478651D01*
G01X389792Y403500D02*
X395554Y409262D01*
G01X400842Y407751D02*
Y476584D01*
G01X364754Y404012D02*
Y501144D01*
G01X406092Y404800D02*
Y474369D01*
G01X404692Y403400D02*
X406092Y404800D01*
G01X393554Y409862D02*
Y479481D01*
G01X387992Y404300D02*
X393554Y409862D01*
G01X398842Y408650D02*
Y477413D01*
G01X394292Y404100D02*
X398842Y408650D01*
G01X355554Y407821D02*
Y487138D01*
G01X385154Y411284D02*
Y483062D01*
G01X377954Y410841D02*
Y495262D01*
G01X356692Y524226D02*
Y527100D01*
G01Y496871D02*
Y506839D01*
G01X362754Y490809D02*
X356692Y496871D01*
G01X398647Y525022D02*
Y526905D01*
G01X399257Y524412D02*
X398647Y525022D01*
G01X400588Y524412D02*
X399257D01*
G01X401212Y523788D02*
X400588Y524412D01*
G01X401212Y522798D02*
Y523788D01*
G01X400616Y522202D02*
X401212Y522798D01*
G01X398797Y522202D02*
X400616D01*
G01X398184Y521589D02*
X398797Y522202D01*
G01X398184Y518008D02*
Y521589D01*
G01X401375Y514817D02*
X398184Y518008D01*
G01X401375Y512792D02*
Y514817D01*
G01Y502112D02*
Y512792D01*
G01X383154Y483891D02*
X401375Y502112D01*
G01X404092Y475199D02*
X430492Y501599D01*
G01X379592Y501700D02*
Y535400D01*
G01X374754Y496862D02*
X379592Y501700D01*
G01X368861Y508705D02*
Y527168D01*
G01X366754Y506598D02*
X368861Y508705D01*
G01X396307Y514085D02*
Y532454D01*
G01X396792Y513600D02*
X396307Y514085D01*
G01X396792Y512000D02*
Y513600D01*
G01X390546Y505754D02*
X396792Y512000D01*
G01X390546Y504654D02*
Y505754D01*
G01X379954Y494062D02*
X390546Y504654D01*
G01X409780Y516588D02*
Y530488D01*
G01X409492Y516300D02*
X409780Y516588D01*
G01X409492Y514500D02*
Y516300D01*
G01X410092Y513900D02*
X409492Y514500D01*
G01X410092Y512100D02*
Y513900D01*
G01X409492Y511500D02*
X410092Y512100D01*
G01X409492Y499945D02*
Y511500D01*
G01X390354Y480807D02*
X409492Y499945D01*
G01X406341Y519149D02*
Y538749D01*
G01X406092Y518900D02*
X406341Y519149D01*
G01X406092Y516900D02*
Y518900D01*
G01X406692Y516300D02*
X406092Y516900D01*
G01X406692Y514500D02*
Y516300D01*
G01X406092Y513900D02*
X406692Y514500D01*
G01X406092Y511800D02*
Y513900D01*
G01X406892Y511000D02*
X406092Y511800D01*
G01X406892Y500174D02*
Y511000D01*
G01X388354Y481636D02*
X406892Y500174D01*
G01X416376Y521616D02*
Y529884D01*
G01X417449Y520543D02*
X416376Y521616D01*
G01X416192Y516600D02*
X417449Y517857D01*
G01X416192Y514400D02*
Y516600D01*
G01X416692Y513900D02*
X416192Y514400D01*
G01X416092Y511200D02*
X416692Y511800D01*
G01X416092Y509100D02*
Y511200D01*
G01X416692Y508500D02*
X416092Y509100D01*
G01X395554Y478651D02*
X416692Y499789D01*
G01X370893Y526001D02*
X371792Y526900D01*
G01X370893Y502072D02*
Y526001D01*
G01X368754Y499933D02*
X370893Y502072D01*
G01X400842Y476584D02*
X425939Y501681D01*
G01X414593Y468602D02*
X443211Y497220D01*
G01X358692Y522968D02*
Y526800D01*
G01X356478Y520754D02*
X358692Y522968D01*
G01X356478Y509420D02*
Y520754D01*
G01X364754Y501144D02*
X356478Y509420D01*
G01X406092Y474369D02*
X429406Y497683D01*
G01X373792Y526001D02*
Y548900D01*
G01X372893Y525102D02*
X373792Y526001D01*
G01X372893Y501243D02*
Y525102D01*
G01X370754Y499104D02*
X372893Y501243D01*
G01X412892Y517000D02*
Y527100D01*
G01X413292Y516600D02*
X412892Y517000D01*
G01X413292Y514300D02*
Y516600D01*
G01X412892Y513900D02*
X413292Y514300D01*
G01X412892Y511700D02*
Y513900D01*
G01X413392Y511200D02*
X412892Y511700D01*
G01X413392Y509400D02*
Y511200D01*
G01X412692Y508700D02*
X413392Y509400D01*
G01X412692Y498619D02*
Y508700D01*
G01X393554Y479481D02*
X412692Y498619D01*
G01X377292Y502813D02*
Y535600D01*
G01X372754Y498275D02*
X377292Y502813D01*
G01X411392Y469928D02*
X439992Y498528D01*
G01X416453Y479659D02*
X417796Y481002D01*
G01X415110Y476475D02*
X416453Y477818D01*
G01X413980Y476475D02*
X415110D01*
G01X413270Y476476D02*
X413980Y476475D01*
G01X411927Y475133D02*
X413270Y476476D01*
G01X411927Y473292D02*
Y475133D01*
G01X409392Y470757D02*
X411927Y473292D01*
G01X398842Y477413D02*
X420666Y499237D01*
G01X403020Y519472D02*
Y530428D01*
G01X403257Y519235D02*
X403020Y519472D01*
G01X403257Y516965D02*
Y519235D01*
G01X402998Y516706D02*
X403257Y516965D01*
G01X402998Y514094D02*
Y516706D01*
G01X403492Y513600D02*
X402998Y514094D01*
G01X403492Y511229D02*
Y513600D01*
G01X404722Y509999D02*
X403492Y511229D01*
G01X404722Y502630D02*
Y509999D01*
G01X385154Y483062D02*
X404722Y502630D01*
G01X381692Y499000D02*
Y535200D01*
G01X377954Y495262D02*
X381692Y499000D01*
G01X356154Y536166D02*
Y541073D01*
G01X355594Y535606D02*
X356154Y536166D01*
G01X355594Y530918D02*
Y535606D01*
G01X356152Y530360D02*
X355594Y530918D01*
G01X356152Y527640D02*
Y530360D01*
G01X356692Y527100D02*
X356152Y527640D01*
G01X401376Y536956D02*
X401377Y536957D01*
G01X401376Y534584D02*
Y536956D01*
G01X399492Y532700D02*
X401376Y534584D01*
G01X399492Y530700D02*
Y532700D01*
G01X399759Y530433D02*
X399492Y530700D01*
G01X399759Y528017D02*
Y530433D01*
G01X398647Y526905D02*
X399759Y528017D01*
G01X406392Y587391D02*
Y600240D01*
G01X404723Y585722D02*
X406392Y587391D01*
G01X404723Y584762D02*
Y585722D01*
G01X397761Y577800D02*
X404723Y584762D01*
G01X385992Y577800D02*
X397761D01*
G01X381792Y573600D02*
X385992Y577800D01*
G01X381792Y537600D02*
Y573600D01*
G01X379592Y535400D02*
X381792Y537600D01*
G01X369792Y575267D02*
X368283Y576776D01*
G01X369792Y558700D02*
Y575267D01*
G01X371992Y556500D02*
X369792Y558700D01*
G01X371992Y551900D02*
Y556500D01*
G01X369792Y549700D02*
X371992Y551900D01*
G01X369792Y528099D02*
Y549700D01*
G01X368861Y527168D02*
X369792Y528099D01*
G01X404723Y569554D02*
Y574757D01*
G01X403109Y567940D02*
X404723Y569554D01*
G01X403109Y552448D02*
Y567940D01*
G01X404723Y550834D02*
X403109Y552448D01*
G01X404723Y547922D02*
Y550834D01*
G01X399737Y542936D02*
X404723Y547922D01*
G01X399737Y535884D02*
Y542936D01*
G01X396307Y532454D02*
X399737Y535884D01*
G01X416375Y569620D02*
X419505Y572750D01*
G01X416375Y554883D02*
Y569620D01*
G01X413100Y551608D02*
X416375Y554883D01*
G01X413100Y546708D02*
Y551608D01*
G01X409779Y543387D02*
X413100Y546708D01*
G01X409779Y535687D02*
Y543387D01*
G01X409992Y535474D02*
X409779Y535687D01*
G01X409992Y530700D02*
Y535474D01*
G01X409780Y530488D02*
X409992Y530700D01*
G01X416391Y573699D02*
Y588592D01*
G01X412792Y570100D02*
X416391Y573699D01*
G01X412792Y568400D02*
Y570100D01*
G01X413158Y568034D02*
X412792Y568400D01*
G01X413158Y554766D02*
Y568034D01*
G01X409992Y551600D02*
X413158Y554766D01*
G01X409992Y549200D02*
Y551600D01*
G01X409809Y549017D02*
X409992Y549200D01*
G01X409809Y546157D02*
Y549017D01*
G01X407092Y543440D02*
X409809Y546157D01*
G01X407092Y539500D02*
Y543440D01*
G01X406341Y538749D02*
X407092Y539500D01*
G01X416376Y529884D02*
X418873Y532381D01*
G01X371792Y575822D02*
X366602Y581012D01*
G01X371792Y559100D02*
Y575822D01*
G01X373692Y557200D02*
X371792Y559100D01*
G01X373692Y551200D02*
Y557200D01*
G01X371792Y549300D02*
X373692Y551200D01*
G01X371792Y526900D02*
Y549300D01*
G01X356202Y562575D02*
X355340D01*
G01X359615Y559162D02*
X356202Y562575D01*
G01X359615Y536302D02*
Y559162D01*
G01X361396Y534521D02*
X359615Y536302D01*
G01X362696Y534521D02*
X361396D01*
G01X363508Y533709D02*
X362696Y534521D01*
G01X363508Y532129D02*
Y533709D01*
G01X362492Y531113D02*
X363508Y532129D01*
G01X360692Y531113D02*
X362492D01*
G01X359892Y530313D02*
X360692Y531113D01*
G01X359892Y528000D02*
Y530313D01*
G01X358692Y526800D02*
X359892Y528000D01*
G01X367270Y582622D02*
X357625D01*
G01X375592Y574300D02*
X367270Y582622D01*
G01X375592Y550700D02*
Y574300D01*
G01X373792Y548900D02*
X375592Y550700D01*
G01X416390Y543558D02*
X419829Y546997D01*
G01X416390Y535498D02*
Y543558D01*
G01X413100Y532208D02*
X416390Y535498D01*
G01X413100Y527308D02*
Y532208D01*
G01X412892Y527100D02*
X413100Y527308D01*
G01X401377Y585722D02*
Y590982D01*
G01X395938Y580283D02*
X401377Y585722D01*
G01X385763Y580283D02*
X395938D01*
G01X380092Y574612D02*
X385763Y580283D01*
G01X380092Y538400D02*
Y574612D01*
G01X377292Y535600D02*
X380092Y538400D01*
G01X404722Y536956D02*
X404723Y536957D01*
G01X404722Y534264D02*
Y536956D01*
G01X403492Y533034D02*
X404722Y534264D01*
G01X403492Y530900D02*
Y533034D01*
G01X403020Y530428D02*
X403492Y530900D01*
G01X401377Y570260D02*
Y574757D01*
G01X399745Y568628D02*
X401377Y570260D01*
G01X399745Y561335D02*
Y568628D01*
G01X399656Y561246D02*
X399745Y561335D01*
G01X399656Y552354D02*
Y561246D01*
G01X401376Y550634D02*
X399656Y552354D01*
G01X401376Y547922D02*
Y550634D01*
G01X399171Y545717D02*
X401376Y547922D01*
G01X392539Y545717D02*
X399171D01*
G01X391419Y544597D02*
X392539Y545717D01*
G01X391419Y542932D02*
Y544597D01*
G01X390234Y541747D02*
X391419Y542932D01*
G01X388239Y541747D02*
X390234D01*
G01X381692Y535200D02*
X388239Y541747D01*
G01X404722Y607602D02*
Y609864D01*
G01X406777Y605547D02*
X404722Y607602D01*
G01X406777Y600625D02*
Y605547D01*
G01X406392Y600240D02*
X406777Y600625D01*
G01X415707Y600765D02*
X421728D01*
G01X414834Y599892D02*
X415707Y600765D01*
G01X414834Y598408D02*
Y599892D01*
G01X415677Y597565D02*
X414834Y598408D01*
G01X420420Y597565D02*
X415677D01*
G01X416391Y588592D02*
X421456Y593657D01*
G01X356329Y606237D02*
Y608263D01*
G01X401376Y610216D02*
Y612658D01*
G01X399497Y608337D02*
X401376Y610216D01*
G01X399497Y606023D02*
Y608337D01*
G01X399973Y605547D02*
X399497Y606023D01*
G01X399973Y595381D02*
Y605547D01*
G01X399643Y595051D02*
X399973Y595381D01*
G01X399643Y592716D02*
Y595051D01*
G01X401377Y590982D02*
X399643Y592716D01*
G01X443147Y-42355D02*
G02Y-45915I0J-1780D01*
G01X476245Y-8654D02*
X474998Y-9901D01*
G01X476245Y-7400D02*
Y-8654D01*
G01X477545Y-6100D02*
X476245Y-7400D01*
G01X478545Y-6100D02*
X477545D01*
G01X476533Y13925D02*
X478344Y12114D01*
G01X476533Y15550D02*
Y13925D01*
G01X479792Y18809D02*
X476533Y15550D01*
G01X421454Y-4538D02*
Y-7108D01*
G01X419592Y-2676D02*
X421454Y-4538D01*
G01X419592Y7600D02*
Y-2676D01*
G01X419836Y7844D02*
X419592Y7600D01*
G01X419836Y10556D02*
Y7844D01*
G01X419592Y10800D02*
X419836Y10556D01*
G01X419592Y14061D02*
Y10800D01*
G01X421456Y15925D02*
X419592Y14061D01*
G01X421456Y17057D02*
Y15925D01*
G01Y18597D02*
Y17057D01*
G01X460045Y-3233D02*
X460912Y-4100D01*
G01X460045Y-932D02*
Y-3233D01*
G01X458412Y701D02*
X460045Y-932D01*
G01X458412Y2000D02*
Y701D01*
G01X459762Y3350D02*
X458412Y2000D01*
G01X459762Y4250D02*
Y3350D01*
G01X458512Y5500D02*
X459762Y4250D01*
G01X458512Y6699D02*
Y5500D01*
G01X460045Y8232D02*
X458512Y6699D01*
G01X460045Y10200D02*
Y8232D01*
G01X457145Y13100D02*
X460045Y10200D01*
G01X457145Y16036D02*
Y13100D01*
G01X458266Y17157D02*
X457145Y16036D01*
G01X458266Y24174D02*
Y17157D01*
G01X460133Y26041D02*
X458266Y24174D01*
G01X460133Y28459D02*
Y26041D01*
G01X458983Y29609D02*
X460133Y28459D01*
G01X458983Y34191D02*
Y29609D01*
G01X476870Y-2226D02*
X478344Y-3700D01*
G01X476870Y-1132D02*
Y-2226D01*
G01X475437Y301D02*
X476870Y-1132D01*
G01X475437Y1524D02*
Y301D01*
G01X475652Y1740D02*
X475437Y1524D01*
G01X476937Y3024D02*
X475652Y1740D01*
G01X476937Y4376D02*
Y3024D01*
G01X475437Y5876D02*
X476937Y4376D01*
G01X475437Y6999D02*
Y5876D01*
G01X477112Y8674D02*
X475437Y6999D01*
G01X477112Y10059D02*
Y8674D01*
G01X474070Y13101D02*
X477112Y10059D01*
G01X474070Y16229D02*
Y13101D01*
G01X474998Y17157D02*
X474070Y16229D01*
G01X477492Y19651D02*
X474998Y17157D01*
G01X477492Y28040D02*
Y19651D01*
G01X476092Y29440D02*
X477492Y28040D01*
G01X476092Y34400D02*
Y29440D01*
G01X450645Y16229D02*
X451573Y17157D01*
G01X450645Y13101D02*
Y16229D01*
G01X453445Y10301D02*
X450645Y13101D01*
G01X453445Y8432D02*
Y10301D01*
G01X452062Y7049D02*
X453445Y8432D01*
G01X452062Y5650D02*
Y7049D01*
G01X453512Y4200D02*
X452062Y5650D01*
G01X453512Y3000D02*
Y4200D01*
G01X452012Y1500D02*
X453512Y3000D01*
G01X452012Y301D02*
Y1500D01*
G01X453445Y-1132D02*
X452012Y301D01*
G01X453445Y-3012D02*
Y-1132D01*
G01X454533Y-4100D02*
X453445Y-3012D01*
G01X452633Y29359D02*
Y34441D01*
G01X453592Y28400D02*
X452633Y29359D01*
G01X453592Y26800D02*
Y28400D01*
G01X451573Y24781D02*
X453592Y26800D01*
G01X451573Y17157D02*
Y24781D01*
G01X438187Y11165D02*
Y9124D01*
G01X439792Y12770D02*
X438187Y11165D01*
G01X439792Y17865D02*
Y12770D01*
G01X440974Y19047D02*
X439792Y17865D01*
G01X443499Y19047D02*
X440974D01*
G01X444096Y19644D02*
X443499Y19047D01*
G01X444096Y21544D02*
Y19644D01*
G01X442295Y23345D02*
X444096Y21544D01*
G01X442295Y26270D02*
Y23345D01*
G01X443268Y27243D02*
X442295Y26270D01*
G01X443268Y28976D02*
Y27243D01*
G01X446500Y32208D02*
X443268Y28976D01*
G01X446500Y37108D02*
Y32208D01*
G01X438189Y9122D02*
X438187Y9124D01*
G01X438189Y-4534D02*
Y9122D01*
G01X438187Y-4536D02*
X438189Y-4534D01*
G01X438187Y9124D02*
Y9120D01*
G01X439575Y31453D02*
X443252Y35130D01*
G01X438893Y31453D02*
X439575D01*
G01X436556Y29116D02*
X438893Y31453D01*
G01X436556Y12658D02*
Y29116D01*
G01X434840Y10942D02*
X436556Y12658D01*
G01X434840Y9124D02*
Y10942D01*
G01X434842Y9122D02*
X434840Y9124D01*
G01Y9120D02*
X434842Y9122D01*
G01X434840Y6229D02*
Y9120D01*
G01X434230Y5619D02*
X434840Y6229D01*
G01X431963Y5619D02*
X434230D01*
G01X431353Y5009D02*
X431963Y5619D01*
G01X431353Y3109D02*
Y5009D01*
G01X431963Y2499D02*
X431353Y3109D01*
G01X434230Y2499D02*
X431963D01*
G01X434840Y1889D02*
X434230Y2499D01*
G01X434840Y-1743D02*
Y1889D01*
G01X458266Y-7779D02*
Y-9901D01*
G01X460145Y-5900D02*
X458266Y-7779D01*
G01X461545Y-5900D02*
X460145D01*
G01X463001Y-4444D02*
X461545Y-5900D01*
G01X463001Y-3100D02*
Y-4444D01*
G01X462385Y-2484D02*
X463001Y-3100D01*
G01X462385Y10641D02*
Y-2484D01*
G01X460912Y12114D02*
X462385Y10641D01*
G01X458839Y14187D02*
X460912Y12114D01*
G01X458839Y15248D02*
Y14187D01*
G01X460333Y16742D02*
X458839Y15248D01*
G01X460333Y22441D02*
Y16742D01*
G01X462833Y24941D02*
X460333Y22441D01*
G01X462833Y37141D02*
Y24941D01*
G01X424903Y-1743D02*
X428147D01*
G01X423729Y-569D02*
X424903Y-1743D01*
G01X423729Y6384D02*
Y-569D01*
G01X424339Y6994D02*
X423729Y6384D01*
G01X425329Y6994D02*
X424339D01*
G01X425939Y6384D02*
X425329Y6994D01*
G01X425939Y2023D02*
Y6384D01*
G01X426589Y1373D02*
X425939Y2023D01*
G01X427579Y1373D02*
X426589D01*
G01X428147Y1941D02*
X427579Y1373D01*
G01X428147Y9120D02*
Y1941D01*
G01Y10483D02*
Y9120D01*
G01X423128Y15502D02*
X428147Y10483D01*
G01X423128Y20322D02*
Y15502D01*
G01X456483Y28849D02*
Y35049D01*
G01X456233Y28599D02*
X456483Y28849D01*
G01X456233Y25841D02*
Y28599D01*
G01X454192Y23800D02*
X456233Y25841D01*
G01X454192Y17073D02*
Y23800D01*
G01X452633Y15514D02*
X454192Y17073D01*
G01X452633Y14100D02*
Y15514D01*
G01X454619Y12114D02*
X452633Y14100D01*
G01X455845Y10888D02*
X454619Y12114D01*
G01X455845Y-2125D02*
Y10888D01*
G01X456620Y-2900D02*
X455845Y-2125D01*
G01X456620Y-4524D02*
Y-2900D01*
G01X455044Y-6100D02*
X456620Y-4524D01*
G01X453820Y-6100D02*
X455044D01*
G01X451573Y-8347D02*
X453820Y-6100D01*
G01X451573Y-9901D02*
Y-8347D01*
G01X419405Y30073D02*
X421456Y28022D01*
G01X419405Y33545D02*
Y30073D01*
G01X433411Y45491D02*
X434842Y46922D01*
G01X433411Y37388D02*
Y45491D01*
G01X434842Y35957D02*
X433411Y37388D01*
G01X429692Y93850D02*
Y109188D01*
G01X430042Y93500D02*
X429692Y93850D01*
G01X430042Y91650D02*
Y93500D01*
G01X429675Y91283D02*
X430042Y91650D01*
G01X429675Y89217D02*
Y91283D01*
G01X430192Y88700D02*
X429675Y89217D01*
G01X430192Y86300D02*
Y88700D01*
G01X429692Y85800D02*
X430192Y86300D01*
G01X429692Y83700D02*
Y85800D01*
G01X430092Y83300D02*
X429692Y83700D01*
G01X430092Y75798D02*
Y83300D01*
G01X429769Y75475D02*
X430092Y75798D01*
G01X429769Y63864D02*
Y75475D01*
G01X433106Y60527D02*
X429769Y63864D01*
G01X433106Y53475D02*
Y60527D01*
G01X431646Y52015D02*
X433106Y53475D01*
G01X431646Y50118D02*
Y52015D01*
G01X434842Y46922D02*
X431646Y50118D01*
G01X436158Y75073D02*
X434842Y73757D01*
G01X436158Y85336D02*
Y75073D01*
G01X436692Y85870D02*
X436158Y85336D01*
G01X436692Y86592D02*
Y85870D01*
G01X435892Y87392D02*
X436692Y86592D01*
G01X434840Y87392D02*
X435892D01*
G01X434840Y88048D02*
Y87392D01*
G01X436292Y89500D02*
X434840Y88048D01*
G01X436292Y90900D02*
Y89500D01*
G01X436692Y91300D02*
X436292Y90900D01*
G01X436692Y93700D02*
Y91300D01*
G01X436492Y93900D02*
X436692Y93700D01*
G01X436492Y101900D02*
Y93900D01*
G01X460092Y35300D02*
X458983Y34191D01*
G01X460092Y37300D02*
Y35300D01*
G01X459592Y37800D02*
X460092Y37300D01*
G01X459592Y45659D02*
Y37800D01*
G01X459992Y46059D02*
X459592Y45659D01*
G01X459992Y47905D02*
Y46059D01*
G01X458983Y48914D02*
X459992Y47905D01*
G01X458983Y53192D02*
Y48914D01*
G01X460333Y54542D02*
X458983Y53192D01*
G01X460333Y66059D02*
Y54542D01*
G01X458983Y67409D02*
X460333Y66059D01*
G01X458983Y72091D02*
Y67409D01*
G01X460066Y73174D02*
X458983Y72091D01*
G01X460066Y75267D02*
Y73174D01*
G01X459767Y75566D02*
X460066Y75267D01*
G01X459767Y83475D02*
Y75566D01*
G01X459992Y83700D02*
X459767Y83475D01*
G01X459992Y85648D02*
Y83700D01*
G01X459066Y86574D02*
X459992Y85648D01*
G01X459066Y90924D02*
Y86574D01*
G01X460166Y92024D02*
X459066Y90924D01*
G01X460166Y102226D02*
Y92024D01*
G01X477233Y35541D02*
X476092Y34400D01*
G01X477233Y37060D02*
Y35541D01*
G01X476392Y37901D02*
X477233Y37060D01*
G01X476392Y45700D02*
Y37901D01*
G01X477233Y46541D02*
X476392Y45700D01*
G01X477233Y47914D02*
Y46541D01*
G01X476433Y48714D02*
X477233Y47914D01*
G01X476433Y53414D02*
Y48714D01*
G01X476833Y53814D02*
X476433Y53414D01*
G01X476833Y66499D02*
Y53814D01*
G01X476192Y67140D02*
X476833Y66499D01*
G01X476192Y72300D02*
Y67140D01*
G01X477233Y73341D02*
X476192Y72300D01*
G01X477233Y74459D02*
Y73341D01*
G01X476192Y75500D02*
X477233Y74459D01*
G01X476192Y83300D02*
Y75500D01*
G01X477233Y84341D02*
X476192Y83300D01*
G01X477233Y85714D02*
Y84341D01*
G01X476092Y86855D02*
X477233Y85714D01*
G01X476092Y90873D02*
Y86855D01*
G01X476892Y91673D02*
X476092Y90873D01*
G01X476892Y101400D02*
Y91673D01*
G01X453461Y91769D02*
Y101066D01*
G01X452766Y91074D02*
X453461Y91769D01*
G01X452766Y86474D02*
Y91074D01*
G01X453417Y85823D02*
X452766Y86474D01*
G01X453417Y84000D02*
Y85823D01*
G01X452792Y83375D02*
X453417Y84000D01*
G01X452792Y75400D02*
Y83375D01*
G01X453417Y74775D02*
X452792Y75400D01*
G01X453417Y73059D02*
Y74775D01*
G01X452633Y72275D02*
X453417Y73059D01*
G01X452633Y67159D02*
Y72275D01*
G01X454292Y65500D02*
X452633Y67159D01*
G01X454292Y54701D02*
Y65500D01*
G01X452769Y53178D02*
X454292Y54701D01*
G01X452769Y48322D02*
Y53178D01*
G01X453692Y47399D02*
X452769Y48322D01*
G01X453692Y46200D02*
Y47399D01*
G01X452992Y45500D02*
X453692Y46200D01*
G01X452992Y37600D02*
Y45500D01*
G01X453692Y36900D02*
X452992Y37600D01*
G01X453692Y35500D02*
Y36900D01*
G01X452633Y34441D02*
X453692Y35500D01*
G01X438187Y46924D02*
X438189Y46922D01*
G01X438187Y49505D02*
Y46924D01*
G01X436128Y51564D02*
X438187Y49505D01*
G01X436128Y53436D02*
Y51564D01*
G01X436557Y53865D02*
X436128Y53436D01*
G01X436557Y61154D02*
Y53865D01*
G01X433216Y64495D02*
X436557Y61154D01*
G01X433216Y66774D02*
Y64495D01*
G01X431761Y68229D02*
X433216Y66774D01*
G01X431761Y70970D02*
Y68229D01*
G01X433216Y72425D02*
X431761Y70970D01*
G01X433216Y76226D02*
Y72425D01*
G01X432792Y76650D02*
X433216Y76226D01*
G01X432792Y83100D02*
Y76650D01*
G01X433392Y83700D02*
X432792Y83100D01*
G01X433392Y85400D02*
Y83700D01*
G01X432592Y86200D02*
X433392Y85400D01*
G01X432592Y88500D02*
Y86200D01*
G01X433392Y89300D02*
X432592Y88500D01*
G01X433392Y91100D02*
Y89300D01*
G01X432792Y91700D02*
X433392Y91100D01*
G01X432792Y93600D02*
Y91700D01*
G01X433292Y94100D02*
X432792Y93600D01*
G01X433292Y101200D02*
Y94100D01*
G01X436492Y37654D02*
X438189Y35957D01*
G01X436492Y45225D02*
Y37654D01*
G01X438189Y46922D02*
X436492Y45225D01*
G01X446692Y37300D02*
X446500Y37108D01*
G01X446692Y85600D02*
Y37300D01*
G01X446680Y85612D02*
X446692Y85600D01*
G01X446680Y102212D02*
Y85612D01*
G01X428147Y88045D02*
Y87392D01*
G01X427792Y88400D02*
X428147Y88045D01*
G01X427792Y90100D02*
Y88400D01*
G01X426069Y91823D02*
X427792Y90100D01*
G01X426069Y93277D02*
Y91823D01*
G01X426492Y93700D02*
X426069Y93277D01*
G01X426492Y101700D02*
Y93700D01*
G01X428149Y75001D02*
Y73757D01*
G01X427554Y75596D02*
X428149Y75001D01*
G01X422138Y75596D02*
X427554D01*
G01X421581Y76153D02*
X422138Y75596D01*
G01X421581Y77143D02*
Y76153D01*
G01X422244Y77806D02*
X421581Y77143D01*
G01X427739Y77806D02*
X422244D01*
G01X428384Y78451D02*
X427739Y77806D01*
G01X428384Y79441D02*
Y78451D01*
G01X427809Y80016D02*
X428384Y79441D01*
G01X424384Y80016D02*
X427809D01*
G01X423774Y80626D02*
X424384Y80016D01*
G01X423774Y81616D02*
Y80626D01*
G01X424384Y82226D02*
X423774Y81616D01*
G01X427234Y82226D02*
X424384D01*
G01X427844Y82836D02*
X427234Y82226D01*
G01X427844Y87089D02*
Y82836D01*
G01X428147Y87392D02*
X427844Y87089D01*
G01X428149Y37190D02*
Y35957D01*
G01X427649Y37690D02*
X428149Y37190D01*
G01X423626Y37690D02*
X427649D01*
G01X422965Y38351D02*
X423626Y37690D01*
G01X422965Y39727D02*
Y38351D01*
G01X423575Y40337D02*
X422965Y39727D01*
G01X427539Y40337D02*
X423575D01*
G01X428149Y40947D02*
X427539Y40337D01*
G01X428149Y42146D02*
Y40947D01*
G01X427539Y42756D02*
X428149Y42146D01*
G01X423575Y42756D02*
X427539D01*
G01X422965Y43366D02*
X423575Y42756D01*
G01X422965Y44397D02*
Y43366D01*
G01X423575Y45007D02*
X422965Y44397D01*
G01X427539Y45007D02*
X423575D01*
G01X428149Y45617D02*
X427539Y45007D01*
G01X428149Y46922D02*
Y45617D01*
G01X428147Y46924D02*
X428149Y46922D01*
G01X428147Y51445D02*
Y46924D01*
G01X426433Y53159D02*
X428147Y51445D01*
G01X426433Y57583D02*
Y53159D01*
G01X419820Y64196D02*
X426433Y57583D01*
G01X419820Y66572D02*
Y64196D01*
G01X417142Y79605D02*
Y76716D01*
G01X419992Y82455D02*
X417142Y79605D01*
G01X419992Y85400D02*
Y82455D01*
G01X419592Y85800D02*
X419992Y85400D01*
G01X419592Y88800D02*
Y85800D01*
G01X419992Y89200D02*
X419592Y88800D01*
G01X419992Y90800D02*
Y89200D01*
G01X419292Y91500D02*
X419992Y90800D01*
G01X419292Y107068D02*
Y91500D01*
G01X438792Y85319D02*
X438187Y84714D01*
G01X438792Y86699D02*
Y85319D01*
G01X439692Y87599D02*
X438792Y86699D01*
G01X439692Y88700D02*
Y87599D01*
G01X440450Y89458D02*
X439692Y88700D01*
G01X440450Y90342D02*
Y89458D01*
G01X438921Y91871D02*
X440450Y90342D01*
G01X438921Y94683D02*
Y91871D01*
G01X440092Y75660D02*
X438189Y73757D01*
G01X440092Y77434D02*
Y75660D01*
G01X438493Y79033D02*
X440092Y77434D01*
G01X438493Y80892D02*
Y79033D01*
G01X439485Y81884D02*
X438493Y80892D01*
G01X439485Y83416D02*
Y81884D01*
G01X438187Y84714D02*
X439485Y83416D01*
G01X443192Y93600D02*
Y109536D01*
G01X443392Y93400D02*
X443192Y93600D01*
G01X443392Y91400D02*
Y93400D01*
G01X442992Y91000D02*
X443392Y91400D01*
G01X442992Y89000D02*
Y91000D01*
G01X443392Y88600D02*
X442992Y89000D01*
G01X443392Y86600D02*
Y88600D01*
G01X442992Y86200D02*
X443392Y86600D01*
G01X442992Y74900D02*
Y86200D01*
G01X443272Y74620D02*
X442992Y74900D01*
G01X443272Y61736D02*
Y74620D01*
G01X442692Y61156D02*
X443272Y61736D01*
G01X442692Y56500D02*
Y61156D01*
G01X443243Y55949D02*
X442692Y56500D01*
G01X443243Y43789D02*
Y55949D01*
G01X442592Y43138D02*
X443243Y43789D01*
G01X442592Y37800D02*
Y43138D01*
G01X443252Y37140D02*
X442592Y37800D01*
G01X443252Y35130D02*
Y37140D01*
G01X421456Y67336D02*
Y65822D01*
G01X419443Y69349D02*
X421456Y67336D01*
G01X419443Y71824D02*
Y69349D01*
G01X419841Y72222D02*
X419443Y71824D01*
G01X419841Y77778D02*
Y72222D01*
G01X421965Y79902D02*
X419841Y77778D01*
G01X421965Y92246D02*
Y79902D01*
G01X421454Y92757D02*
X421965Y92246D01*
G01X421454Y94815D02*
Y92757D01*
G01X463400Y37708D02*
X462833Y37141D01*
G01X463400Y45687D02*
Y37708D01*
G01X462833Y46254D02*
X463400Y45687D01*
G01X462833Y75000D02*
Y46254D01*
G01X463492Y75659D02*
X462833Y75000D01*
G01X463492Y83300D02*
Y75659D01*
G01X462833Y83959D02*
X463492Y83300D01*
G01X462833Y105050D02*
Y83959D01*
G01X456184Y91856D02*
Y102408D01*
G01X456566Y91474D02*
X456184Y91856D01*
G01X456566Y86574D02*
Y91474D01*
G01X455917Y85925D02*
X456566Y86574D01*
G01X455917Y84375D02*
Y85925D01*
G01X456692Y83600D02*
X455917Y84375D01*
G01X456692Y74800D02*
Y83600D01*
G01X455917Y74025D02*
X456692Y74800D01*
G01X455917Y72508D02*
Y74025D01*
G01X456483Y71942D02*
X455917Y72508D01*
G01X456483Y66649D02*
Y71942D01*
G01X456392Y66558D02*
X456483Y66649D01*
G01X456392Y53705D02*
Y66558D01*
G01X456483Y53614D02*
X456392Y53705D01*
G01X456483Y47692D02*
Y53614D01*
G01X456133Y47342D02*
X456483Y47692D01*
G01X456133Y46200D02*
Y47342D01*
G01X456792Y45541D02*
X456133Y46200D01*
G01X456792Y37600D02*
Y45541D01*
G01X456133Y36941D02*
X456792Y37600D01*
G01X456133Y35399D02*
Y36941D01*
G01X456483Y35049D02*
X456133Y35399D01*
G01X419826Y33966D02*
X419405Y33545D01*
G01X419826Y49193D02*
Y33966D01*
G01X419368Y49651D02*
X419826Y49193D01*
G01X419368Y52769D02*
Y49651D01*
G01X421456Y54857D02*
X419368Y52769D01*
G01X421456Y59161D02*
Y54857D01*
G01X416692Y88400D02*
Y86200D01*
G01X416792Y106739D02*
Y92200D01*
G01X466251Y153116D02*
X490267Y129100D01*
G01X466251Y166859D02*
Y153116D01*
G01X434892Y103500D02*
X436492Y101900D01*
G01X434892Y111405D02*
Y103500D01*
G01X445320Y154246D02*
X481392Y118174D01*
G01X445320Y169265D02*
Y154246D01*
G01X456892Y105500D02*
X460166Y102226D01*
G01X456892Y120613D02*
Y105500D01*
G01X455765Y121740D02*
X456892Y120613D01*
G01X454636Y121740D02*
X455765D01*
G01X453390Y120494D02*
X454636Y121740D01*
G01X452598Y120494D02*
X453390D01*
G01X451127Y121965D02*
X452598Y120494D01*
G01X451127Y122757D02*
Y121965D01*
G01X452372Y124002D02*
X451127Y122757D01*
G01X452372Y125133D02*
Y124002D01*
G01X451239Y126266D02*
X452372Y125133D01*
G01X450109Y126266D02*
X451239D01*
G01X447906Y124063D02*
X450109Y126266D01*
G01X446777Y124063D02*
X447906D01*
G01X445644Y125196D02*
X446777Y124063D01*
G01X445644Y126326D02*
Y125196D01*
G01X447846Y128528D02*
X445644Y126326D01*
G01X447846Y129659D02*
Y128528D01*
G01X446713Y130792D02*
X447846Y129659D01*
G01X445583Y130792D02*
X446713D01*
G01X444607Y129816D02*
X445583Y130792D01*
G01X443478Y129816D02*
X444607D01*
G01X442345Y130949D02*
X443478Y129816D01*
G01X442345Y132079D02*
Y130949D01*
G01X443320Y133054D02*
X442345Y132079D01*
G01X443320Y134185D02*
Y133054D01*
G01X424519Y152992D02*
X443320Y134185D01*
G01X424519Y188139D02*
Y152992D01*
G01X468656Y154248D02*
X489818Y133086D01*
G01X468656Y168028D02*
Y154248D01*
G01X475592Y102700D02*
X476892Y101400D01*
G01X475592Y103452D02*
Y102700D01*
G01X476392Y104252D02*
X475592Y103452D01*
G01X477492Y104252D02*
X476392D01*
G01X478292Y105052D02*
X477492Y104252D01*
G01Y107452D02*
X478292Y106652D01*
G01X476392Y107452D02*
X477492D01*
G01X475592Y108252D02*
X476392Y107452D01*
G01X475592Y109852D02*
Y108252D01*
G01X476392Y110652D02*
X475592Y109852D01*
G01X478515Y110652D02*
X476392D01*
G01Y113852D02*
X478515D01*
G01X475592Y114652D02*
X476392Y113852D01*
G01X475592Y115500D02*
Y114652D01*
G01X477292Y117200D02*
X475592Y115500D01*
G01X477292Y118738D02*
Y117200D01*
G01X437771Y158259D02*
X477292Y118738D01*
G01X463781Y152050D02*
X489631Y126200D01*
G01X463781Y166274D02*
Y152050D01*
G01X419784Y150508D02*
Y189404D01*
G01X426378Y143914D02*
X419784Y150508D01*
G01X426378Y142782D02*
Y143914D01*
G01X423755Y140159D02*
X426378Y142782D01*
G01X423755Y139027D02*
Y140159D01*
G01X425222Y137560D02*
X423755Y139027D01*
G01X426354Y137560D02*
X425222D01*
G01X428977Y140183D02*
X426354Y137560D01*
G01X430109Y140183D02*
X428977D01*
G01X431415Y138877D02*
X430109Y140183D01*
G01X431415Y137745D02*
Y138877D01*
G01X428838Y135168D02*
X431415Y137745D01*
G01X428838Y133555D02*
Y135168D01*
G01X451792Y110601D02*
X428838Y133555D01*
G01X451792Y102735D02*
Y110601D01*
G01X453461Y101066D02*
X451792Y102735D01*
G01X431692Y102800D02*
X433292Y101200D01*
G01X431692Y110079D02*
Y102800D01*
G01X445192Y103700D02*
X446680Y102212D01*
G01X445192Y105900D02*
Y103700D01*
G01X445875Y106583D02*
X445192Y105900D01*
G01X425754Y102438D02*
X426492Y101700D01*
G01X425754Y108662D02*
Y102438D01*
G01X457345Y149293D02*
X486392Y120246D01*
G01X457345Y153017D02*
Y149293D01*
G01X456785Y153577D02*
X457345Y153017D01*
G01X454852Y153577D02*
X456785D01*
G01X454292Y154137D02*
X454852Y153577D01*
G01X454292Y155577D02*
Y154137D01*
G01X454852Y156137D02*
X454292Y155577D01*
G01X456785Y156137D02*
X454852D01*
G01X457345Y156697D02*
X456785Y156137D01*
G01X439992Y95754D02*
X438921Y94683D01*
G01X439992Y103312D02*
Y95754D01*
G01X439323Y103981D02*
X439992Y103312D01*
G01X437724Y103981D02*
X439323D01*
G01X437031Y104674D02*
X437724Y103981D01*
G01X437031Y106626D02*
Y104674D01*
G01X437647Y107242D02*
X437031Y106626D01*
G01X439355Y107242D02*
X437647D01*
G01X440015Y107902D02*
X439355Y107242D01*
G01X440015Y109111D02*
Y107902D01*
G01X422064Y95425D02*
X421454Y94815D01*
G01X423042Y95425D02*
X422064D01*
G01X423634Y96017D02*
X423042Y95425D01*
G01X423634Y97007D02*
Y96017D01*
G01X423006Y97635D02*
X423634Y97007D01*
G01X422264Y97635D02*
X423006D01*
G01X421654Y98245D02*
X422264Y97635D01*
G01X421654Y99961D02*
Y98245D01*
G01X423754Y102061D02*
X421654Y99961D01*
G01X423754Y107833D02*
Y102061D01*
G01X462033Y105850D02*
X462833Y105050D01*
G01X460442Y105850D02*
X462033D01*
G01X459392Y106900D02*
X460442Y105850D01*
G01X459392Y115918D02*
Y106900D01*
G01X460192Y116718D02*
X459392Y115918D01*
G01X460992Y116718D02*
X460192D01*
G01X461792Y117518D02*
X460992Y116718D01*
G01X461792Y119118D02*
Y117518D01*
G01X460992Y119918D02*
X461792Y119118D01*
G01X460192Y119918D02*
X460992D01*
G01X459392Y120718D02*
X460192Y119918D01*
G01X459392Y121649D02*
Y120718D01*
G01X427457Y153584D02*
X459392Y121649D01*
G01X427457Y188577D02*
Y153584D01*
G01X422284Y151685D02*
Y189404D01*
G01X435641Y138328D02*
X422284Y151685D01*
G01X435641Y137466D02*
Y138328D01*
G01X433429Y135254D02*
X435641Y137466D01*
G01X433429Y134462D02*
Y135254D01*
G01X434837Y133054D02*
X433429Y134462D01*
G01X435629Y133054D02*
X434837D01*
G01X437841Y135266D02*
X435629Y133054D01*
G01X438703Y135266D02*
X437841D01*
G01X439860Y134109D02*
X438703Y135266D01*
G01X439860Y125781D02*
Y134109D01*
G01X454392Y111249D02*
X439860Y125781D01*
G01X454392Y104200D02*
Y111249D01*
G01X456184Y102408D02*
X454392Y104200D01*
G01X450780Y152322D02*
X483892Y119210D01*
G01X450780Y154295D02*
Y152322D01*
G01X450170Y154905D02*
X450780Y154295D01*
G01X448465Y154905D02*
X450170D01*
G01X447855Y155515D02*
X448465Y154905D01*
G01X447855Y157405D02*
Y155515D01*
G01X461766Y150529D02*
X494295Y118000D01*
G01X461766Y164649D02*
Y150529D01*
G01X454284Y178826D02*
X466251Y166859D01*
G01X454284Y185697D02*
Y178826D01*
G01X467448Y184671D02*
X480680Y171439D01*
G01X467448Y187055D02*
Y184671D01*
G01X440271Y174314D02*
X445320Y169265D01*
G01X440271Y186121D02*
Y174314D01*
G01X424957Y188577D02*
X424519Y188139D01*
G01X456492Y180192D02*
X468656Y168028D01*
G01X456492Y185400D02*
Y180192D01*
G01X437771Y166300D02*
Y158259D01*
G01X438381Y166910D02*
X437771Y166300D01*
G01X439832Y166910D02*
X438381D01*
G01X440392Y167470D02*
X439832Y166910D01*
G01X440392Y169460D02*
Y167470D01*
G01X439832Y170020D02*
X440392Y169460D01*
G01X438381Y170020D02*
X439832D01*
G01X437771Y170630D02*
X438381Y170020D01*
G01X437771Y185879D02*
Y170630D01*
G01X451592Y178463D02*
X463781Y166274D01*
G01X451592Y185669D02*
Y178463D01*
G01X419784Y189404D02*
X419957Y189577D01*
G01X469948Y185280D02*
X483392Y171836D01*
G01X469948Y187055D02*
Y185280D01*
G01X457345Y164714D02*
Y156697D01*
G01X445271Y176788D02*
X457345Y164714D01*
G01X445271Y188577D02*
Y176788D01*
G01X472448Y185478D02*
X486392Y171534D01*
G01X472448Y187055D02*
Y185478D01*
G01X474948Y185980D02*
X488380Y172548D01*
G01X474948Y187055D02*
Y185980D01*
G01X422284Y189404D02*
X422457Y189577D01*
G01X448465Y158015D02*
X447855Y157405D01*
G01X450170Y158015D02*
X448465D01*
G01X450780Y158625D02*
X450170Y158015D01*
G01X450780Y160515D02*
Y158625D01*
G01X450170Y161125D02*
X450780Y160515D01*
G01X448465Y161125D02*
X450170D01*
G01X447855Y161735D02*
X448465Y161125D01*
G01X447855Y163625D02*
Y161735D01*
G01X448465Y164235D02*
X447855Y163625D01*
G01X450170Y164235D02*
X448465D01*
G01X450780Y164845D02*
X450170Y164235D01*
G01X450780Y167835D02*
Y164845D01*
G01X442771Y175844D02*
X450780Y167835D01*
G01X442771Y188577D02*
Y175844D01*
G01X449392Y177023D02*
X461766Y164649D01*
G01X449392Y185848D02*
Y177023D01*
G01X416593Y401566D02*
Y467701D01*
G01X474079Y440287D02*
Y419941D01*
G01X495065Y461273D02*
X474079Y440287D01*
G01X476579Y439187D02*
Y419941D01*
G01X496486Y459094D02*
X476579Y439187D01*
G01X452828Y448691D02*
X490357Y486220D01*
G01X452828Y423264D02*
Y448691D01*
G01X454192Y421900D02*
X452828Y423264D01*
G01X454192Y420160D02*
Y421900D01*
G01X426139Y459519D02*
X440940Y474320D01*
G01X426139Y413466D02*
Y459519D01*
G01X426372Y413233D02*
X426139Y413466D01*
G01X440992Y453188D02*
X478414Y490610D01*
G01X440992Y415900D02*
Y453188D01*
G01X442092Y414800D02*
X440992Y415900D01*
G01X442092Y406930D02*
Y414800D01*
G01X442381Y406641D02*
X442092Y406930D01*
G01X456473Y448800D02*
X490877Y483204D01*
G01X456473Y420405D02*
Y448800D01*
G01X469079Y442487D02*
X495325Y468733D01*
G01X469079Y421025D02*
Y442487D01*
G01X421139Y411271D02*
Y466138D01*
G01X421372Y411038D02*
X421139Y411271D01*
G01X446328Y451714D02*
X485890Y491276D01*
G01X446328Y417064D02*
Y451714D01*
G01X449392Y414000D02*
X446328Y417064D01*
G01X449392Y406860D02*
Y414000D01*
G01X449023Y406491D02*
X449392Y406860D01*
G01X458973Y447764D02*
X491507Y480298D01*
G01X458973Y420405D02*
Y447764D01*
G01X428714Y458519D02*
X445606Y475411D01*
G01X428714Y413391D02*
Y458519D01*
G01X428872Y413233D02*
X428714Y413391D01*
G01X450328Y449727D02*
X488901Y488300D01*
G01X450328Y421086D02*
Y449727D01*
G01X451473Y419941D02*
X450328Y421086D01*
G01X438492Y454224D02*
X474046Y489778D01*
G01X438492Y415400D02*
Y454224D01*
G01X439592Y414300D02*
X438492Y415400D01*
G01X439592Y406970D02*
Y414300D01*
G01X439921Y406641D02*
X439592Y406970D01*
G01X423639Y410880D02*
Y465354D01*
G01X423872Y410647D02*
X423639Y410880D01*
G01X443492Y452426D02*
X481420Y490354D01*
G01X443492Y416900D02*
Y452426D01*
G01X444792Y415600D02*
X443492Y416900D01*
G01X444792Y407081D02*
Y415600D01*
G01X444881Y406992D02*
X444792Y407081D01*
G01X471579Y441587D02*
Y421025D01*
G01X493752Y463760D02*
X471579Y441587D01*
G01X430695Y523332D02*
Y526822D01*
G01X429992Y522629D02*
X430695Y523332D01*
G01X429992Y517000D02*
Y522629D01*
G01X429692Y516700D02*
X429992Y517000D01*
G01X429692Y514600D02*
Y516700D01*
G01X430398Y513894D02*
X429692Y514600D01*
G01X430398Y511506D02*
Y513894D01*
G01X429777Y510885D02*
X430398Y511506D01*
G01X429777Y509015D02*
Y510885D01*
G01X430492Y508300D02*
X429777Y509015D01*
G01X430492Y501599D02*
Y508300D01*
G01X459992Y519441D02*
Y527900D01*
G01X460333Y519100D02*
X459992Y519441D01*
G01X460333Y517657D02*
Y519100D01*
G01X458983Y516307D02*
X460333Y517657D01*
G01X458983Y512057D02*
Y516307D01*
G01X460333Y510707D02*
X458983Y512057D01*
G01X460333Y509441D02*
Y510707D01*
G01X457554Y506662D02*
X460333Y509441D01*
G01X457554Y495463D02*
Y506662D01*
G01X440940Y478849D02*
X457554Y495463D01*
G01X440940Y474320D02*
Y478849D01*
G01X417449Y517857D02*
Y520543D01*
G01X416692Y511800D02*
Y513900D01*
G01Y499789D02*
Y508500D01*
G01X476476Y505944D02*
X479733Y509201D01*
G01X476476Y503877D02*
Y505944D01*
G01X477086Y503267D02*
X476476Y503877D01*
G01X478604Y503267D02*
X477086D01*
G01Y500657D02*
X478604D01*
G01X476476Y500047D02*
X477086Y500657D01*
G01X476476Y498657D02*
Y500047D01*
G01X477086Y498047D02*
X476476Y498657D01*
G01X478604Y498047D02*
X477086D01*
G01Y495437D02*
X478604D01*
G01X476476Y494827D02*
X477086Y495437D01*
G01X476476Y493437D02*
Y494827D01*
G01X477086Y492827D02*
X476476Y493437D01*
G01X477904Y492827D02*
X477086D01*
G01X478414Y492317D02*
X477904Y492827D01*
G01X453292Y519741D02*
Y527800D01*
G01X453533Y519500D02*
X453292Y519741D01*
G01X453533Y517357D02*
Y519500D01*
G01X452633Y516457D02*
X453533Y517357D01*
G01X452633Y511797D02*
Y516457D01*
G01X453533Y510897D02*
X452633Y511797D01*
G01X453533Y509200D02*
Y510897D01*
G01X451974Y507641D02*
X453533Y509200D01*
G01X451974Y496973D02*
Y507641D01*
G01X421139Y466138D02*
X451974Y496973D01*
G01X426543Y519351D02*
Y535351D01*
G01X426192Y519000D02*
X426543Y519351D01*
G01X426192Y517110D02*
Y519000D01*
G01X426692Y516610D02*
X426192Y517110D01*
G01X426692Y514247D02*
Y516610D01*
G01X428147Y512792D02*
X426692Y514247D01*
G01X428147Y510145D02*
Y512792D01*
G01X425254Y507252D02*
X428147Y510145D01*
G01X423536Y507252D02*
X425254D01*
G01X422852Y506568D02*
X423536Y507252D01*
G01X422852Y504736D02*
Y506568D01*
G01X423536Y504052D02*
X422852Y504736D01*
G01X425250Y504052D02*
X423536D01*
G01X425939Y503363D02*
X425250Y504052D01*
G01X425939Y501681D02*
Y503363D01*
G01X443263Y519329D02*
Y530371D01*
G01X443692Y518900D02*
X443263Y519329D01*
G01X443692Y517100D02*
Y518900D01*
G01X442992Y516400D02*
X443692Y517100D01*
G01X442992Y514300D02*
Y516400D01*
G01X443692Y513600D02*
X442992Y514300D01*
G01X443692Y512200D02*
Y513600D01*
G01X442892Y511400D02*
X443692Y512200D01*
G01X442892Y509198D02*
Y511400D01*
G01X443211Y508879D02*
X442892Y509198D01*
G01X443211Y497220D02*
Y508879D01*
G01X433214Y519222D02*
Y530278D01*
G01X433032Y519040D02*
X433214Y519222D01*
G01X433032Y516460D02*
Y519040D01*
G01X433391Y516101D02*
X433032Y516460D01*
G01X433391Y514299D02*
Y516101D01*
G01X432964Y513872D02*
X433391Y514299D01*
G01X432964Y511328D02*
Y513872D01*
G01X433392Y510900D02*
X432964Y511328D01*
G01X433392Y501670D02*
Y510900D01*
G01X429406Y497684D02*
X433392Y501670D01*
G01X429406Y497683D02*
Y497684D01*
G01X446485Y518007D02*
Y531205D01*
G01X446892Y517600D02*
X446485Y518007D01*
G01X446892Y514800D02*
Y517600D01*
G01X445892Y513800D02*
X446892Y514800D01*
G01X445892Y511800D02*
Y513800D01*
G01X446892Y510800D02*
X445892Y511800D01*
G01X446892Y498000D02*
Y510800D01*
G01X416593Y467701D02*
X446892Y498000D01*
G01X463292Y519059D02*
Y528100D01*
G01X462833Y518600D02*
X463292Y519059D01*
G01X462833Y509359D02*
Y518600D01*
G01X463992Y508200D02*
X462833Y509359D01*
G01X463992Y506551D02*
Y508200D01*
G01X463382Y505941D02*
X463992Y506551D01*
G01X460900Y505941D02*
X463382D01*
G01X460290Y505331D02*
X460900Y505941D01*
G01X460290Y503351D02*
Y505331D01*
G01X460900Y502741D02*
X460290Y503351D01*
G01X463382Y502741D02*
X460900D01*
G01X463992Y502131D02*
X463382Y502741D01*
G01X463992Y500151D02*
Y502131D01*
G01X463382Y499541D02*
X463992Y500151D01*
G01X460900Y499541D02*
X463382D01*
G01X460290Y498931D02*
X460900Y499541D01*
G01X460290Y496951D02*
Y498931D01*
G01X460645Y496596D02*
X460290Y496951D01*
G01X460645Y495888D02*
Y496596D01*
G01X450494Y485737D02*
X460645Y495888D01*
G01X450494Y480299D02*
Y485737D01*
G01X448314Y478119D02*
X450494Y480299D01*
G01X447452Y478119D02*
X448314D01*
G01X445746Y479826D02*
X447452Y478119D01*
G01X444884Y479826D02*
X445746D01*
G01X443900Y478842D02*
X444884Y479826D01*
G01X443900Y477980D02*
Y478842D01*
G01X445606Y476273D02*
X443900Y477980D01*
G01X445606Y475411D02*
Y476273D01*
G01X439825Y519233D02*
Y530067D01*
G01X439692Y519100D02*
X439825Y519233D01*
G01X439692Y516700D02*
Y519100D01*
G01X439992Y516400D02*
X439692Y516700D01*
G01X439992Y514300D02*
Y516400D01*
G01X438187Y512495D02*
X439992Y514300D01*
G01X438187Y510114D02*
Y512495D01*
G01X439992Y508309D02*
X438187Y510114D01*
G01X439992Y498528D02*
Y508309D01*
G01X435482Y525002D02*
Y526835D01*
G01X436092Y524392D02*
X435482Y525002D01*
G01X437103Y524392D02*
X436092D01*
G01X437740Y523755D02*
X437103Y524392D01*
G01X437740Y522765D02*
Y523755D01*
G01X437157Y522182D02*
X437740Y522765D01*
G01X436162Y522182D02*
X437157D01*
G01X435524Y521544D02*
X436162Y522182D01*
G01X435524Y520265D02*
Y521544D01*
G01X436140Y519649D02*
X435524Y520265D01*
G01X437251Y519649D02*
X436140D01*
G01X437859Y519041D02*
X437251Y519649D01*
G01X437859Y517977D02*
Y519041D01*
G01X435679Y515797D02*
X437859Y517977D01*
G01X435679Y514387D02*
Y515797D01*
G01X434840Y513548D02*
X435679Y514387D01*
G01X434840Y512792D02*
Y513548D01*
G01X436292Y511340D02*
X434840Y512792D01*
G01X436292Y505952D02*
Y511340D01*
G01X437088Y505156D02*
X436292Y505952D01*
G01X437088Y498453D02*
Y505156D01*
G01X434235Y495600D02*
X437088Y498453D01*
G01X432206Y495600D02*
X434235D01*
G01X430031Y493425D02*
X432206Y495600D01*
G01X430031Y491396D02*
Y493425D01*
G01X428688Y490053D02*
X430031Y491396D01*
G01X427558Y490053D02*
X428688D01*
G01X426848Y490054D02*
X427558Y490053D01*
G01X425505Y488711D02*
X426848Y490054D01*
G01X425505Y486870D02*
Y488711D01*
G01X424162Y485527D02*
X425505Y486870D01*
G01X422743Y485527D02*
X424162D01*
G01X420979Y483763D02*
X422743Y485527D01*
G01X420979Y482344D02*
Y483763D01*
G01X419636Y481001D02*
X420979Y482344D01*
G01X418506Y481001D02*
X419636D01*
G01X417796Y481002D02*
X418506Y481001D01*
G01X416453Y477818D02*
Y479659D01*
G01X476833Y517357D02*
Y529842D01*
G01X476433Y516957D02*
X476833Y517357D01*
G01X476433Y512057D02*
Y516957D01*
G01X476783Y511707D02*
X476433Y512057D01*
G01X476783Y509435D02*
Y511707D01*
G01X474046Y506698D02*
X476783Y509435D01*
G01X474046Y489778D02*
Y506698D01*
G01X456592Y519799D02*
Y527500D01*
G01X455792Y518999D02*
X456592Y519799D01*
G01X455792Y517500D02*
Y518999D01*
G01X457092Y516200D02*
X455792Y517500D01*
G01X457092Y512356D02*
Y516200D01*
G01X456233Y511497D02*
X457092Y512356D01*
G01X456233Y509159D02*
Y511497D01*
G01X454672Y507598D02*
X456233Y509159D01*
G01X454672Y496387D02*
Y507598D01*
G01X435709Y477424D02*
X454672Y496387D01*
G01X435709Y476562D02*
Y477424D01*
G01X436948Y475323D02*
X435709Y476562D01*
G01X436948Y474461D02*
Y475323D01*
G01X435964Y473477D02*
X436948Y474461D01*
G01X435102Y473477D02*
X435964D01*
G01X433863Y474716D02*
X435102Y473477D01*
G01X433001Y474716D02*
X433863D01*
G01X432017Y473732D02*
X433001Y474716D01*
G01X432017Y472870D02*
Y473732D01*
G01X433256Y471631D02*
X432017Y472870D01*
G01X433256Y470769D02*
Y471631D01*
G01X432272Y469785D02*
X433256Y470769D01*
G01X431410Y469785D02*
X432272D01*
G01X430171Y471024D02*
X431410Y469785D01*
G01X429309Y471024D02*
X430171D01*
G01X423639Y465354D02*
X429309Y471024D01*
G01X419032Y525715D02*
Y526598D01*
G01X420122Y524625D02*
X419032Y525715D01*
G01X421272Y524625D02*
X420122D01*
G01X422521Y525874D02*
X421272Y524625D01*
G01X423728Y525874D02*
X422521D01*
G01X424711Y524891D02*
X423728Y525874D01*
G01X424711Y522795D02*
Y524891D01*
G01X423341Y521425D02*
X424711Y522795D01*
G01X420754Y521425D02*
X423341D01*
G01X419762Y520433D02*
X420754Y521425D01*
G01X419762Y518988D02*
Y520433D01*
G01X420593Y518157D02*
X419762Y518988D01*
G01X421454Y518157D02*
X420593D01*
G01X421454Y515738D02*
Y518157D01*
G01X423204Y513988D02*
X421454Y515738D01*
G01X423204Y511912D02*
Y513988D01*
G01X420666Y509374D02*
X423204Y511912D01*
G01X420666Y499237D02*
Y509374D01*
G01X434842Y572750D02*
Y574757D01*
G01X435271Y572321D02*
X434842Y572750D01*
G01X435271Y569591D02*
Y572321D01*
G01X433236Y567556D02*
X435271Y569591D01*
G01X433236Y560438D02*
Y567556D01*
G01X433119Y560321D02*
X433236Y560438D01*
G01X433119Y555081D02*
Y560321D01*
G01X435232Y552968D02*
X433119Y555081D01*
G01X435232Y548312D02*
Y552968D01*
G01X434842Y547922D02*
X435232Y548312D01*
G01X429761Y542841D02*
X434842Y547922D01*
G01X429761Y527756D02*
Y542841D01*
G01X430695Y526822D02*
X429761Y527756D01*
G01X428149Y585722D02*
Y590657D01*
G01X426958Y584531D02*
X428149Y585722D01*
G01X426958Y583275D02*
Y584531D01*
G01X428752Y581481D02*
X426958Y583275D01*
G01X428752Y580307D02*
Y581481D01*
G01X427281Y578836D02*
X428752Y580307D01*
G01X426110Y578836D02*
X427281D01*
G01X424176Y580770D02*
X426110Y578836D01*
G01X422819Y580770D02*
X424176D01*
G01X421213Y579164D02*
X422819Y580770D01*
G01X421213Y577924D02*
Y579164D01*
G01X423090Y576047D02*
X421213Y577924D01*
G01X423090Y573970D02*
Y576047D01*
G01X421870Y572750D02*
X423090Y573970D01*
G01X419505Y572750D02*
X421870D01*
G01X460183Y586457D02*
X456833Y589807D01*
G01X460183Y584891D02*
Y586457D01*
G01X459892Y584600D02*
X460183Y584891D01*
G01X459892Y575891D02*
Y584600D01*
G01X460183Y575600D02*
X459892Y575891D01*
G01X460183Y574291D02*
Y575600D01*
G01X459033Y573141D02*
X460183Y574291D01*
G01X459033Y568359D02*
Y573141D01*
G01X460133Y567259D02*
X459033Y568359D01*
G01X460133Y566041D02*
Y567259D01*
G01X459892Y565800D02*
X460133Y566041D01*
G01X459892Y557541D02*
Y565800D01*
G01X460133Y557300D02*
X459892Y557541D01*
G01X460133Y555257D02*
Y557300D01*
G01X458983Y554107D02*
X460133Y555257D01*
G01X458983Y549857D02*
Y554107D01*
G01X460333Y548507D02*
X458983Y549857D01*
G01X460333Y547141D02*
Y548507D01*
G01X459992Y546800D02*
X460333Y547141D01*
G01X459992Y538601D02*
Y546800D01*
G01X460333Y538260D02*
X459992Y538601D01*
G01X460333Y536640D02*
Y538260D01*
G01X458983Y535290D02*
X460333Y536640D01*
G01X458983Y530608D02*
Y535290D01*
G01X460333Y529258D02*
X458983Y530608D01*
G01X460333Y528241D02*
Y529258D01*
G01X459992Y527900D02*
X460333Y528241D01*
G01X428147Y574755D02*
X428149Y574757D01*
G01X428147Y569683D02*
Y574755D01*
G01X429761Y568069D02*
X428147Y569683D01*
G01X429761Y557231D02*
Y568069D01*
G01X429878Y557114D02*
X429761Y557231D01*
G01X429878Y549651D02*
Y557114D01*
G01X428149Y547922D02*
X429878Y549651D01*
G01X426005Y545778D02*
X428149Y547922D01*
G01X421592Y545778D02*
X426005D01*
G01X419843Y544029D02*
X421592Y545778D01*
G01X419843Y542838D02*
Y544029D01*
G01X420453Y542228D02*
X419843Y542838D01*
G01X422846Y542228D02*
X420453D01*
G01X423497Y541577D02*
X422846Y542228D01*
G01X423497Y540187D02*
Y541577D01*
G01X422928Y539618D02*
X423497Y540187D01*
G01X420835Y539618D02*
X422928D01*
G01X419843Y538626D02*
X420835Y539618D01*
G01X419843Y535537D02*
Y538626D01*
G01X418873Y534567D02*
X419843Y535537D01*
G01X418873Y532381D02*
Y534567D01*
G01X453483Y586457D02*
X450492Y589448D01*
G01X453483Y584991D02*
Y586457D01*
G01X453292Y584800D02*
X453483Y584991D01*
G01X453292Y575691D02*
Y584800D01*
G01X453483Y575500D02*
X453292Y575691D01*
G01X453483Y573942D02*
Y575500D01*
G01X452485Y572944D02*
X453483Y573942D01*
G01X452485Y568207D02*
Y572944D01*
G01X453533Y567159D02*
X452485Y568207D01*
G01X453533Y565941D02*
Y567159D01*
G01X453192Y565600D02*
X453533Y565941D01*
G01X453192Y557641D02*
Y565600D01*
G01X453533Y557300D02*
X453192Y557641D01*
G01X453533Y555157D02*
Y557300D01*
G01X452633Y554257D02*
X453533Y555157D01*
G01X452633Y549557D02*
Y554257D01*
G01X453633Y548557D02*
X452633Y549557D01*
G01X453633Y546841D02*
Y548557D01*
G01X453292Y546500D02*
X453633Y546841D01*
G01X453292Y538241D02*
Y546500D01*
G01X453633Y537900D02*
X453292Y538241D01*
G01X453633Y536242D02*
Y537900D01*
G01X452633Y535242D02*
X453633Y536242D01*
G01X452633Y530258D02*
Y535242D01*
G01X453533Y529358D02*
X452633Y530258D01*
G01X453533Y528041D02*
Y529358D01*
G01X453292Y527800D02*
X453533Y528041D01*
G01X426543Y535351D02*
X428149Y536957D01*
G01X434842Y587910D02*
X435270Y588338D01*
G01X434842Y585722D02*
Y587910D01*
G01X439810Y580754D02*
X434842Y585722D01*
G01X439810Y573782D02*
Y580754D01*
G01X443247Y570345D02*
X439810Y573782D01*
G01X443247Y535855D02*
Y570345D01*
G01X442992Y535600D02*
X443247Y535855D01*
G01X442992Y533200D02*
Y535600D01*
G01X443692Y532500D02*
X442992Y533200D01*
G01X443692Y530800D02*
Y532500D01*
G01X443263Y530371D02*
X443692Y530800D01*
G01X438187Y574755D02*
X438189Y574757D01*
G01X438187Y569519D02*
Y574755D01*
G01X436578Y567910D02*
X438187Y569519D01*
G01X436578Y565673D02*
Y567910D01*
G01X437421Y564830D02*
X436578Y565673D01*
G01X437421Y561318D02*
Y564830D01*
G01X436578Y560475D02*
X437421Y561318D01*
G01X436578Y554796D02*
Y560475D01*
G01X438187Y553187D02*
X436578Y554796D01*
G01X438187Y547924D02*
Y553187D01*
G01X438189Y547922D02*
X438187Y547924D01*
G01X438189Y546172D02*
Y547922D01*
G01X433228Y541211D02*
X438189Y546172D01*
G01X433228Y535664D02*
Y541211D01*
G01X431788Y534224D02*
X433228Y535664D01*
G01X431788Y531704D02*
Y534224D01*
G01X433214Y530278D02*
X431788Y531704D01*
G01X421456Y564972D02*
Y566822D01*
G01X422066Y564362D02*
X421456Y564972D01*
G01X425908Y564362D02*
X422066D01*
G01X426518Y563752D02*
X425908Y564362D01*
G01X426518Y562762D02*
Y563752D01*
G01X425908Y562152D02*
X426518Y562762D01*
G01X422066Y562152D02*
X425908D01*
G01X421456Y561542D02*
X422066Y562152D01*
G01X421456Y560552D02*
Y561542D01*
G01X422066Y559942D02*
X421456Y560552D01*
G01X425804Y559942D02*
X422066D01*
G01X426393Y559353D02*
X425804Y559942D01*
G01X426393Y558363D02*
Y559353D01*
G01X425762Y557732D02*
X426393Y558363D01*
G01X422066Y557732D02*
X425762D01*
G01X421456Y557122D02*
X422066Y557732D01*
G01X421456Y555857D02*
Y557122D01*
G01X419392Y553793D02*
X421456Y555857D01*
G01X419392Y549700D02*
Y553793D01*
G01X419829Y549263D02*
X419392Y549700D01*
G01X419829Y546997D02*
Y549263D01*
G01X446509Y577402D02*
X438189Y585722D01*
G01X446509Y567783D02*
Y577402D01*
G01X446992Y567300D02*
X446509Y567783D01*
G01X446992Y557300D02*
Y567300D01*
G01X446671Y556979D02*
X446992Y557300D01*
G01X446671Y552079D02*
Y556979D01*
G01X446366Y551774D02*
X446671Y552079D01*
G01X446366Y549026D02*
Y551774D01*
G01X446892Y548500D02*
X446366Y549026D01*
G01X446892Y538600D02*
Y548500D01*
G01X446592Y538300D02*
X446892Y538600D01*
G01X446592Y531312D02*
Y538300D01*
G01X446485Y531205D02*
X446592Y531312D01*
G01X438187Y585724D02*
X438189Y585722D01*
G01X438187Y587895D02*
Y585724D01*
G01X439810Y589518D02*
X438187Y587895D01*
G01X462833Y586443D02*
X460912Y588364D01*
G01X462833Y584759D02*
Y586443D01*
G01X463292Y584300D02*
X462833Y584759D01*
G01X463292Y575959D02*
Y584300D01*
G01X462833Y575500D02*
X463292Y575959D01*
G01X462833Y565759D02*
Y575500D01*
G01X463292Y565300D02*
X462833Y565759D01*
G01X463292Y556999D02*
Y565300D01*
G01X462833Y556540D02*
X463292Y556999D01*
G01X462833Y546459D02*
Y556540D01*
G01X463292Y546000D02*
X462833Y546459D01*
G01X463292Y538159D02*
Y546000D01*
G01X462833Y537700D02*
X463292Y538159D01*
G01X462833Y528559D02*
Y537700D01*
G01X463292Y528100D02*
X462833Y528559D01*
G01X439592Y535554D02*
X438189Y536957D01*
G01X439592Y530300D02*
Y535554D01*
G01X439825Y530067D02*
X439592Y530300D01*
G01X436475Y535324D02*
X434842Y536957D01*
G01X436475Y527828D02*
Y535324D01*
G01X435482Y526835D02*
X436475Y527828D01*
G01X476840Y586750D02*
X474565Y589025D01*
G01X476840Y573849D02*
Y586750D01*
G01X475960Y572969D02*
X476840Y573849D01*
G01X475960Y568470D02*
Y572969D01*
G01X477033Y567397D02*
X475960Y568470D01*
G01X477033Y555357D02*
Y567397D01*
G01X476433Y554757D02*
X477033Y555357D01*
G01X476433Y549857D02*
Y554757D01*
G01X476895Y549395D02*
X476433Y549857D01*
G01X476895Y536404D02*
Y549395D01*
G01X476433Y535942D02*
X476895Y536404D01*
G01X476433Y530242D02*
Y535942D01*
G01X476833Y529842D02*
X476433Y530242D01*
G01X456133Y587200D02*
X454619Y588714D01*
G01X456133Y584959D02*
Y587200D01*
G01X456592Y584500D02*
X456133Y584959D01*
G01X456592Y575859D02*
Y584500D01*
G01X456133Y575400D02*
X456592Y575859D01*
G01X456133Y573256D02*
Y575400D01*
G01X456733Y572656D02*
X456133Y573256D01*
G01X456733Y568497D02*
Y572656D01*
G01X456233Y567997D02*
X456733Y568497D01*
G01X456233Y565859D02*
Y567997D01*
G01X456592Y565500D02*
X456233Y565859D01*
G01X456592Y557699D02*
Y565500D01*
G01X455878Y556985D02*
X456592Y557699D01*
G01X455878Y554814D02*
Y556985D01*
G01X456792Y553900D02*
X455878Y554814D01*
G01X456792Y549800D02*
Y553900D01*
G01X455892Y548900D02*
X456792Y549800D01*
G01X455892Y546900D02*
Y548900D01*
G01X456592Y546200D02*
X455892Y546900D01*
G01X456592Y538199D02*
Y546200D01*
G01X456028Y537635D02*
X456592Y538199D01*
G01X456028Y536263D02*
Y537635D01*
G01X456792Y535499D02*
X456028Y536263D01*
G01X456792Y530499D02*
Y535499D01*
G01X455933Y529640D02*
X456792Y530499D01*
G01X455933Y528159D02*
Y529640D01*
G01X456592Y527500D02*
X455933Y528159D01*
G01X419032Y526598D02*
X421456Y529022D01*
G01X428147Y610245D02*
Y612657D01*
G01X430011Y608381D02*
X428147Y610245D01*
G01X430011Y606119D02*
Y608381D01*
G01X428692Y604800D02*
X430011Y606119D01*
G01X428692Y596200D02*
Y604800D01*
G01X429864Y595028D02*
X428692Y596200D01*
G01X429864Y592372D02*
Y595028D01*
G01X428149Y590657D02*
X429864Y592372D01*
G01X459746Y610300D02*
X460912D01*
G01X456561Y607115D02*
X459746Y610300D01*
G01X456561Y595462D02*
Y607115D01*
G01X458266Y593757D02*
X456561Y595462D01*
G01X456833Y592324D02*
X458266Y593757D01*
G01X456833Y589807D02*
Y592324D01*
G01X422786Y605960D02*
X421454Y607292D01*
G01X422786Y601823D02*
Y605960D01*
G01X421728Y600765D02*
X422786Y601823D01*
G01X421454Y596531D02*
X420420Y597565D01*
G01X421454Y593659D02*
Y596531D01*
G01X421456Y593657D02*
X421454Y593659D01*
G01X476070Y604499D02*
X474998D01*
G01X476770Y603799D02*
X476070Y604499D01*
G01X476770Y602525D02*
Y603799D01*
G01X475633Y601388D02*
X476770Y602525D01*
G01X475633Y600312D02*
Y601388D01*
G01X475818Y600126D02*
X475633Y600312D01*
G01X476645Y599300D02*
X475818Y600126D01*
G01X476645Y598100D02*
Y599300D01*
G01X475633Y597088D02*
X476645Y598100D01*
G01X475633Y596012D02*
Y597088D01*
G01X476745Y594900D02*
X475633Y596012D01*
G01X476745Y592267D02*
Y594900D01*
G01X476570Y592092D02*
X476745Y592267D01*
G01X476570Y590400D02*
Y592092D01*
G01X478256Y588714D02*
X476570Y590400D01*
G01X453545Y610300D02*
X454533D01*
G01X450490Y607245D02*
X453545Y610300D01*
G01X450490Y606057D02*
Y607245D01*
G01X449868Y605435D02*
X450490Y606057D01*
G01X449868Y595462D02*
Y605435D01*
G01X451573Y593757D02*
X449868Y595462D01*
G01X450492Y592676D02*
X451573Y593757D01*
G01X450492Y589448D02*
Y592676D01*
G01X434840Y610248D02*
Y612657D01*
G01X433038Y608446D02*
X434840Y610248D01*
G01X433038Y606054D02*
Y608446D01*
G01X433414Y605678D02*
X433038Y606054D01*
G01X433414Y595222D02*
Y605678D01*
G01X433126Y594934D02*
X433414Y595222D01*
G01X433126Y592768D02*
Y594934D01*
G01X435270Y590624D02*
X433126Y592768D01*
G01X435270Y588338D02*
Y590624D01*
G01X439810Y594618D02*
Y589518D01*
G01X440692Y595500D02*
X439810Y594618D01*
G01X440692Y604900D02*
Y595500D01*
G01X438187Y607405D02*
X440692Y604900D01*
G01X438187Y609864D02*
Y607405D01*
G01X459246Y604499D02*
X458266D01*
G01X459845Y603900D02*
X459246Y604499D01*
G01X459845Y602700D02*
Y603900D01*
G01X458901Y601756D02*
X459845Y602700D01*
G01X458901Y600544D02*
Y601756D01*
G01X459745Y599700D02*
X458901Y600544D01*
G01X459745Y598000D02*
Y599700D01*
G01X458901Y597156D02*
X459745Y598000D01*
G01X458901Y595736D02*
Y597156D01*
G01X460045Y594592D02*
X458901Y595736D01*
G01X460045Y592999D02*
Y594592D01*
G01X459138Y592092D02*
X460045Y592999D01*
G01X459138Y590400D02*
Y592092D01*
G01X460824Y588714D02*
X459138Y590400D01*
G01X460912Y588714D02*
X460824D01*
G01X460912Y588364D02*
Y588714D01*
G01X473293Y605649D02*
X478344Y610700D01*
G01X473293Y595462D02*
Y605649D01*
G01X474998Y593757D02*
X473293Y595462D01*
G01X474565Y593324D02*
X474998Y593757D01*
G01X474565Y589025D02*
Y593324D01*
G01X452645Y604499D02*
X451573D01*
G01X453245Y603899D02*
X452645Y604499D01*
G01X453245Y603001D02*
Y603899D01*
G01X452208Y601964D02*
X453245Y603001D01*
G01X452208Y600736D02*
Y601964D01*
G01X453145Y599799D02*
X452208Y600736D01*
G01X453145Y598401D02*
Y599799D01*
G01X452208Y597464D02*
X453145Y598401D01*
G01X452208Y596136D02*
Y597464D01*
G01X453345Y594999D02*
X452208Y596136D01*
G01X453345Y593100D02*
Y594999D01*
G01X452845Y592600D02*
X453345Y593100D01*
G01X452845Y590400D02*
Y592600D01*
G01X454531Y588714D02*
X452845Y590400D01*
G01X454619Y588714D02*
X454531D01*
G01X496856Y-3233D02*
X497723Y-4100D01*
G01X496856Y-932D02*
Y-3233D01*
G01X495223Y701D02*
X496856Y-932D01*
G01X495223Y2000D02*
Y701D01*
G01X496573Y3350D02*
X495223Y2000D01*
G01X496573Y4250D02*
Y3350D01*
G01X495323Y5500D02*
X496573Y4250D01*
G01X495323Y6699D02*
Y5500D01*
G01X496856Y8232D02*
X495323Y6699D01*
G01X496856Y10200D02*
Y8232D01*
G01X493956Y13100D02*
X496856Y10200D01*
G01X493956Y16036D02*
Y13100D01*
G01X495077Y17157D02*
X493956Y16036D01*
G01X513056Y-8654D02*
X511809Y-9901D01*
G01X513056Y-7400D02*
Y-8654D01*
G01X514356Y-6100D02*
X513056Y-7400D01*
G01X515356Y-6100D02*
X514356D01*
G01X517156Y-4300D02*
X515356Y-6100D01*
G01X517156Y-2900D02*
Y-4300D01*
G01X516544Y-2288D02*
X517156Y-2900D01*
G01X516544Y10725D02*
Y-2288D01*
G01X515155Y12114D02*
X516544Y10725D01*
G01X489492Y29007D02*
X488384Y27899D01*
G01X489492Y30561D02*
Y29007D01*
G01X490631Y31700D02*
X489492Y30561D01*
G01X491855Y31700D02*
X490631D01*
G01X493431Y33276D02*
X491855Y31700D01*
G01X533667Y-3233D02*
X534534Y-4100D01*
G01X533667Y-932D02*
Y-3233D01*
G01X532034Y701D02*
X533667Y-932D01*
G01X532034Y2000D02*
Y701D01*
G01X533384Y3350D02*
X532034Y2000D01*
G01X533384Y4250D02*
Y3350D01*
G01X532134Y5500D02*
X533384Y4250D01*
G01X532134Y6699D02*
Y5500D01*
G01X533667Y8232D02*
X532134Y6699D01*
G01X533667Y10200D02*
Y8232D01*
G01X530767Y13100D02*
X533667Y10200D01*
G01X530767Y16036D02*
Y13100D01*
G01X531888Y17157D02*
X530767Y16036D01*
G01X531888Y24796D02*
Y17157D01*
G01X533755Y26663D02*
X531888Y24796D01*
G01X533755Y28444D02*
Y26663D01*
G01X532605Y29594D02*
X533755Y28444D01*
G01X532605Y34213D02*
Y29594D01*
G01X490256Y-3012D02*
X491344Y-4100D01*
G01X490256Y-1132D02*
Y-3012D01*
G01X488823Y301D02*
X490256Y-1132D01*
G01X488823Y1500D02*
Y301D01*
G01X490323Y3000D02*
X488823Y1500D01*
G01X490323Y4200D02*
Y3000D01*
G01X488873Y5650D02*
X490323Y4200D01*
G01X488873Y7049D02*
Y5650D01*
G01X490256Y8432D02*
X488873Y7049D01*
G01X490256Y10301D02*
Y8432D01*
G01X487456Y13101D02*
X490256Y10301D01*
G01X487456Y16229D02*
Y13101D01*
G01X488384Y17157D02*
X487456Y16229D01*
G01X498356Y31900D02*
X499812Y33356D01*
G01X496956Y31900D02*
X498356D01*
G01X495077Y30021D02*
X496956Y31900D01*
G01X495077Y27899D02*
Y30021D01*
G01X515356Y31700D02*
X517156Y33500D01*
G01X514356Y31700D02*
X515356D01*
G01X513056Y30400D02*
X514356Y31700D01*
G01X513056Y29146D02*
Y30400D01*
G01X511809Y27899D02*
X513056Y29146D01*
G01X480345Y-4300D02*
X478545Y-6100D01*
G01X480345Y-2900D02*
Y-4300D01*
G01X479733Y-2288D02*
X480345Y-2900D01*
G01X479733Y10725D02*
Y-2288D01*
G01X478344Y12114D02*
X479733Y10725D01*
G01X479792Y28658D02*
Y18809D01*
G01X480633Y29499D02*
X479792Y28658D01*
G01X480633Y34359D02*
Y29499D01*
G01X519749Y29146D02*
X518502Y27899D01*
G01X519749Y30400D02*
Y29146D01*
G01X521049Y31700D02*
X519749Y30400D01*
G01X522049Y31700D02*
X521049D01*
G01X523849Y33500D02*
X522049Y31700D01*
G01X523237Y10725D02*
X521848Y12114D01*
G01X523237Y-2288D02*
Y10725D01*
G01X523849Y-2900D02*
X523237Y-2288D01*
G01X523849Y-4300D02*
Y-2900D01*
G01X522049Y-6100D02*
X523849Y-4300D01*
G01X521049Y-6100D02*
X522049D01*
G01X519749Y-7400D02*
X521049Y-6100D01*
G01X519749Y-8654D02*
Y-7400D01*
G01X518502Y-9901D02*
X519749Y-8654D01*
G01X531888Y-7779D02*
Y-9901D01*
G01X533767Y-5900D02*
X531888Y-7779D01*
G01X535167Y-5900D02*
X533767D01*
G01X536623Y-4444D02*
X535167Y-5900D01*
G01X536623Y-3100D02*
Y-4444D01*
G01X536007Y-2484D02*
X536623Y-3100D01*
G01X536007Y10641D02*
Y-2484D01*
G01X534534Y12114D02*
X536007Y10641D01*
G01X532461Y14187D02*
X534534Y12114D01*
G01X532461Y15168D02*
Y14187D01*
G01X533955Y16662D02*
X532461Y15168D01*
G01X533955Y23363D02*
Y16662D01*
G01X536455Y25863D02*
X533955Y23363D01*
G01X536455Y74863D02*
Y25863D01*
G01X513681Y-2226D02*
X515155Y-3700D01*
G01X513681Y-1132D02*
Y-2226D01*
G01X512248Y301D02*
X513681Y-1132D01*
G01X512248Y1524D02*
Y301D01*
G01X513748Y3024D02*
X512248Y1524D01*
G01X513748Y4376D02*
Y3024D01*
G01X512248Y5876D02*
X513748Y4376D01*
G01X512248Y6999D02*
Y5876D01*
G01X513923Y8674D02*
X512248Y6999D01*
G01X513923Y10059D02*
Y8674D01*
G01X510881Y13101D02*
X513923Y10059D01*
G01X510881Y16229D02*
Y13101D01*
G01X511809Y17157D02*
X510881Y16229D01*
G01X525195Y-8347D02*
Y-9901D01*
G01X527442Y-6100D02*
X525195Y-8347D01*
G01X528666Y-6100D02*
X527442D01*
G01X530242Y-4524D02*
X528666Y-6100D01*
G01X530242Y-2900D02*
Y-4524D01*
G01X529467Y-2125D02*
X530242Y-2900D01*
G01X529467Y10888D02*
Y-2125D01*
G01X528241Y12114D02*
X529467Y10888D01*
G01X527391Y12964D02*
X528241Y12114D01*
G01X527391Y12968D02*
Y12964D01*
G01X526255Y14104D02*
X527391Y12968D01*
G01X526255Y15514D02*
Y14104D01*
G01X528392Y17651D02*
X526255Y15514D01*
G01X528392Y24800D02*
Y17651D01*
G01X529855Y26263D02*
X528392Y24800D01*
G01X529855Y28599D02*
Y26263D01*
G01X530105Y28849D02*
X529855Y28599D01*
G01X530105Y35049D02*
Y28849D01*
G01X495077Y-7779D02*
Y-9901D01*
G01X496956Y-5900D02*
X495077Y-7779D01*
G01X498356Y-5900D02*
X496956D01*
G01X499812Y-4444D02*
X498356Y-5900D01*
G01X499812Y-3100D02*
Y-4444D01*
G01X499196Y-2484D02*
X499812Y-3100D01*
G01X499196Y10641D02*
Y-2484D01*
G01X497723Y12114D02*
X499196Y10641D01*
G01X482938Y-8654D02*
X481691Y-9901D01*
G01X482938Y-7400D02*
Y-8654D01*
G01X484238Y-6100D02*
X482938Y-7400D01*
G01X485238Y-6100D02*
X484238D01*
G01X487038Y-4300D02*
X485238Y-6100D01*
G01X487038Y-2900D02*
Y-4300D01*
G01X486426Y-2288D02*
X487038Y-2900D01*
G01X486426Y10725D02*
Y-2288D01*
G01X485037Y12114D02*
X486426Y10725D01*
G01X483133Y14018D02*
X485037Y12114D01*
G01X483133Y15614D02*
Y14018D01*
G01X486483Y18964D02*
X483133Y15614D01*
G01X486483Y28699D02*
Y18964D01*
G01X487033Y29249D02*
X486483Y28699D01*
G01X487033Y34759D02*
Y29249D01*
G01X488384Y-8347D02*
Y-9901D01*
G01X490631Y-6100D02*
X488384Y-8347D01*
G01X491855Y-6100D02*
X490631D01*
G01X493431Y-4524D02*
X491855Y-6100D01*
G01X493431Y-2900D02*
Y-4524D01*
G01X492656Y-2125D02*
X493431Y-2900D01*
G01X492656Y10888D02*
Y-2125D01*
G01X491430Y12114D02*
X492656Y10888D01*
G01X520281Y-2133D02*
X521848Y-3700D01*
G01X520281Y-932D02*
Y-2133D01*
G01X518923Y426D02*
X520281Y-932D01*
G01X518923Y1799D02*
Y426D01*
G01X520123Y2999D02*
X518923Y1799D01*
G01X520123Y4125D02*
Y2999D01*
G01X518923Y5325D02*
X520123Y4125D01*
G01X518923Y6900D02*
Y5325D01*
G01X520723Y8700D02*
X518923Y6900D01*
G01X520723Y9758D02*
Y8700D01*
G01X517381Y13100D02*
X520723Y9758D01*
G01X517381Y16036D02*
Y13100D01*
G01X518502Y17157D02*
X517381Y16036D01*
G01X483470Y-2133D02*
X485037Y-3700D01*
G01X483470Y-932D02*
Y-2133D01*
G01X482112Y426D02*
X483470Y-932D01*
G01X482112Y1799D02*
Y426D01*
G01X483312Y2999D02*
X482112Y1799D01*
G01X483312Y4125D02*
Y2999D01*
G01X482112Y5325D02*
X483312Y4125D01*
G01X482112Y6900D02*
Y5325D01*
G01X483912Y8700D02*
X482112Y6900D01*
G01X483912Y9758D02*
Y8700D01*
G01X480570Y13100D02*
X483912Y9758D01*
G01X480570Y16036D02*
Y13100D01*
G01X481691Y17157D02*
X480570Y16036D01*
G01X484092Y19558D02*
X481691Y17157D01*
G01X484092Y22201D02*
Y19558D01*
G01X483392Y22901D02*
X484092Y22201D01*
G01X483392Y25600D02*
Y22901D01*
G01X484192Y26400D02*
X483392Y25600D01*
G01X484192Y27940D02*
Y26400D01*
G01X483133Y28999D02*
X484192Y27940D01*
G01X483133Y34641D02*
Y28999D01*
G01X527067Y-3012D02*
X528155Y-4100D01*
G01X527067Y-1132D02*
Y-3012D01*
G01X525634Y301D02*
X527067Y-1132D01*
G01X525634Y1500D02*
Y301D01*
G01X527134Y3000D02*
X525634Y1500D01*
G01X527134Y4200D02*
Y3000D01*
G01X525684Y5650D02*
X527134Y4200D01*
G01X525684Y7049D02*
Y5650D01*
G01X527067Y8432D02*
X525684Y7049D01*
G01X527067Y10301D02*
Y8432D01*
G01X524267Y13101D02*
X527067Y10301D01*
G01X524267Y16229D02*
Y13101D01*
G01X525195Y17157D02*
X524267Y16229D01*
G01X525195Y25103D02*
Y17157D01*
G01X527155Y27063D02*
X525195Y25103D01*
G01X527155Y28537D02*
Y27063D01*
G01X526255Y29437D02*
X527155Y28537D01*
G01X526255Y34299D02*
Y29437D01*
G01X491430Y56962D02*
Y49914D01*
G01X491266Y57126D02*
X491430Y56962D01*
G01X491266Y61302D02*
Y57126D01*
G01X492986Y63022D02*
X491266Y61302D01*
G01X492986Y67059D02*
Y63022D01*
G01X493286Y67359D02*
X492986Y67059D01*
G01X493286Y72659D02*
Y67359D01*
G01X492986Y72959D02*
X493286Y72659D01*
G01X492986Y74694D02*
Y72959D01*
G01X493492Y75200D02*
X492986Y74694D01*
G01X493492Y83500D02*
Y75200D01*
G01X492986Y84006D02*
X493492Y83500D01*
G01X492986Y86074D02*
Y84006D01*
G01X493386Y86474D02*
X492986Y86074D01*
G01X493386Y91174D02*
Y86474D01*
G01X493086Y91474D02*
X493386Y91174D01*
G01X493086Y105308D02*
Y91474D01*
G01X493431Y34900D02*
Y33276D01*
G01X492656Y35675D02*
X493431Y34900D01*
G01X492656Y48688D02*
Y35675D01*
G01X491430Y49914D02*
X492656Y48688D01*
G01X510881Y54029D02*
X511809Y54957D01*
G01X510881Y50901D02*
Y54029D01*
G01X513923Y47859D02*
X510881Y50901D01*
G01X513923Y46474D02*
Y47859D01*
G01X512248Y44799D02*
X513923Y46474D01*
G01X512248Y43676D02*
Y44799D01*
G01X513748Y42176D02*
X512248Y43676D01*
G01X513748Y40824D02*
Y42176D01*
G01X512248Y39324D02*
X513748Y40824D01*
G01X512248Y38101D02*
Y39324D01*
G01X513681Y36668D02*
X512248Y38101D01*
G01X513681Y35574D02*
Y36668D01*
G01X515155Y34100D02*
X513681Y35574D01*
G01X514086Y92174D02*
Y104907D01*
G01X512986Y91074D02*
X514086Y92174D01*
G01X512986Y86774D02*
Y91074D01*
G01X513686Y86074D02*
X512986Y86774D01*
G01X513686Y83900D02*
Y86074D01*
G01X512992Y83206D02*
X513686Y83900D01*
G01X512992Y75600D02*
Y83206D01*
G01X513686Y74906D02*
X512992Y75600D01*
G01X513686Y72995D02*
Y74906D01*
G01X512986Y72295D02*
X513686Y72995D01*
G01X512986Y67139D02*
Y72295D01*
G01X513786Y66339D02*
X512986Y67139D01*
G01X513786Y56934D02*
Y66339D01*
G01X511809Y54957D02*
X513786Y56934D01*
G01X533955Y35563D02*
X532605Y34213D01*
G01X533955Y47355D02*
Y35563D01*
G01X532666Y48644D02*
X533955Y47355D01*
G01X532666Y53158D02*
Y48644D01*
G01X533766Y54258D02*
X532666Y53158D01*
G01X533766Y66227D02*
Y54258D01*
G01X533593Y66400D02*
X533766Y66227D01*
G01X533593Y66406D02*
Y66400D01*
G01X532666Y67333D02*
X533593Y66406D01*
G01X532666Y72175D02*
Y67333D01*
G01X533966Y73475D02*
X532666Y72175D01*
G01X533966Y74826D02*
Y73475D01*
G01X533292Y75500D02*
X533966Y74826D01*
G01X533292Y83526D02*
Y75500D01*
G01X533966Y84200D02*
X533292Y83526D01*
G01X533966Y85174D02*
Y84200D01*
G01X532666Y86474D02*
X533966Y85174D01*
G01X532666Y90974D02*
Y86474D01*
G01X533766Y92074D02*
X532666Y90974D01*
G01X533766Y104974D02*
Y92074D01*
G01X490492Y91980D02*
Y105300D01*
G01X489486Y90974D02*
X490492Y91980D01*
G01X489486Y86374D02*
Y90974D01*
G01X490286Y85574D02*
X489486Y86374D01*
G01X490286Y84000D02*
Y85574D01*
G01X489692Y83406D02*
X490286Y84000D01*
G01X489692Y75300D02*
Y83406D01*
G01X490286Y74706D02*
X489692Y75300D01*
G01X490286Y72959D02*
Y74706D01*
G01X489486Y72159D02*
X490286Y72959D01*
G01X489486Y67107D02*
Y72159D01*
G01X490286Y66307D02*
X489486Y67107D01*
G01X490286Y63359D02*
Y66307D01*
G01X488384Y61457D02*
X490286Y63359D01*
G01X488384Y54957D02*
Y61457D01*
G01X489092Y54249D02*
X488384Y54957D01*
G01X489092Y49265D02*
Y54249D01*
G01X490256Y48101D02*
X489092Y49265D01*
G01X490256Y46364D02*
Y48101D01*
G01X488392Y44500D02*
X490256Y46364D01*
G01X488392Y43899D02*
Y44500D01*
G01X490323Y41968D02*
X488392Y43899D01*
G01X490323Y41232D02*
Y41968D01*
G01X488392Y39301D02*
X490323Y41232D01*
G01X488392Y38500D02*
Y39301D01*
G01X490256Y36636D02*
X488392Y38500D01*
G01X490256Y34788D02*
Y36636D01*
G01X491344Y33700D02*
X490256Y34788D01*
G01X520486Y91874D02*
Y104906D01*
G01X519986Y91374D02*
X520486Y91874D01*
G01X519986Y86374D02*
Y91374D01*
G01X520586Y85774D02*
X519986Y86374D01*
G01X520586Y84100D02*
Y85774D01*
G01X519792Y83306D02*
X520586Y84100D01*
G01X519792Y75500D02*
Y83306D01*
G01X520586Y74706D02*
X519792Y75500D01*
G01X520586Y73395D02*
Y74706D01*
G01X519786Y72595D02*
X520586Y73395D01*
G01X519786Y67259D02*
Y72595D01*
G01X520466Y66579D02*
X519786Y67259D01*
G01X520466Y56921D02*
Y66579D01*
G01X518502Y54957D02*
X520466Y56921D01*
G01X517381Y53836D02*
X518502Y54957D01*
G01X517381Y50900D02*
Y53836D01*
G01X520723Y47558D02*
X517381Y50900D01*
G01X520723Y46500D02*
Y47558D01*
G01X518923Y44700D02*
X520723Y46500D01*
G01X518923Y43125D02*
Y44700D01*
G01X520123Y41925D02*
X518923Y43125D01*
G01X520123Y40799D02*
Y41925D01*
G01X518923Y39599D02*
X520123Y40799D01*
G01X518923Y38226D02*
Y39599D01*
G01X520281Y36868D02*
X518923Y38226D01*
G01X520281Y35667D02*
Y36868D01*
G01X521848Y34100D02*
X520281Y35667D01*
G01X499586Y83900D02*
Y105101D01*
G01X500192Y83294D02*
X499586Y83900D01*
G01X500192Y75200D02*
Y83294D01*
G01X499586Y74594D02*
X500192Y75200D01*
G01X499586Y63859D02*
Y74594D01*
G01X497066Y61339D02*
X499586Y63859D01*
G01X497066Y54374D02*
Y61339D01*
G01X495992Y53300D02*
X497066Y54374D01*
G01X495992Y51645D02*
Y53300D01*
G01X497723Y49914D02*
X495992Y51645D01*
G01X499196Y48441D02*
X497723Y49914D01*
G01X499196Y35316D02*
Y48441D01*
G01X499812Y34700D02*
X499196Y35316D01*
G01X499812Y33356D02*
Y34700D01*
G01X516292Y92006D02*
Y105492D01*
G01X517286Y91012D02*
X516292Y92006D01*
G01X517286Y86674D02*
Y91012D01*
G01X516686Y86074D02*
X517286Y86674D01*
G01X516686Y83900D02*
Y86074D01*
G01X517092Y83494D02*
X516686Y83900D01*
G01X517092Y75300D02*
Y83494D01*
G01X516686Y74894D02*
X517092Y75300D01*
G01X516686Y72659D02*
Y74894D01*
G01X517186Y72159D02*
X516686Y72659D01*
G01X517186Y67059D02*
Y72159D01*
G01X515986Y65859D02*
X517186Y67059D01*
G01X515986Y56264D02*
Y65859D01*
G01X513316Y53594D02*
X515986Y56264D01*
G01X513316Y51753D02*
Y53594D01*
G01X515155Y49914D02*
X513316Y51753D01*
G01X516544Y48525D02*
X515155Y49914D01*
G01X516544Y35512D02*
Y48525D01*
G01X517156Y34900D02*
X516544Y35512D01*
G01X517156Y33500D02*
Y34900D01*
G01X479733Y35259D02*
X480633Y34359D01*
G01X479733Y36740D02*
Y35259D01*
G01X480392Y37399D02*
X479733Y36740D01*
G01X480392Y45600D02*
Y37399D01*
G01X479733Y46259D02*
X480392Y45600D01*
G01X479733Y47914D02*
Y46259D01*
G01X480266Y48447D02*
X479733Y47914D01*
G01X480266Y53481D02*
Y48447D01*
G01X479833Y53914D02*
X480266Y53481D01*
G01X479833Y66499D02*
Y53914D01*
G01X480633Y67299D02*
X479833Y66499D01*
G01X480633Y72259D02*
Y67299D01*
G01X479733Y73159D02*
X480633Y72259D01*
G01X479733Y74741D02*
Y73159D01*
G01X480092Y75100D02*
X479733Y74741D01*
G01X480092Y83441D02*
Y75100D01*
G01X479733Y83800D02*
X480092Y83441D01*
G01X479733Y85714D02*
Y83800D01*
G01X480533Y86514D02*
X479733Y85714D01*
G01X480533Y91014D02*
Y86514D01*
G01X479792Y91755D02*
X480533Y91014D01*
G01X479792Y94864D02*
Y91755D01*
G01X523849Y34900D02*
Y33500D01*
G01X523237Y35512D02*
X523849Y34900D01*
G01X523237Y48525D02*
Y35512D01*
G01X521848Y49914D02*
X523237Y48525D01*
G01X519892Y51870D02*
X521848Y49914D01*
G01X519892Y53570D02*
Y51870D01*
G01X523120Y56798D02*
X519892Y53570D01*
G01X523120Y66313D02*
Y56798D01*
G01X523686Y66879D02*
X523120Y66313D01*
G01X523686Y72707D02*
Y66879D01*
G01X523086Y73307D02*
X523686Y72707D01*
G01X523086Y74994D02*
Y73307D01*
G01X523692Y75600D02*
X523086Y74994D01*
G01X523692Y83594D02*
Y75600D01*
G01X523086Y84200D02*
X523692Y83594D01*
G01X523086Y85794D02*
Y84200D01*
G01X523786Y86494D02*
X523086Y85794D01*
G01X523786Y91154D02*
Y86494D01*
G01X523086Y91854D02*
X523786Y91154D01*
G01X523086Y104991D02*
Y91854D01*
G01X537092Y75500D02*
X536455Y74863D01*
G01X537092Y83263D02*
Y75500D01*
G01X536455Y83900D02*
X537092Y83263D01*
G01X536455Y115600D02*
Y83900D01*
G01X529755Y35399D02*
X530105Y35049D01*
G01X529755Y48027D02*
Y35399D01*
G01X530466Y48738D02*
X529755Y48027D01*
G01X530466Y53274D02*
Y48738D01*
G01X529766Y53974D02*
X530466Y53274D01*
G01X529766Y66959D02*
Y53974D01*
G01X530366Y67559D02*
X529766Y66959D01*
G01X530366Y72175D02*
Y67559D01*
G01X529800Y72741D02*
X530366Y72175D01*
G01X529800Y74708D02*
Y72741D01*
G01X530492Y75400D02*
X529800Y74708D01*
G01X530492Y83408D02*
Y75400D01*
G01X529800Y84100D02*
X530492Y83408D01*
G01X529800Y85772D02*
Y84100D01*
G01X530566Y86538D02*
X529800Y85772D01*
G01X530566Y91274D02*
Y86538D01*
G01X529866Y91974D02*
X530566Y91274D01*
G01X529866Y105438D02*
Y91974D01*
G01X495077Y62670D02*
Y54957D01*
G01X496986Y64579D02*
X495077Y62670D01*
G01X496986Y66207D02*
Y64579D01*
G01X495886Y67307D02*
X496986Y66207D01*
G01X495886Y72195D02*
Y67307D01*
G01X496886Y73195D02*
X495886Y72195D01*
G01X496886Y74906D02*
Y73195D01*
G01X496592Y75200D02*
X496886Y74906D01*
G01X496592Y83706D02*
Y75200D01*
G01X496886Y84000D02*
X496592Y83706D01*
G01X496886Y85474D02*
Y84000D01*
G01X495486Y86874D02*
X496886Y85474D01*
G01X495486Y90694D02*
Y86874D01*
G01X496886Y92094D02*
X495486Y90694D01*
G01X496886Y105106D02*
Y92094D01*
G01X496856Y34567D02*
X497723Y33700D01*
G01X496856Y36868D02*
Y34567D01*
G01X495223Y38501D02*
X496856Y36868D01*
G01X495223Y39800D02*
Y38501D01*
G01X496573Y41150D02*
X495223Y39800D01*
G01X496573Y42050D02*
Y41150D01*
G01X495323Y43300D02*
X496573Y42050D01*
G01X495323Y44499D02*
Y43300D01*
G01X496856Y46032D02*
X495323Y44499D01*
G01X496856Y48000D02*
Y46032D01*
G01X493956Y50900D02*
X496856Y48000D01*
G01X493956Y53836D02*
Y50900D01*
G01X495077Y54957D02*
X493956Y53836D01*
G01X485892Y35900D02*
X487033Y34759D01*
G01X485892Y47573D02*
Y35900D01*
G01X486866Y48547D02*
X485892Y47573D01*
G01X486866Y53481D02*
Y48547D01*
G01X486292Y54055D02*
X486866Y53481D01*
G01X486292Y66308D02*
Y54055D01*
G01X487033Y67049D02*
X486292Y66308D01*
G01X487033Y72559D02*
Y67049D01*
G01X486433Y73159D02*
X487033Y72559D01*
G01X486433Y74641D02*
Y73159D01*
G01X486992Y75200D02*
X486433Y74641D01*
G01X486992Y83441D02*
Y75200D01*
G01X486433Y84000D02*
X486992Y83441D01*
G01X486433Y85914D02*
Y84000D01*
G01X487133Y86614D02*
X486433Y85914D01*
G01X487133Y91274D02*
Y86614D01*
G01X486392Y92015D02*
X487133Y91274D01*
G01X486392Y120246D02*
Y92015D01*
G01X483633Y35141D02*
X483133Y34641D01*
G01X483633Y36859D02*
Y35141D01*
G01X482592Y37900D02*
X483633Y36859D01*
G01X482592Y39399D02*
Y37900D01*
G01X483292Y40099D02*
X482592Y39399D01*
G01X483292Y41374D02*
Y40099D01*
G01X482692Y41974D02*
X483292Y41374D01*
G01X482692Y45301D02*
Y41974D01*
G01X483633Y46242D02*
X482692Y45301D01*
G01X483633Y48014D02*
Y46242D01*
G01X482792Y48855D02*
X483633Y48014D01*
G01X482792Y53073D02*
Y48855D01*
G01X483566Y53847D02*
X482792Y53073D01*
G01X483566Y56200D02*
Y53847D01*
G01X484292Y56926D02*
X483566Y56200D01*
G01X484292Y58000D02*
Y56926D01*
G01X483566Y58726D02*
X484292Y58000D01*
G01X483566Y60100D02*
Y58726D01*
G01X484392Y60926D02*
X483566Y60100D01*
G01X484392Y62000D02*
Y60926D01*
G01X483566Y62826D02*
X484392Y62000D01*
G01X483566Y63774D02*
Y62826D01*
G01X484392Y64600D02*
X483566Y63774D01*
G01X484392Y65540D02*
Y64600D01*
G01X483133Y66799D02*
X484392Y65540D01*
G01X483133Y72541D02*
Y66799D01*
G01X484097Y73505D02*
X483133Y72541D01*
G01X484097Y74295D02*
Y73505D01*
G01X483192Y75200D02*
X484097Y74295D01*
G01X483192Y83599D02*
Y75200D01*
G01X483954Y84361D02*
X483192Y83599D01*
G01X483954Y85493D02*
Y84361D01*
G01X483092Y86355D02*
X483954Y85493D01*
G01X483092Y91201D02*
Y86355D01*
G01X483892Y92001D02*
X483092Y91201D01*
G01X483892Y119210D02*
Y92001D01*
G01X527255Y35299D02*
X526255Y34299D01*
G01X527255Y47885D02*
Y35299D01*
G01X526366Y48774D02*
X527255Y47885D01*
G01X526366Y53238D02*
Y48774D01*
G01X527266Y54138D02*
X526366Y53238D01*
G01X527266Y66226D02*
Y54138D01*
G01X526166Y67326D02*
X527266Y66226D01*
G01X526166Y71959D02*
Y67326D01*
G01X527066Y72859D02*
X526166Y71959D01*
G01X527066Y74826D02*
Y72859D01*
G01X526692Y75200D02*
X527066Y74826D01*
G01X526692Y83526D02*
Y75200D01*
G01X527066Y83900D02*
X526692Y83526D01*
G01X527066Y85874D02*
Y83900D01*
G01X526266Y86674D02*
X527066Y85874D01*
G01X526266Y90974D02*
Y86674D01*
G01X527166Y91874D02*
X526266Y90974D01*
G01X527166Y105374D02*
Y91874D01*
G01X491430Y106964D02*
X493086Y105308D01*
G01X536625Y157600D02*
X572284Y121941D01*
G01X512024Y106969D02*
Y112357D01*
G01X514086Y104907D02*
X512024Y106969D01*
G01X532666Y106074D02*
X533766Y104974D01*
G01X532666Y110438D02*
Y106074D01*
G01X533784Y111556D02*
X532666Y110438D01*
G01X533784Y114734D02*
Y111556D01*
G01X522518Y126000D02*
X533784Y114734D01*
G01X521436Y126000D02*
X522518D01*
G01X520636Y125200D02*
X521436Y126000D01*
G01X520636Y123782D02*
Y125200D01*
G01X519836Y122982D02*
X520636Y123782D01*
G01X518236Y122982D02*
X519836D01*
G01X517436Y123782D02*
X518236Y122982D01*
G01X517436Y125200D02*
Y123782D01*
G01X516636Y126000D02*
X517436Y125200D01*
G01X515036Y126000D02*
X516636D01*
G01X514236Y125200D02*
X515036Y126000D01*
G01X514236Y124560D02*
Y125200D01*
G01X513676Y124000D02*
X514236Y124560D01*
G01X511596Y124000D02*
X513676D01*
G01X511036Y124560D02*
X511596Y124000D01*
G01X511036Y127356D02*
Y124560D01*
G01X509292Y129100D02*
X511036Y127356D01*
G01X490267Y129100D02*
X509292D01*
G01X488634Y107158D02*
Y112357D01*
G01X490492Y105300D02*
X488634Y107158D01*
G01X521667Y145100D02*
X550420Y116347D01*
G01X491492Y145100D02*
X521667D01*
G01X489008Y147584D02*
X491492Y145100D01*
G01X489008Y148376D02*
Y147584D01*
G01X489866Y149234D02*
X489008Y148376D01*
G01X489866Y150026D02*
Y149234D01*
G01X488847Y151045D02*
X489866Y150026D01*
G01X488055Y151045D02*
X488847D01*
G01X487197Y150187D02*
X488055Y151045D01*
G01X486405Y150187D02*
X487197D01*
G01X485386Y151206D02*
X486405Y150187D01*
G01X485386Y151998D02*
Y151206D01*
G01X486244Y152856D02*
X485386Y151998D01*
G01X486244Y153648D02*
Y152856D01*
G01X485225Y154667D02*
X486244Y153648D01*
G01X484433Y154667D02*
X485225D01*
G01X483575Y153809D02*
X484433Y154667D01*
G01X482783Y153809D02*
X483575D01*
G01X480680Y155912D02*
X482783Y153809D01*
G01X480680Y171439D02*
Y155912D01*
G01X518317Y107075D02*
Y112357D01*
G01X520486Y104906D02*
X518317Y107075D01*
G01X499586Y105101D02*
X497723Y106964D01*
G01X516292Y105492D02*
X514820Y106964D01*
G01X481392Y96464D02*
X479792Y94864D01*
G01X481392Y118174D02*
Y96464D01*
G01X539594Y148990D02*
X540502Y149898D01*
G01X538802Y148990D02*
X539594D01*
G01X537783Y150009D02*
X538802Y148990D01*
G01X537783Y150801D02*
Y150009D01*
G01X538291Y151309D02*
X537783Y150801D01*
G01X538291Y152101D02*
Y151309D01*
G01X537272Y153120D02*
X538291Y152101D01*
G01X536480Y153120D02*
X537272D01*
G01X535972Y152612D02*
X536480Y153120D01*
G01X535180Y152612D02*
X535972D01*
G01X508892Y178900D02*
X535180Y152612D01*
G01X521113Y106964D02*
X523086Y104991D01*
G01X508493Y176100D02*
X555754Y128839D01*
G01X520955Y131100D02*
X536455Y115600D01*
G01X495570Y131100D02*
X520955D01*
G01X493584Y133086D02*
X495570Y131100D01*
G01X489818Y133086D02*
X493584D01*
G01X478292Y106652D02*
Y105052D01*
G01X479315Y111452D02*
X478515Y110652D01*
G01X479315Y113052D02*
Y111452D01*
G01X478515Y113852D02*
X479315Y113052D01*
G01X530184Y105756D02*
X529866Y105438D01*
G01X530184Y110956D02*
Y105756D01*
G01X529884Y111256D02*
X530184Y110956D01*
G01X529884Y115098D02*
Y111256D01*
G01X525682Y119300D02*
X529884Y115098D01*
G01X515646Y119300D02*
X525682D01*
G01X514546Y118200D02*
X515646Y119300D01*
G01X512946Y118200D02*
X514546D01*
G01X512146Y119000D02*
X512946Y118200D01*
G01X512146Y120200D02*
Y119000D01*
G01X506146Y126200D02*
X512146Y120200D01*
G01X489631Y126200D02*
X506146D01*
G01X495077Y106915D02*
X496886Y105106D01*
G01X495077Y112207D02*
Y106915D01*
G01X494927Y112357D02*
X495077Y112207D01*
G01X523475Y147000D02*
X553284Y117191D01*
G01X495492Y147000D02*
X523475D01*
G01X483392Y159100D02*
X495492Y147000D01*
G01X524693Y157300D02*
X564784Y117209D01*
G01X523711Y150300D02*
X558192Y115819D01*
G01X505740Y150300D02*
X523711D01*
G01X504840Y149400D02*
X505740Y150300D01*
G01X503400Y149400D02*
X504840D01*
G01X502840Y149960D02*
X503400Y149400D01*
G01X502840Y151240D02*
Y149960D01*
G01X502280Y151800D02*
X502840Y151240D01*
G01X500840Y151800D02*
X502280D01*
G01X500280Y151240D02*
X500840Y151800D01*
G01X500280Y149960D02*
Y151240D01*
G01X499720Y149400D02*
X500280Y149960D01*
G01X498280Y149400D02*
X499720D01*
G01X497720Y149960D02*
X498280Y149400D01*
G01X497720Y151240D02*
Y149960D01*
G01X497160Y151800D02*
X497720Y151240D01*
G01X494468Y151800D02*
X497160D01*
G01X486392Y159876D02*
X494468Y151800D01*
G01X523547Y154000D02*
X560692Y116855D01*
G01X495392Y154000D02*
X523547D01*
G01X488380Y161012D02*
X495392Y154000D01*
G01X526366Y106174D02*
X527166Y105374D01*
G01X526366Y110838D02*
Y106174D01*
G01X527092Y111564D02*
X526366Y110838D01*
G01X527092Y114354D02*
Y111564D01*
G01X525746Y115700D02*
X527092Y114354D01*
G01X504133Y115700D02*
X525746D01*
G01X503573Y116260D02*
X504133Y115700D01*
G01X503573Y122800D02*
Y116260D01*
G01X502773Y123600D02*
X503573Y122800D01*
G01X501173Y123600D02*
X502773D01*
G01X500373Y122800D02*
X501173Y123600D01*
G01X500373Y118800D02*
Y122800D01*
G01X499573Y118000D02*
X500373Y118800D01*
G01X494295Y118000D02*
X499573D01*
G01X537766Y176126D02*
X593492Y120400D01*
G01X533766Y176126D02*
X537766D01*
G01X511992Y197900D02*
X533766Y176126D01*
G01X500292Y197900D02*
X511992D01*
G01X493692Y204500D02*
X500292Y197900D01*
G01X532791Y157600D02*
X536625D01*
G01X507491Y182900D02*
X532791Y157600D01*
G01X494792Y182900D02*
X507491D01*
G01X483492Y194200D02*
X494792Y182900D01*
G01X495992Y178900D02*
X508892D01*
G01X481592Y193300D02*
X495992Y178900D01*
G01X538892Y178500D02*
X598792Y118600D01*
G01X534592Y178500D02*
X538892D01*
G01X512792Y200300D02*
X534592Y178500D01*
G01X500592Y200300D02*
X512792D01*
G01X495392Y205500D02*
X500592Y200300D01*
G01X495792Y176100D02*
X508493D01*
G01X481142Y190750D02*
X495792Y176100D01*
G01X483392Y171836D02*
Y159100D01*
G01X517161Y157300D02*
X524693D01*
G01X516601Y157860D02*
X517161Y157300D01*
G01X516601Y163740D02*
Y157860D01*
G01X516041Y164300D02*
X516601Y163740D01*
G01X514601Y164300D02*
X516041D01*
G01X514041Y163740D02*
X514601Y164300D01*
G01X514041Y160060D02*
Y163740D01*
G01X513481Y159500D02*
X514041Y160060D01*
G01X511652Y159500D02*
X513481D01*
G01X511092Y160060D02*
X511652Y159500D01*
G01X511092Y167201D02*
Y160060D01*
G01X504193Y174100D02*
X511092Y167201D01*
G01X494692Y174100D02*
X504193D01*
G01X479792Y189000D02*
X494692Y174100D01*
G01X479792Y189500D02*
Y189000D01*
G01X539630Y167962D02*
X585966Y121626D01*
G01X535530Y167962D02*
X539630D01*
G01X510292Y193200D02*
X535530Y167962D01*
G01X499092Y193200D02*
X510292D01*
G01X491842Y200450D02*
X499092Y193200D01*
G01X486392Y171534D02*
Y159876D01*
G01X539092Y171599D02*
X590992Y119699D01*
G01X535292Y171599D02*
X539092D01*
G01X511291Y195600D02*
X535292Y171599D01*
G01X499792Y195600D02*
X511291D01*
G01X492592Y202800D02*
X499792Y195600D01*
G01X488380Y172548D02*
Y161012D01*
G01X526176Y461273D02*
X495065D01*
G01X549112Y484209D02*
X526176Y461273D01*
G01X530144Y459094D02*
X496486D01*
G01X540360Y469310D02*
X530144Y459094D01*
G01X531347Y454600D02*
X563806Y487059D01*
G01X496792Y454600D02*
X531347D01*
G01X481192Y439000D02*
X496792Y454600D01*
G01X481192Y414631D02*
Y439000D01*
G01X481148Y414587D02*
X481192Y414631D01*
G01X537322Y432806D02*
X588466Y483950D01*
G01X530112Y432806D02*
X537322D01*
G01X506074Y408768D02*
X530112Y432806D01*
G01X501326Y408768D02*
X506074D01*
G01X501126Y408568D02*
X501326Y408768D01*
G01X532412Y452200D02*
X567205Y486993D01*
G01X497692Y452200D02*
X532412D01*
G01X483992Y438500D02*
X497692Y452200D01*
G01X483992Y432973D02*
Y438500D01*
G01X484602Y432363D02*
X483992Y432973D01*
G01X486091Y432363D02*
X484602D01*
G01X486701Y431753D02*
X486091Y432363D01*
G01X486701Y430363D02*
Y431753D01*
G01X486091Y429753D02*
X486701Y430363D01*
G01X484602Y429753D02*
X486091D01*
G01X483992Y429143D02*
X484602Y429753D01*
G01X483992Y414931D02*
Y429143D01*
G01X538214Y430682D02*
X590966Y483434D01*
G01X531114Y430682D02*
X538214D01*
G01X507332Y406900D02*
X531114Y430682D01*
G01X503108Y406900D02*
X507332D01*
G01X502951Y406743D02*
X503108Y406900D01*
G01X534083Y449903D02*
X570539Y486359D01*
G01X517488Y449903D02*
X534083D01*
G01X512515Y444930D02*
X517488Y449903D01*
G01X512515Y434817D02*
Y444930D01*
G01X505598Y427900D02*
X512515Y434817D01*
G01X498668Y427900D02*
X505598D01*
G01X486148Y415380D02*
X498668Y427900D01*
G01X486148Y412641D02*
Y415380D01*
G01X535811Y447835D02*
X573266Y485290D01*
G01X521510Y447835D02*
X535811D01*
G01X520081Y446406D02*
X521510Y447835D01*
G01X520081Y438919D02*
Y446406D01*
G01X519471Y438309D02*
X520081Y438919D01*
G01X518081Y438309D02*
X519471D01*
G01X517471Y438919D02*
X518081Y438309D01*
G01X517471Y443845D02*
Y438919D01*
G01X516861Y444455D02*
X517471Y443845D01*
G01X515471Y444455D02*
X516861D01*
G01X514861Y443845D02*
X515471Y444455D01*
G01X514861Y433569D02*
Y443845D01*
G01X507307Y426015D02*
X514861Y433569D01*
G01X500330Y426015D02*
X507307D01*
G01X488648Y414333D02*
X500330Y426015D01*
G01X538886Y428447D02*
X596213Y485774D01*
G01X532021Y428447D02*
X538886D01*
G01X522050Y418476D02*
X532021Y428447D01*
G01X522050Y417614D02*
Y418476D01*
G01X522888Y416776D02*
X522050Y417614D01*
G01X522888Y415814D02*
Y416776D01*
G01X522004Y414930D02*
X522888Y415814D01*
G01X521042Y414930D02*
X522004D01*
G01X520204Y415768D02*
X521042Y414930D01*
G01X519342Y415768D02*
X520204D01*
G01X518358Y414784D02*
X519342Y415768D01*
G01X518358Y413922D02*
Y414784D01*
G01X519196Y413084D02*
X518358Y413922D01*
G01X519196Y412222D02*
Y413084D01*
G01X518212Y411238D02*
X519196Y412222D01*
G01X517350Y411238D02*
X518212D01*
G01X516512Y412076D02*
X517350Y411238D01*
G01X515650Y412076D02*
X516512D01*
G01X508477Y404903D02*
X515650Y412076D01*
G01X504791Y404903D02*
X508477D01*
G01X536428Y435096D02*
X585933Y484601D01*
G01X529276Y435096D02*
X536428D01*
G01X505380Y411200D02*
X529276Y435096D01*
G01X500208Y411200D02*
X505380D01*
G01X499351Y410343D02*
X500208Y411200D01*
G01X495752Y463760D02*
X493752D01*
G01X496362Y464370D02*
X495752Y463760D01*
G01X496362Y466139D02*
Y464370D01*
G01X498972D02*
Y466139D01*
G01X499582Y463760D02*
X498972Y464370D01*
G01X500972Y463760D02*
X499582D01*
G01X501582Y464370D02*
X500972Y463760D01*
G01X501582Y466139D02*
Y464370D01*
G01X504192D02*
Y466139D01*
G01X504802Y463760D02*
X504192Y464370D01*
G01X506192Y463760D02*
X504802D01*
G01X506802Y464370D02*
X506192Y463760D01*
G01X506802Y465748D02*
Y464370D01*
G01X509412D02*
Y465804D01*
G01X510022Y463760D02*
X509412Y464370D01*
G01X525982Y463760D02*
X510022D01*
G01X548554Y486332D02*
X525982Y463760D01*
G01X493266Y492980D02*
X491430Y491144D01*
G01X493266Y494326D02*
Y492980D01*
G01X492377Y495215D02*
X493266Y494326D01*
G01X492377Y499063D02*
Y495215D01*
G01X492944Y499630D02*
X492377Y499063D01*
G01X492944Y510657D02*
Y499630D01*
G01X493294Y511007D02*
X492944Y510657D01*
G01X493294Y517207D02*
Y511007D01*
G01X493044Y517457D02*
X493294Y517207D01*
G01X493044Y519100D02*
Y517457D01*
G01X493392Y519448D02*
X493044Y519100D01*
G01X493392Y527800D02*
Y519448D01*
G01X514866Y493855D02*
X514755Y493744D01*
G01X514866Y507570D02*
Y493855D01*
G01X516544Y509248D02*
X514866Y507570D01*
G01X516544Y511257D02*
Y509248D01*
G01X517444Y512157D02*
X516544Y511257D01*
G01X517444Y516557D02*
Y512157D01*
G01X516344Y517657D02*
X517444Y516557D01*
G01X516344Y519200D02*
Y517657D01*
G01X516892Y519748D02*
X516344Y519200D01*
G01X516892Y527700D02*
Y519748D01*
G01X539504Y471028D02*
X540360Y470172D01*
G01X539504Y471890D02*
Y471028D01*
G01X540488Y472874D02*
X539504Y471890D01*
G01X520192Y519752D02*
Y527800D01*
G01X520744Y519200D02*
X520192Y519752D01*
G01X520744Y517857D02*
Y519200D01*
G01X519944Y517057D02*
X520744Y517857D01*
G01X519944Y511657D02*
Y517057D01*
G01X520444Y511157D02*
X519944Y511657D01*
G01X520444Y509153D02*
Y511157D01*
G01X517902Y506611D02*
X520444Y509153D01*
G01X517902Y498487D02*
Y506611D01*
G01X531265Y525717D02*
Y526941D01*
G01X530655Y525107D02*
X531265Y525717D01*
G01X529977Y525107D02*
X530655D01*
G01X529367Y524497D02*
X529977Y525107D01*
G01X529367Y522517D02*
Y524497D01*
G01X529977Y521907D02*
X529367Y522517D01*
G01X530655Y521907D02*
X529977D01*
G01X531265Y521297D02*
X530655Y521907D01*
G01X531265Y520122D02*
Y521297D01*
G01X529855Y518712D02*
X531265Y520122D01*
G01X529855Y517457D02*
Y518712D01*
G01X530105Y517207D02*
X529855Y517457D01*
G01X530105Y511747D02*
Y517207D01*
G01X529855Y511497D02*
X530105Y511747D01*
G01X529855Y509337D02*
Y511497D01*
G01X531112Y508080D02*
X529855Y509337D01*
G01X531112Y506900D02*
Y508080D01*
G01X530390Y506178D02*
X531112Y506900D01*
G01X529294Y506178D02*
X530390D01*
G01X528656Y505540D02*
X529294Y506178D01*
G01X528656Y495536D02*
Y505540D01*
G01X529992Y494200D02*
X528656Y495536D01*
G01X529992Y489882D02*
Y494200D01*
G01X527842Y487732D02*
X529992Y489882D01*
G01X527842Y486913D02*
Y487732D01*
G01X526441Y485512D02*
X527842Y486913D01*
G01X525536Y485512D02*
X526441D01*
G01X523431Y487617D02*
X525536Y485512D01*
G01X522610Y487617D02*
X523431D01*
G01X521213Y486220D02*
X522610Y487617D01*
G01X490357Y486220D02*
X521213D01*
G01X495766Y492851D02*
X497723Y490894D01*
G01X495766Y493974D02*
Y492851D01*
G01X497066Y495274D02*
X495766Y493974D01*
G01X497066Y503752D02*
Y495274D01*
G01X499644Y506330D02*
X497066Y503752D01*
G01X499644Y518600D02*
Y506330D01*
G01X500092Y519048D02*
X499644Y518600D01*
G01X500092Y527900D02*
Y519048D01*
G01X496792Y519552D02*
Y527900D01*
G01X496944Y519400D02*
X496792Y519552D01*
G01X496944Y517457D02*
Y519400D01*
G01X495794Y516307D02*
X496944Y517457D01*
G01X495794Y512057D02*
Y516307D01*
G01X497144Y510707D02*
X495794Y512057D01*
G01X497144Y507366D02*
Y510707D01*
G01X494777Y504999D02*
X497144Y507366D01*
G01X494777Y498487D02*
Y504999D01*
G01X479992Y519459D02*
Y527600D01*
G01X479833Y519300D02*
X479992Y519459D01*
G01X479833Y517357D02*
Y519300D01*
G01X480633Y516557D02*
X479833Y517357D01*
G01X480633Y512157D02*
Y516557D01*
G01X479733Y511257D02*
X480633Y512157D01*
G01X479733Y509201D02*
Y511257D01*
G01X479214Y502657D02*
X478604Y503267D01*
G01X479214Y501267D02*
Y502657D01*
G01X478604Y500657D02*
X479214Y501267D01*
G01Y497437D02*
X478604Y498047D01*
G01X479214Y496047D02*
Y497437D01*
G01X478604Y495437D02*
X479214Y496047D01*
G01X478414Y490610D02*
Y492317D01*
G01X523492Y519498D02*
Y527800D01*
G01X523294Y519300D02*
X523492Y519498D01*
G01X523294Y517357D02*
Y519300D01*
G01X523844Y516807D02*
X523294Y517357D01*
G01X523844Y512257D02*
Y516807D01*
G01X523244Y511657D02*
X523844Y512257D01*
G01X523244Y509348D02*
Y511657D01*
G01X523592Y509000D02*
X523244Y509348D01*
G01X523592Y504000D02*
Y509000D01*
G01X521048Y501456D02*
X523592Y504000D01*
G01X521048Y493844D02*
Y501456D01*
G01X533955Y517657D02*
Y529267D01*
G01X532740Y516442D02*
X533955Y517657D01*
G01X532740Y511922D02*
Y516442D01*
G01X533663Y510999D02*
X532740Y511922D01*
G01X533663Y497539D02*
Y510999D01*
G01X532721Y496597D02*
X533663Y497539D01*
G01X532721Y488876D02*
Y496597D01*
G01X527049Y483204D02*
X532721Y488876D01*
G01X490877Y483204D02*
X527049D01*
G01X525225Y465938D02*
X547574Y488287D01*
G01X512514Y465938D02*
X525225D01*
G01X509719Y468733D02*
X512514Y465938D01*
G01X495325Y468733D02*
X509719D01*
G01X490092Y519852D02*
Y528000D01*
G01X490344Y519600D02*
X490092Y519852D01*
G01X490344Y517357D02*
Y519600D01*
G01X489444Y516457D02*
X490344Y517357D01*
G01X489444Y511757D02*
Y516457D01*
G01X490444Y510757D02*
X489444Y511757D01*
G01X490444Y509051D02*
Y510757D01*
G01X490092Y508699D02*
X490444Y509051D01*
G01X490092Y500195D02*
Y508699D01*
G01X488384Y498487D02*
X490092Y500195D01*
G01X513492Y519852D02*
Y527800D01*
G01X513844Y519500D02*
X513492Y519852D01*
G01X513844Y517557D02*
Y519500D01*
G01X513244Y516957D02*
X513844Y517557D01*
G01X513244Y512057D02*
Y516957D01*
G01X514044Y511257D02*
X513244Y512057D01*
G01X514044Y509552D02*
Y511257D01*
G01X512266Y507774D02*
X514044Y509552D01*
G01X512266Y498944D02*
Y507774D01*
G01X511809Y498487D02*
X512266Y498944D01*
G01X486692Y519709D02*
Y527700D01*
G01X486483Y519500D02*
X486692Y519709D01*
G01X486483Y517357D02*
Y519500D01*
G01X487492Y516348D02*
X486483Y517357D01*
G01X487492Y512100D02*
Y516348D01*
G01X485890Y510498D02*
X487492Y512100D01*
G01X485890Y505916D02*
Y510498D01*
G01X485280Y505306D02*
X485890Y505916D01*
G01X483986Y505306D02*
X485280D01*
G01X483376Y504696D02*
X483986Y505306D01*
G01X483376Y503306D02*
Y504696D01*
G01X483986Y502696D02*
X483376Y503306D01*
G01X485280Y502696D02*
X483986D01*
G01X485890Y502086D02*
X485280Y502696D01*
G01X485890Y491276D02*
Y502086D01*
G01X536892Y519101D02*
Y527800D01*
G01X536455Y518664D02*
X536892Y519101D01*
G01X536455Y509237D02*
Y518664D01*
G01X538203Y507489D02*
X536455Y509237D01*
G01X538203Y506110D02*
Y507489D01*
G01X537593Y505500D02*
X538203Y506110D01*
G01X536441Y505500D02*
X537593D01*
G01X535831Y504890D02*
X536441Y505500D01*
G01X535831Y504010D02*
Y504890D01*
G01X536441Y503400D02*
X535831Y504010D01*
G01X537593Y503400D02*
X536441D01*
G01X538203Y502790D02*
X537593Y503400D01*
G01X538203Y501312D02*
Y502790D01*
G01X536455Y499564D02*
X538203Y501312D01*
G01X536455Y489844D02*
Y499564D01*
G01X524451Y477840D02*
X536455Y489844D01*
G01X520577Y477840D02*
X524451D01*
G01X519967Y478450D02*
X520577Y477840D01*
G01X519967Y479688D02*
Y478450D01*
G01X519357Y480298D02*
X519967Y479688D01*
G01X517967Y480298D02*
X519357D01*
G01X517357Y479688D02*
X517967Y480298D01*
G01X517357Y478450D02*
Y479688D01*
G01X516747Y477840D02*
X517357Y478450D01*
G01X515357Y477840D02*
X516747D01*
G01X514747Y478450D02*
X515357Y477840D01*
G01X514747Y479688D02*
Y478450D01*
G01X514137Y480298D02*
X514747Y479688D01*
G01X511956Y480298D02*
X514137D01*
G01X511346Y479688D02*
X511956Y480298D01*
G01X511346Y478478D02*
Y479688D01*
G01X510736Y477868D02*
X511346Y478478D01*
G01X509346Y477868D02*
X510736D01*
G01X508736Y478478D02*
X509346Y477868D01*
G01X508736Y479688D02*
Y478478D01*
G01X508126Y480298D02*
X508736Y479688D01*
G01X506736Y480298D02*
X508126D01*
G01X506126Y479688D02*
X506736Y480298D01*
G01X506126Y478478D02*
Y479688D01*
G01X505516Y477868D02*
X506126Y478478D01*
G01X504126Y477868D02*
X505516D01*
G01X503516Y478478D02*
X504126Y477868D01*
G01X503516Y479688D02*
Y478478D01*
G01X502906Y480298D02*
X503516Y479688D01*
G01X491507Y480298D02*
X502906D01*
G01X527155Y517357D02*
Y529438D01*
G01X526255Y516457D02*
X527155Y517357D01*
G01X526255Y511797D02*
Y516457D01*
G01X527155Y510897D02*
X526255Y511797D01*
G01X527155Y509400D02*
Y510897D01*
G01X526343Y508588D02*
X527155Y509400D01*
G01X526343Y503051D02*
Y508588D01*
G01X522792Y499500D02*
X526343Y503051D01*
G01X522792Y490499D02*
Y499500D01*
G01X520593Y488300D02*
X522792Y490499D01*
G01X488901Y488300D02*
X520593D01*
G01X483496Y517004D02*
Y529903D01*
G01X483160Y516668D02*
X483496Y517004D01*
G01X483160Y511630D02*
Y516668D01*
G01X483537Y511253D02*
X483160Y511630D01*
G01X483537Y509244D02*
Y511253D01*
G01X481420Y507127D02*
X483537Y509244D01*
G01X481420Y490354D02*
Y507127D01*
G01X496972Y466749D02*
X496362Y466139D01*
G01X498362Y466749D02*
X496972D01*
G01X498972Y466139D02*
X498362Y466749D01*
G01X502192D02*
X501582Y466139D01*
G01X503582Y466749D02*
X502192D01*
G01X504192Y466139D02*
X503582Y466749D01*
G01X507440Y466386D02*
X506802Y465748D01*
G01X508830Y466386D02*
X507440D01*
G01X509412Y465804D02*
X508830Y466386D01*
G01X493044Y528148D02*
X493392Y527800D01*
G01X493044Y530197D02*
Y528148D01*
G01X493544Y530697D02*
X493044Y530197D01*
G01X493544Y534856D02*
Y530697D01*
G01X492944Y535456D02*
X493544Y534856D01*
G01X492944Y537600D02*
Y535456D01*
G01X493392Y538048D02*
X492944Y537600D01*
G01X493392Y546100D02*
Y538048D01*
G01X492944Y546548D02*
X493392Y546100D01*
G01X492944Y549400D02*
Y546548D01*
G01X491430Y550914D02*
X492944Y549400D01*
G01X516644Y527948D02*
X516892Y527700D01*
G01X516644Y529797D02*
Y527948D01*
G01X517210Y530363D02*
X516644Y529797D01*
G01X517210Y535581D02*
Y530363D01*
G01X516544Y536247D02*
X517210Y535581D01*
G01X516544Y537800D02*
Y536247D01*
G01X516792Y538048D02*
X516544Y537800D01*
G01X516792Y546200D02*
Y538048D01*
G01X516544Y546448D02*
X516792Y546200D01*
G01X516544Y549568D02*
Y546448D01*
G01X516501Y549568D02*
X516544D01*
G01X515155Y550914D02*
X516501Y549568D01*
G01X517144Y554599D02*
X518502Y555957D01*
G01X517144Y552107D02*
Y554599D01*
G01X520544Y548707D02*
X517144Y552107D01*
G01X520544Y546552D02*
Y548707D01*
G01X520192Y546200D02*
X520544Y546552D01*
G01X520192Y538052D02*
Y546200D01*
G01X520544Y537700D02*
X520192Y538052D01*
G01X520544Y536242D02*
Y537700D01*
G01X519644Y535342D02*
X520544Y536242D01*
G01X519644Y530597D02*
Y535342D01*
G01X520744Y529497D02*
X519644Y530597D01*
G01X520744Y528352D02*
Y529497D01*
G01X520192Y527800D02*
X520744Y528352D01*
G01X529755Y587200D02*
X528241Y588714D01*
G01X529755Y584737D02*
Y587200D01*
G01X530692Y583800D02*
X529755Y584737D01*
G01X530692Y576237D02*
Y583800D01*
G01X529755Y575300D02*
X530692Y576237D01*
G01X529755Y573256D02*
Y575300D01*
G01X530355Y572656D02*
X529755Y573256D01*
G01X530355Y568497D02*
Y572656D01*
G01X529855Y567997D02*
X530355Y568497D01*
G01X529855Y566237D02*
Y567997D01*
G01X530192Y565900D02*
X529855Y566237D01*
G01X530192Y557437D02*
Y565900D01*
G01X529855Y557100D02*
X530192Y557437D01*
G01X529855Y555257D02*
Y557100D01*
G01X530105Y555007D02*
X529855Y555257D01*
G01X530105Y548807D02*
Y555007D01*
G01X529755Y548457D02*
X530105Y548807D01*
G01X529755Y535542D02*
Y548457D01*
G01X530105Y535192D02*
X529755Y535542D01*
G01X530105Y530242D02*
Y535192D01*
G01X529855Y529992D02*
X530105Y530242D01*
G01X529855Y528351D02*
Y529992D01*
G01X531265Y526941D02*
X529855Y528351D01*
G01X499644Y528348D02*
X500092Y527900D01*
G01X499644Y537700D02*
Y528348D01*
G01X500092Y538148D02*
X499644Y537700D01*
G01X500092Y546100D02*
Y538148D01*
G01X499644Y546548D02*
X500092Y546100D01*
G01X499644Y548643D02*
Y546548D01*
G01X497723Y550564D02*
X499644Y548643D01*
G01X497723Y550914D02*
Y550564D01*
G01X493644Y554524D02*
X495077Y555957D01*
G01X493644Y552007D02*
Y554524D01*
G01X496994Y548657D02*
X493644Y552007D01*
G01X496994Y546502D02*
Y548657D01*
G01X496792Y546300D02*
X496994Y546502D01*
G01X496792Y537802D02*
Y546300D01*
G01X496994Y537600D02*
X496792Y537802D01*
G01X496994Y536503D02*
Y537600D01*
G01X495844Y535353D02*
X496994Y536503D01*
G01X495844Y530547D02*
Y535353D01*
G01X496944Y529447D02*
X495844Y530547D01*
G01X496944Y528052D02*
Y529447D01*
G01X496792Y527900D02*
X496944Y528052D01*
G01X479690Y587368D02*
X478344Y588714D01*
G01X479733Y587368D02*
X479690D01*
G01X479733Y584559D02*
Y587368D01*
G01X479992Y584300D02*
X479733Y584559D01*
G01X479992Y575759D02*
Y584300D01*
G01X479733Y575500D02*
X479992Y575759D01*
G01X479733Y574059D02*
Y575500D01*
G01X480399Y573393D02*
X479733Y574059D01*
G01X480399Y568163D02*
Y573393D01*
G01X479833Y567597D02*
X480399Y568163D01*
G01X479833Y565859D02*
Y567597D01*
G01X479992Y565700D02*
X479833Y565859D01*
G01X479992Y557659D02*
Y565700D01*
G01X479533Y557200D02*
X479992Y557659D01*
G01X479533Y555457D02*
Y557200D01*
G01X480633Y554357D02*
X479533Y555457D01*
G01X480633Y549957D02*
Y554357D01*
G01X479733Y549057D02*
X480633Y549957D01*
G01X479733Y546759D02*
Y549057D01*
G01X479992Y546500D02*
X479733Y546759D01*
G01X479992Y537959D02*
Y546500D01*
G01X479733Y537700D02*
X479992Y537959D01*
G01X479733Y536458D02*
Y537700D01*
G01X480533Y535658D02*
X479733Y536458D01*
G01X480533Y530542D02*
Y535658D01*
G01X479833Y529842D02*
X480533Y530542D01*
G01X479833Y527759D02*
Y529842D01*
G01X479992Y527600D02*
X479833Y527759D01*
G01X521848Y550966D02*
Y550914D01*
G01X523144Y549670D02*
X521848Y550966D01*
G01X523144Y546248D02*
Y549670D01*
G01X523492Y545900D02*
X523144Y546248D01*
G01X523492Y537948D02*
Y545900D01*
G01X523144Y537600D02*
X523492Y537948D01*
G01X523144Y536348D02*
Y537600D01*
G01X524144Y535348D02*
X523144Y536348D01*
G01X524144Y530697D02*
Y535348D01*
G01X523294Y529847D02*
X524144Y530697D01*
G01X523294Y527998D02*
Y529847D01*
G01X523492Y527800D02*
X523294Y527998D01*
G01X533634Y586628D02*
X531148Y589114D01*
G01X533634Y574142D02*
Y586628D01*
G01X532655Y573163D02*
X533634Y574142D01*
G01X532655Y568367D02*
Y573163D01*
G01X533635Y567387D02*
X532655Y568367D01*
G01X533635Y555137D02*
Y567387D01*
G01X532605Y554107D02*
X533635Y555137D01*
G01X532605Y549857D02*
Y554107D01*
G01X533606Y548856D02*
X532605Y549857D01*
G01X533606Y536215D02*
Y548856D01*
G01X532741Y535350D02*
X533606Y536215D01*
G01X532741Y530481D02*
Y535350D01*
G01X533955Y529267D02*
X532741Y530481D01*
G01X490294Y549186D02*
X488380Y551100D01*
G01X490294Y546602D02*
Y549186D01*
G01X490092Y546400D02*
X490294Y546602D01*
G01X490092Y538002D02*
Y546400D01*
G01X490294Y537800D02*
X490092Y538002D01*
G01X490294Y536142D02*
Y537800D01*
G01X489296Y535144D02*
X490294Y536142D01*
G01X489296Y530497D02*
Y535144D01*
G01X490344Y529449D02*
X489296Y530497D01*
G01X490344Y528252D02*
Y529449D01*
G01X490092Y528000D02*
X490344Y528252D01*
G01X511144Y555292D02*
X511809Y555957D01*
G01X511144Y551457D02*
Y555292D01*
G01X514044Y548557D02*
X511144Y551457D01*
G01X514044Y547152D02*
Y548557D01*
G01X513492Y546600D02*
X514044Y547152D01*
G01X513492Y538152D02*
Y546600D01*
G01X514044Y537600D02*
X513492Y538152D01*
G01X514044Y536442D02*
Y537600D01*
G01X512771Y535169D02*
X514044Y536442D01*
G01X512771Y530670D02*
Y535169D01*
G01X513844Y529597D02*
X512771Y530670D01*
G01X513844Y528152D02*
Y529597D01*
G01X513492Y527800D02*
X513844Y528152D01*
G01X486333Y587470D02*
X485037Y588766D01*
G01X486333Y584659D02*
Y587470D01*
G01X486692Y584300D02*
X486333Y584659D01*
G01X486692Y575659D02*
Y584300D01*
G01X486333Y575300D02*
X486692Y575659D01*
G01X486333Y574058D02*
Y575300D01*
G01X487333Y573058D02*
X486333Y574058D01*
G01X487333Y568497D02*
Y573058D01*
G01X486483Y567647D02*
X487333Y568497D01*
G01X486483Y554809D02*
Y567647D01*
G01X486433Y546659D02*
Y549641D01*
G01X486692Y546400D02*
X486433Y546659D01*
G01X486692Y538499D02*
Y546400D01*
G01X486092Y537899D02*
X486692Y538499D01*
G01X486092Y536499D02*
Y537899D01*
G01X487133Y535458D02*
X486092Y536499D01*
G01X487133Y530466D02*
Y535458D01*
G01X486483Y529816D02*
X487133Y530466D01*
G01X486483Y527909D02*
Y529816D01*
G01X486692Y527700D02*
X486483Y527909D01*
G01X536455Y586443D02*
X534534Y588364D01*
G01X536455Y565737D02*
Y586443D01*
G01X536892Y565300D02*
X536455Y565737D01*
G01X536892Y557101D02*
Y565300D01*
G01X536455Y556664D02*
X536892Y557101D01*
G01X536455Y546537D02*
Y556664D01*
G01X536892Y546100D02*
X536455Y546537D01*
G01X536892Y538137D02*
Y546100D01*
G01X536455Y537700D02*
X536892Y538137D01*
G01X536455Y528237D02*
Y537700D01*
G01X536892Y527800D02*
X536455Y528237D01*
G01X524792Y587700D02*
X523955Y588537D01*
G01X525992Y587700D02*
X524792D01*
G01X527105Y586587D02*
X525992Y587700D01*
G01X527105Y573942D02*
Y586587D01*
G01X525792Y572629D02*
X527105Y573942D01*
G01X525792Y568600D02*
Y572629D01*
G01X527155Y567237D02*
X525792Y568600D01*
G01X527155Y565863D02*
Y567237D01*
G01X526892Y565600D02*
X527155Y565863D01*
G01X526892Y557699D02*
Y565600D01*
G01X527728Y556863D02*
X526892Y557699D01*
G01X527728Y555730D02*
Y556863D01*
G01X525792Y553794D02*
X527728Y555730D01*
G01X525792Y550400D02*
Y553794D01*
G01X527126Y549066D02*
X525792Y550400D01*
G01X527126Y536113D02*
Y549066D01*
G01X526255Y535242D02*
X527126Y536113D01*
G01X526255Y530338D02*
Y535242D01*
G01X527155Y529438D02*
X526255Y530338D01*
G01X483796Y586444D02*
X481253Y588987D01*
G01X483796Y574389D02*
Y586444D01*
G01X482692Y573285D02*
X483796Y574389D01*
G01X482692Y568538D02*
Y573285D01*
G01X483614Y567616D02*
X482692Y568538D01*
G01X483614Y565622D02*
Y567616D01*
G01X483367Y565375D02*
X483614Y565622D01*
G01X483367Y557566D02*
Y565375D01*
G01X483740Y557193D02*
X483367Y557566D01*
G01X483740Y554948D02*
Y557193D01*
G01X482892Y554100D02*
X483740Y554948D01*
G01X482892Y549800D02*
Y554100D01*
G01X483572Y549120D02*
X482892Y549800D01*
G01X483572Y536081D02*
Y549120D01*
G01X482592Y535101D02*
X483572Y536081D01*
G01X482592Y530807D02*
Y535101D01*
G01X483496Y529903D02*
X482592Y530807D01*
G01X516797Y595462D02*
X518502Y593757D01*
G01X516797Y605649D02*
Y595462D01*
G01X521848Y610700D02*
X516797Y605649D01*
G01X526267Y604499D02*
X525195D01*
G01X526867Y603899D02*
X526267Y604499D01*
G01X526867Y603001D02*
Y603899D01*
G01X525830Y601964D02*
X526867Y603001D01*
G01X525830Y600736D02*
Y601964D01*
G01X526767Y599799D02*
X525830Y600736D01*
G01X526767Y598401D02*
Y599799D01*
G01X525830Y597464D02*
X526767Y598401D01*
G01X525830Y596136D02*
Y597464D01*
G01X526967Y594999D02*
X525830Y596136D01*
G01X526967Y593100D02*
Y594999D01*
G01X526467Y592600D02*
X526967Y593100D01*
G01X526467Y590400D02*
Y592600D01*
G01X528153Y588714D02*
X526467Y590400D01*
G01X528241Y588714D02*
X528153D01*
G01X497635D02*
X497723D01*
G01X495949Y590400D02*
X497635Y588714D01*
G01X495949Y592092D02*
Y590400D01*
G01X496856Y592999D02*
X495949Y592092D01*
G01X496856Y594592D02*
Y592999D01*
G01X495712Y595736D02*
X496856Y594592D01*
G01X495712Y597156D02*
Y595736D01*
G01X496556Y598000D02*
X495712Y597156D01*
G01X496556Y599700D02*
Y598000D01*
G01X495712Y600544D02*
X496556Y599700D01*
G01X495712Y601756D02*
Y600544D01*
G01X496656Y602700D02*
X495712Y601756D01*
G01X496656Y603900D02*
Y602700D01*
G01X496057Y604499D02*
X496656Y603900D01*
G01X495077Y604499D02*
X496057D01*
G01X478344Y588714D02*
X478256D01*
G01X533368Y610300D02*
X534534D01*
G01X530183Y607115D02*
X533368Y610300D01*
G01X530183Y595462D02*
Y607115D01*
G01X531888Y593757D02*
X530183Y595462D01*
G01X531148Y593017D02*
X531888Y593757D01*
G01X531148Y589114D02*
Y593017D01*
G01X515067Y588714D02*
X515155D01*
G01X513381Y590400D02*
X515067Y588714D01*
G01X513381Y592092D02*
Y590400D01*
G01X513556Y592267D02*
X513381Y592092D01*
G01X513556Y594900D02*
Y592267D01*
G01X512444Y596012D02*
X513556Y594900D01*
G01X512444Y597088D02*
Y596012D01*
G01X513456Y598100D02*
X512444Y597088D01*
G01X513456Y599300D02*
Y598100D01*
G01X512444Y600312D02*
X513456Y599300D01*
G01X512444Y601388D02*
Y600312D01*
G01X513581Y602525D02*
X512444Y601388D01*
G01X513581Y603799D02*
Y602525D01*
G01X512881Y604499D02*
X513581Y603799D01*
G01X511809Y604499D02*
X512881D01*
G01X510104Y595462D02*
X511809Y593757D01*
G01X510104Y605649D02*
Y595462D01*
G01X515155Y610700D02*
X510104Y605649D01*
G01X491342Y588714D02*
X491430D01*
G01X489656Y590400D02*
X491342Y588714D01*
G01X489656Y592600D02*
Y590400D01*
G01X490156Y593100D02*
X489656Y592600D01*
G01X490156Y594999D02*
Y593100D01*
G01X489019Y596136D02*
X490156Y594999D01*
G01X489019Y597464D02*
Y596136D01*
G01X489956Y598401D02*
X489019Y597464D01*
G01X489956Y599799D02*
Y598401D01*
G01X489019Y600736D02*
X489956Y599799D01*
G01X489019Y601964D02*
Y600736D01*
G01X490056Y603001D02*
X489019Y601964D01*
G01X490056Y603899D02*
Y603001D01*
G01X489456Y604499D02*
X490056Y603899D01*
G01X488384Y604499D02*
X489456D01*
G01X482763D02*
X481691D01*
G01X483463Y603799D02*
X482763Y604499D01*
G01X483463Y602525D02*
Y603799D01*
G01X482326Y601388D02*
X483463Y602525D01*
G01X482326Y600312D02*
Y601388D01*
G01X483338Y599300D02*
X482326Y600312D01*
G01X483338Y598100D02*
Y599300D01*
G01X482326Y597088D02*
X483338Y598100D01*
G01X482326Y596012D02*
Y597088D01*
G01X483438Y594900D02*
X482326Y596012D01*
G01X483438Y592267D02*
Y594900D01*
G01X483263Y592092D02*
X483438Y592267D01*
G01X483263Y590400D02*
Y592092D01*
G01X484949Y588714D02*
X483263Y590400D01*
G01X485037Y588714D02*
X484949D01*
G01X485037Y588766D02*
Y588714D01*
G01X532868Y604499D02*
X531888D01*
G01X533467Y603900D02*
X532868Y604499D01*
G01X533467Y602700D02*
Y603900D01*
G01X532523Y601756D02*
X533467Y602700D01*
G01X532523Y600544D02*
Y601756D01*
G01X533367Y599700D02*
X532523Y600544D01*
G01X533367Y598000D02*
Y599700D01*
G01X532523Y597156D02*
X533367Y598000D01*
G01X532523Y595736D02*
Y597156D01*
G01X533667Y594592D02*
X532523Y595736D01*
G01X533667Y592999D02*
Y594592D01*
G01X532760Y592092D02*
X533667Y592999D01*
G01X532760Y590400D02*
Y592092D01*
G01X534446Y588714D02*
X532760Y590400D01*
G01X534534Y588714D02*
X534446D01*
G01X534534Y588364D02*
Y588714D01*
G01X486679Y595462D02*
X488384Y593757D01*
G01X486679Y605435D02*
Y595462D01*
G01X487301Y606057D02*
X486679Y605435D01*
G01X487301Y607245D02*
Y606057D01*
G01X491724Y611668D02*
X487301Y607245D01*
G01X527167Y610300D02*
X528155D01*
G01X524112Y607245D02*
X527167Y610300D01*
G01X524112Y606057D02*
Y607245D01*
G01X523490Y605435D02*
X524112Y606057D01*
G01X523490Y595462D02*
Y605435D01*
G01X525195Y593757D02*
X523490Y595462D01*
G01X523955Y592517D02*
X525195Y593757D01*
G01X523955Y588537D02*
Y592517D01*
G01X521760Y588714D02*
X521848D01*
G01X520074Y590400D02*
X521760Y588714D01*
G01X520074Y592092D02*
Y590400D01*
G01X520249Y592267D02*
X520074Y592092D01*
G01X520249Y594900D02*
Y592267D01*
G01X519137Y596012D02*
X520249Y594900D01*
G01X519137Y597088D02*
Y596012D01*
G01X520149Y598100D02*
X519137Y597088D01*
G01X520149Y599300D02*
Y598100D01*
G01X519137Y600312D02*
X520149Y599300D01*
G01X519137Y601388D02*
Y600312D01*
G01X520274Y602525D02*
X519137Y601388D01*
G01X520274Y603799D02*
Y602525D01*
G01X519574Y604499D02*
X520274Y603799D01*
G01X518502Y604499D02*
X519574D01*
G01X479986Y605649D02*
X485037Y610700D01*
G01X479986Y595462D02*
Y605649D01*
G01X481691Y593757D02*
X479986Y595462D01*
G01X481253Y593319D02*
X481691Y593757D01*
G01X481253Y588987D02*
Y593319D01*
G01X493372Y595462D02*
X495077Y593757D01*
G01X493372Y606480D02*
Y595462D01*
G01X498092Y611200D02*
X493372Y606480D01*
G01X593903Y-2133D02*
X595470Y-3700D01*
G01X593903Y-932D02*
Y-2133D01*
G01X592545Y426D02*
X593903Y-932D01*
G01X592545Y1799D02*
Y426D01*
G01X593745Y2999D02*
X592545Y1799D01*
G01X593745Y4125D02*
Y2999D01*
G01X592545Y5325D02*
X593745Y4125D01*
G01X592545Y6900D02*
Y5325D01*
G01X594345Y8700D02*
X592545Y6900D01*
G01X594345Y9758D02*
Y8700D01*
G01X591003Y13100D02*
X594345Y9758D01*
G01X591003Y16036D02*
Y13100D01*
G01X592124Y17157D02*
X591003Y16036D01*
G01X594366Y19399D02*
X592124Y17157D01*
G01X594366Y28199D02*
Y19399D01*
G01X593566Y28999D02*
X594366Y28199D01*
G01X593566Y34675D02*
Y28999D01*
G01X568699Y-7779D02*
Y-9901D01*
G01X570578Y-5900D02*
X568699Y-7779D01*
G01X571978Y-5900D02*
X570578D01*
G01X573434Y-4444D02*
X571978Y-5900D01*
G01X573434Y-3100D02*
Y-4444D01*
G01X572818Y-2484D02*
X573434Y-3100D01*
G01X572818Y10641D02*
Y-2484D01*
G01X571345Y12114D02*
X572818Y10641D01*
G01X569272Y14187D02*
X571345Y12114D01*
G01X569272Y15180D02*
Y14187D01*
G01X570766Y16674D02*
X569272Y15180D01*
G01X570766Y23173D02*
Y16674D01*
G01X573266Y25673D02*
X570766Y23173D01*
G01X573266Y37200D02*
Y25673D01*
G01X550492Y-2226D02*
X551966Y-3700D01*
G01X550492Y-1132D02*
Y-2226D01*
G01X549059Y301D02*
X550492Y-1132D01*
G01X549059Y1524D02*
Y301D01*
G01X550559Y3024D02*
X549059Y1524D01*
G01X550559Y4376D02*
Y3024D01*
G01X549059Y5876D02*
X550559Y4376D01*
G01X549059Y6999D02*
Y5876D01*
G01X550734Y8674D02*
X549059Y6999D01*
G01X550734Y10059D02*
Y8674D01*
G01X547692Y13101D02*
X550734Y10059D01*
G01X547692Y16229D02*
Y13101D01*
G01X548620Y17157D02*
X547692Y16229D01*
G01X550655Y19192D02*
X548620Y17157D01*
G01X550655Y28499D02*
Y19192D01*
G01X550055Y29099D02*
X550655Y28499D01*
G01X550055Y34763D02*
Y29099D01*
G01X570478Y-3233D02*
X571345Y-4100D01*
G01X570478Y-932D02*
Y-3233D01*
G01X568845Y701D02*
X570478Y-932D01*
G01X568845Y2000D02*
Y701D01*
G01X570195Y3350D02*
X568845Y2000D01*
G01X570195Y4250D02*
Y3350D01*
G01X568945Y5500D02*
X570195Y4250D01*
G01X568945Y6699D02*
Y5500D01*
G01X570478Y8232D02*
X568945Y6699D01*
G01X570478Y10200D02*
Y8232D01*
G01X567578Y13100D02*
X570478Y10200D01*
G01X567578Y16036D02*
Y13100D01*
G01X568699Y17157D02*
X567578Y16036D01*
G01X568699Y24906D02*
Y17157D01*
G01X570592Y26799D02*
X568699Y24906D01*
G01X570592Y28418D02*
Y26799D01*
G01X569416Y29594D02*
X570592Y28418D01*
G01X569416Y34183D02*
Y29594D01*
G01X592124Y-8647D02*
Y-9901D01*
G01X594671Y-6100D02*
X592124Y-8647D01*
G01X595671Y-6100D02*
X594671D01*
G01X597471Y-4300D02*
X595671Y-6100D01*
G01X597471Y-2900D02*
Y-4300D01*
G01X596859Y-2288D02*
X597471Y-2900D01*
G01X596859Y10725D02*
Y-2288D01*
G01X595470Y12114D02*
X596859Y10725D01*
G01X593566Y14018D02*
X595470Y12114D01*
G01X593566Y15614D02*
Y14018D01*
G01X596916Y18964D02*
X593566Y15614D01*
G01X596916Y28699D02*
Y18964D01*
G01X597466Y29249D02*
X596916Y28699D01*
G01X597466Y34627D02*
Y29249D01*
G01X562006Y-8347D02*
Y-9901D01*
G01X564253Y-6100D02*
X562006Y-8347D01*
G01X565477Y-6100D02*
X564253D01*
G01X567053Y-4524D02*
X565477Y-6100D01*
G01X567053Y-2900D02*
Y-4524D01*
G01X566278Y-2125D02*
X567053Y-2900D01*
G01X566278Y10888D02*
Y-2125D01*
G01X565052Y12114D02*
X566278Y10888D01*
G01X563184Y13982D02*
X565052Y12114D01*
G01X563184Y15632D02*
Y13982D01*
G01X566592Y19040D02*
X563184Y15632D01*
G01X566592Y28525D02*
Y19040D01*
G01X566916Y28849D02*
X566592Y28525D01*
G01X566916Y35049D02*
Y28849D01*
G01X549867Y-8654D02*
X548620Y-9901D01*
G01X549867Y-7400D02*
Y-8654D01*
G01X551167Y-6100D02*
X549867Y-7400D01*
G01X552167Y-6100D02*
X551167D01*
G01X553967Y-4300D02*
X552167Y-6100D01*
G01X553967Y-2900D02*
Y-4300D01*
G01X553355Y-2288D02*
X553967Y-2900D01*
G01X553355Y10725D02*
Y-2288D01*
G01X551966Y12114D02*
X553355Y10725D01*
G01X550155Y13925D02*
X551966Y12114D01*
G01X550155Y15562D02*
Y13925D01*
G01X553513Y18920D02*
X550155Y15562D01*
G01X553513Y28757D02*
Y18920D01*
G01X553892Y29136D02*
X553513Y28757D01*
G01X553892Y34900D02*
Y29136D01*
G01X563878Y-3012D02*
X564966Y-4100D01*
G01X563878Y-1132D02*
Y-3012D01*
G01X562445Y301D02*
X563878Y-1132D01*
G01X562445Y1500D02*
Y301D01*
G01X563945Y3000D02*
X562445Y1500D01*
G01X563945Y4200D02*
Y3000D01*
G01X562495Y5650D02*
X563945Y4200D01*
G01X562495Y7049D02*
Y5650D01*
G01X563878Y8432D02*
X562495Y7049D01*
G01X563878Y10301D02*
Y8432D01*
G01X561078Y13101D02*
X563878Y10301D01*
G01X561078Y16229D02*
Y13101D01*
G01X561868Y17019D02*
X561078Y16229D01*
G01X564092Y19243D02*
X561868Y17019D01*
G01X564092Y20514D02*
Y19243D01*
G01X563192Y21414D02*
X564092Y20514D01*
G01X563192Y22500D02*
Y21414D01*
G01X563976Y23284D02*
X563192Y22500D01*
G01X563976Y24416D02*
Y23284D01*
G01X563258Y25134D02*
X563976Y24416D01*
G01X563258Y26266D02*
Y25134D01*
G01X563992Y27000D02*
X563258Y26266D01*
G01X563992Y28401D02*
Y27000D01*
G01X563066Y29327D02*
X563992Y28401D01*
G01X563066Y34299D02*
Y29327D01*
G01X587303Y-2226D02*
X588777Y-3700D01*
G01X587303Y-1132D02*
Y-2226D01*
G01X585870Y301D02*
X587303Y-1132D01*
G01X585870Y1524D02*
Y301D01*
G01X587370Y3024D02*
X585870Y1524D01*
G01X587370Y4376D02*
Y3024D01*
G01X585870Y5876D02*
X587370Y4376D01*
G01X585870Y6999D02*
Y5876D01*
G01X587545Y8674D02*
X585870Y6999D01*
G01X587545Y10059D02*
Y8674D01*
G01X584503Y13101D02*
X587545Y10059D01*
G01X584503Y16229D02*
Y13101D01*
G01X585431Y17157D02*
X584503Y16229D01*
G01X587466Y19192D02*
X585431Y17157D01*
G01X587466Y28499D02*
Y19192D01*
G01X586866Y29099D02*
X587466Y28499D01*
G01X586866Y34601D02*
Y29099D01*
G01X557092Y-2133D02*
X558659Y-3700D01*
G01X557092Y-932D02*
Y-2133D01*
G01X555734Y426D02*
X557092Y-932D01*
G01X555734Y1799D02*
Y426D01*
G01X556934Y2999D02*
X555734Y1799D01*
G01X556934Y4125D02*
Y2999D01*
G01X555734Y5325D02*
X556934Y4125D01*
G01X555734Y6900D02*
Y5325D01*
G01X557534Y8700D02*
X555734Y6900D01*
G01X557534Y9758D02*
Y8700D01*
G01X554192Y13100D02*
X557534Y9758D01*
G01X554192Y16036D02*
Y13100D01*
G01X555313Y17157D02*
X554192Y16036D01*
G01X557555Y19399D02*
X555313Y17157D01*
G01X557555Y28237D02*
Y19399D01*
G01X556792Y29000D02*
X557555Y28237D01*
G01X556792Y34900D02*
Y29000D01*
G01X586678Y-8654D02*
X585431Y-9901D01*
G01X586678Y-7400D02*
Y-8654D01*
G01X587978Y-6100D02*
X586678Y-7400D01*
G01X588978Y-6100D02*
X587978D01*
G01X590778Y-4300D02*
X588978Y-6100D01*
G01X590778Y-2900D02*
Y-4300D01*
G01X590166Y-2288D02*
X590778Y-2900D01*
G01X590166Y10725D02*
Y-2288D01*
G01X588777Y12114D02*
X590166Y10725D01*
G01X586873Y14018D02*
X588777Y12114D01*
G01X586873Y15614D02*
Y14018D01*
G01X590223Y18964D02*
X586873Y15614D01*
G01X590223Y28699D02*
Y18964D01*
G01X590773Y29249D02*
X590223Y28699D01*
G01X590773Y34627D02*
Y29249D01*
G01X556560Y-8654D02*
X555313Y-9901D01*
G01X556560Y-7400D02*
Y-8654D01*
G01X557860Y-6100D02*
X556560Y-7400D01*
G01X558860Y-6100D02*
X557860D01*
G01X560660Y-4300D02*
X558860Y-6100D01*
G01X560660Y-2900D02*
Y-4300D01*
G01X560048Y-2288D02*
X560660Y-2900D01*
G01X560048Y10725D02*
Y-2288D01*
G01X558659Y12114D02*
X560048Y10725D01*
G01X556755Y14018D02*
X558659Y12114D01*
G01X556755Y15614D02*
Y14018D01*
G01X560105Y18964D02*
X556755Y15614D01*
G01X560105Y28699D02*
Y18964D01*
G01X560655Y29249D02*
X560105Y28699D01*
G01X560655Y34637D02*
Y29249D01*
G01X594066Y35175D02*
X593566Y34675D01*
G01X594066Y37100D02*
Y35175D01*
G01X593592Y37574D02*
X594066Y37100D01*
G01X593592Y45700D02*
Y37574D01*
G01X594066Y46174D02*
X593592Y45700D01*
G01X594066Y47774D02*
Y46174D01*
G01X593466Y48374D02*
X594066Y47774D01*
G01X593466Y53314D02*
Y48374D01*
G01X594416Y54264D02*
X593466Y53314D01*
G01X594416Y66225D02*
Y54264D01*
G01X593566Y67075D02*
X594416Y66225D01*
G01X593566Y72675D02*
Y67075D01*
G01X594066Y73175D02*
X593566Y72675D01*
G01X594066Y74626D02*
Y73175D01*
G01X593592Y75100D02*
X594066Y74626D01*
G01X593592Y83626D02*
Y75100D01*
G01X594066Y84100D02*
X593592Y83626D01*
G01X594066Y85814D02*
Y84100D01*
G01X593466Y86414D02*
X594066Y85814D01*
G01X593466Y91238D02*
Y86414D01*
G01X594466Y92238D02*
X593466Y91238D01*
G01X594466Y94574D02*
Y92238D01*
G01X593492Y95548D02*
X594466Y94574D01*
G01X573992Y37926D02*
X573266Y37200D01*
G01X573992Y45300D02*
Y37926D01*
G01X573266Y46026D02*
X573992Y45300D01*
G01X573266Y74700D02*
Y46026D01*
G01X574192Y75626D02*
X573266Y74700D01*
G01X574192Y83101D02*
Y75626D01*
G01X573266Y84027D02*
X574192Y83101D01*
G01X573266Y102126D02*
Y84027D01*
G01X550855Y35563D02*
X550055Y34763D01*
G01X550855Y37037D02*
Y35563D01*
G01X550092Y37800D02*
X550855Y37037D01*
G01X550092Y45637D02*
Y37800D01*
G01X550855Y46400D02*
X550092Y45637D01*
G01X550855Y47914D02*
Y46400D01*
G01X550055Y48714D02*
X550855Y47914D01*
G01X550055Y53526D02*
Y48714D01*
G01X550455Y53926D02*
X550055Y53526D01*
G01X550455Y64448D02*
Y53926D01*
G01X550766Y64759D02*
X550455Y64448D01*
G01X550766Y66259D02*
Y64759D01*
G01X550066Y66959D02*
X550766Y66259D01*
G01X550066Y72575D02*
Y66959D01*
G01X550666Y73175D02*
X550066Y72575D01*
G01X550666Y74350D02*
Y73175D01*
G01X549392Y75624D02*
X550666Y74350D01*
G01X549392Y82940D02*
Y75624D01*
G01X550666Y84214D02*
X549392Y82940D01*
G01X550666Y85374D02*
Y84214D01*
G01X549866Y86174D02*
X550666Y85374D01*
G01X549866Y90938D02*
Y86174D01*
G01X550666Y91738D02*
X549866Y90938D01*
G01X550666Y105574D02*
Y91738D01*
G01X570592Y35359D02*
X569416Y34183D01*
G01X570592Y36900D02*
Y35359D01*
G01X569292Y38200D02*
X570592Y36900D01*
G01X569292Y39000D02*
Y38200D01*
G01X570192Y39900D02*
X569292Y39000D01*
G01X570192Y41734D02*
Y39900D01*
G01X569492Y42434D02*
X570192Y41734D01*
G01X569492Y44734D02*
Y42434D01*
G01X570592Y45834D02*
X569492Y44734D01*
G01X570592Y47738D02*
Y45834D01*
G01X569416Y48914D02*
X570592Y47738D01*
G01X569416Y52788D02*
Y48914D01*
G01X569640Y53012D02*
X569416Y52788D01*
G01X569640Y53321D02*
Y53012D01*
G01X570592Y54273D02*
X569640Y53321D01*
G01X570592Y66218D02*
Y54273D01*
G01X569416Y67394D02*
X570592Y66218D01*
G01X569416Y72123D02*
Y67394D01*
G01X570592Y73299D02*
X569416Y72123D01*
G01X570592Y74700D02*
Y73299D01*
G01X569792Y75500D02*
X570592Y74700D01*
G01X569792Y83299D02*
Y75500D01*
G01X570592Y84099D02*
X569792Y83299D01*
G01X570592Y85248D02*
Y84099D01*
G01X569492Y86348D02*
X570592Y85248D01*
G01X569492Y91100D02*
Y86348D01*
G01X570499Y92107D02*
X569492Y91100D01*
G01X570499Y101492D02*
Y92107D01*
G01X596866Y35227D02*
X597466Y34627D01*
G01X596866Y36900D02*
Y35227D01*
G01X597692Y37726D02*
X596866Y36900D01*
G01X597692Y45400D02*
Y37726D01*
G01X596866Y46226D02*
X597692Y45400D01*
G01X596866Y47938D02*
Y46226D01*
G01X597566Y48638D02*
X596866Y47938D01*
G01X597566Y53214D02*
Y48638D01*
G01X596916Y53864D02*
X597566Y53214D01*
G01X596916Y66499D02*
Y53864D01*
G01X597466Y67049D02*
X596916Y66499D01*
G01X597466Y72527D02*
Y67049D01*
G01X596866Y73127D02*
X597466Y72527D01*
G01X596866Y74874D02*
Y73127D01*
G01X597392Y75400D02*
X596866Y74874D01*
G01X597392Y83574D02*
Y75400D01*
G01X596866Y84100D02*
X597392Y83574D01*
G01X596866Y85914D02*
Y84100D01*
G01X597566Y86614D02*
X596866Y85914D01*
G01X597566Y91274D02*
Y86614D01*
G01X596966Y91874D02*
X597566Y91274D01*
G01X596966Y93674D02*
Y91874D01*
G01X598792Y95500D02*
X596966Y93674D01*
G01X566749Y35216D02*
X566916Y35049D01*
G01X566749Y37357D02*
Y35216D01*
G01X567316Y37924D02*
X566749Y37357D01*
G01X567316Y45477D02*
Y37924D01*
G01X566749Y46044D02*
X567316Y45477D01*
G01X566749Y48497D02*
Y46044D01*
G01X567084Y48832D02*
X566749Y48497D01*
G01X567084Y53446D02*
Y48832D01*
G01X566892Y53638D02*
X567084Y53446D01*
G01X566892Y67365D02*
Y53638D01*
G01X567084Y67557D02*
X566892Y67365D01*
G01X567084Y72357D02*
Y67557D01*
G01X566692Y72749D02*
X567084Y72357D01*
G01X566692Y75000D02*
Y72749D01*
G01X567292Y75600D02*
X566692Y75000D01*
G01X567292Y83300D02*
Y75600D01*
G01X566692Y83900D02*
X567292Y83300D01*
G01X566692Y86000D02*
Y83900D01*
G01X567092Y86400D02*
X566692Y86000D01*
G01X567092Y90648D02*
Y86400D01*
G01X566784Y90956D02*
X567092Y90648D01*
G01X566784Y102092D02*
Y90956D01*
G01X553355Y35437D02*
X553892Y34900D01*
G01X553355Y36963D02*
Y35437D01*
G01X553892Y37500D02*
X553355Y36963D01*
G01X553892Y45663D02*
Y37500D01*
G01X553355Y46200D02*
X553892Y45663D01*
G01X553355Y47914D02*
Y46200D01*
G01X554155Y48714D02*
X553355Y47914D01*
G01X554155Y53286D02*
Y48714D01*
G01X553455Y53986D02*
X554155Y53286D01*
G01X553455Y66648D02*
Y53986D01*
G01X554022Y67215D02*
X553455Y66648D01*
G01X554022Y72371D02*
Y67215D01*
G01X553292Y73101D02*
X554022Y72371D01*
G01X553292Y85364D02*
Y73101D01*
G01X554066Y86138D02*
X553292Y85364D01*
G01X554066Y90974D02*
Y86138D01*
G01X553366Y91674D02*
X554066Y90974D01*
G01X553366Y105438D02*
Y91674D01*
G01X564192Y35425D02*
X563066Y34299D01*
G01X564192Y37300D02*
Y35425D01*
G01X563492Y38000D02*
X564192Y37300D01*
G01X563492Y45500D02*
Y38000D01*
G01X564192Y46200D02*
X563492Y45500D01*
G01X564192Y48000D02*
Y46200D01*
G01X563202Y48990D02*
X564192Y48000D01*
G01X563202Y53550D02*
Y48990D01*
G01X564292Y54640D02*
X563202Y53550D01*
G01X564292Y66001D02*
Y54640D01*
G01X563066Y67227D02*
X564292Y66001D01*
G01X563066Y72239D02*
Y67227D01*
G01X564192Y73365D02*
X563066Y72239D01*
G01X564192Y74400D02*
Y73365D01*
G01X563392Y75200D02*
X564192Y74400D01*
G01X563392Y83500D02*
Y75200D01*
G01X564192Y84300D02*
X563392Y83500D01*
G01X564192Y85648D02*
Y84300D01*
G01X563466Y86374D02*
X564192Y85648D01*
G01X563466Y91138D02*
Y86374D01*
G01X564192Y91864D02*
X563466Y91138D01*
G01X564192Y103300D02*
Y91864D01*
G01X587666Y35401D02*
X586866Y34601D01*
G01X587666Y36826D02*
Y35401D01*
G01X586892Y37600D02*
X587666Y36826D01*
G01X586892Y45626D02*
Y37600D01*
G01X587666Y46400D02*
X586892Y45626D01*
G01X587666Y47914D02*
Y46400D01*
G01X586866Y48714D02*
X587666Y47914D01*
G01X586866Y53414D02*
Y48714D01*
G01X587266Y53814D02*
X586866Y53414D01*
G01X587266Y66575D02*
Y53814D01*
G01X586866Y66975D02*
X587266Y66575D01*
G01X586866Y72575D02*
Y66975D01*
G01X587666Y73375D02*
X586866Y72575D01*
G01X587666Y74926D02*
Y73375D01*
G01X587092Y75500D02*
X587666Y74926D01*
G01X587092Y83526D02*
Y75500D01*
G01X587666Y84100D02*
X587092Y83526D01*
G01X587666Y85714D02*
Y84100D01*
G01X586866Y86514D02*
X587666Y85714D01*
G01X586866Y91214D02*
Y86514D01*
G01X587266Y91614D02*
X586866Y91214D01*
G01X587266Y100827D02*
Y91614D01*
G01X557255Y35363D02*
X556792Y34900D01*
G01X557255Y36800D02*
Y35363D01*
G01X556592Y37463D02*
X557255Y36800D01*
G01X556592Y45400D02*
Y37463D01*
G01X557255Y46063D02*
X556592Y45400D01*
G01X557255Y48014D02*
Y46063D01*
G01X556655Y48614D02*
X557255Y48014D01*
G01X556655Y53526D02*
Y48614D01*
G01X557392Y54263D02*
X556655Y53526D01*
G01X557392Y66233D02*
Y54263D01*
G01X556566Y67059D02*
X557392Y66233D01*
G01X556566Y72375D02*
Y67059D01*
G01X557266Y73075D02*
X556566Y72375D01*
G01X557266Y74800D02*
Y73075D01*
G01X556592Y75474D02*
X557266Y74800D01*
G01X556592Y83300D02*
Y75474D01*
G01X557266Y83974D02*
X556592Y83300D01*
G01X557266Y85674D02*
Y83974D01*
G01X556566Y86374D02*
X557266Y85674D01*
G01X556566Y90938D02*
Y86374D01*
G01X557292Y91664D02*
X556566Y90938D01*
G01X557292Y103000D02*
Y91664D01*
G01X590173Y35227D02*
X590773Y34627D01*
G01X590173Y36900D02*
Y35227D01*
G01X590999Y37726D02*
X590173Y36900D01*
G01X590999Y45400D02*
Y37726D01*
G01X590173Y46226D02*
X590999Y45400D01*
G01X590173Y47938D02*
Y46226D01*
G01X590873Y48638D02*
X590173Y47938D01*
G01X590873Y53214D02*
Y48638D01*
G01X590223Y53864D02*
X590873Y53214D01*
G01X590223Y66499D02*
Y53864D01*
G01X590773Y67049D02*
X590223Y66499D01*
G01X590773Y72527D02*
Y67049D01*
G01X590173Y73127D02*
X590773Y72527D01*
G01X590173Y74874D02*
Y73127D01*
G01X590699Y75400D02*
X590173Y74874D01*
G01X590699Y83574D02*
Y75400D01*
G01X590173Y84100D02*
X590699Y83574D01*
G01X590173Y85914D02*
Y84100D01*
G01X590873Y86614D02*
X590173Y85914D01*
G01X590873Y91274D02*
Y86614D01*
G01X590273Y91874D02*
X590873Y91274D01*
G01X590273Y93674D02*
Y91874D01*
G01X590992Y94393D02*
X590273Y93674D01*
G01X590992Y119699D02*
Y94393D01*
G01X560055Y35237D02*
X560655Y34637D01*
G01X560055Y37000D02*
Y35237D01*
G01X560792Y37737D02*
X560055Y37000D01*
G01X560792Y45300D02*
Y37737D01*
G01X560055Y46037D02*
X560792Y45300D01*
G01X560055Y48064D02*
Y46037D01*
G01X560566Y48575D02*
X560055Y48064D01*
G01X560566Y53453D02*
Y48575D01*
G01X560105Y53914D02*
X560566Y53453D01*
G01X560105Y66598D02*
Y53914D01*
G01X560566Y67059D02*
X560105Y66598D01*
G01X560566Y72627D02*
Y67059D01*
G01X559984Y73209D02*
X560566Y72627D01*
G01X559984Y74592D02*
Y73209D01*
G01X560592Y75200D02*
X559984Y74592D01*
G01X560592Y83492D02*
Y75200D01*
G01X559984Y84100D02*
X560592Y83492D01*
G01X559984Y85492D02*
Y84100D01*
G01X560459Y85967D02*
X559984Y85492D01*
G01X560459Y91281D02*
Y85967D01*
G01X560192Y91548D02*
X560459Y91281D01*
G01X560192Y102600D02*
Y91548D01*
G01X593492Y97205D02*
Y95548D01*
G01X594052Y97765D02*
X593492Y97205D01*
G01X595432Y97765D02*
X594052D01*
G01X595992Y98325D02*
X595432Y97765D01*
G01X595992Y99765D02*
Y98325D01*
G01X595432Y100325D02*
X595992Y99765D01*
G01X594052Y100325D02*
X595432D01*
G01X593492Y100885D02*
X594052Y100325D01*
G01X593492Y102325D02*
Y100885D01*
G01X594052Y102885D02*
X593492Y102325D01*
G01X595432Y102885D02*
X594052D01*
G01X595992Y103445D02*
X595432Y102885D01*
G01X595992Y104885D02*
Y103445D01*
G01X595432Y105445D02*
X595992Y104885D01*
G01X594052Y105445D02*
X595432D01*
G01X593492Y106005D02*
X594052Y105445D01*
G01X593492Y107445D02*
Y106005D01*
G01X594052Y108005D02*
X593492Y107445D01*
G01X595432Y108005D02*
X594052D01*
G01X595992Y108565D02*
X595432Y108005D01*
G01X595992Y110005D02*
Y108565D01*
G01X595432Y110565D02*
X595992Y110005D01*
G01X594052Y110565D02*
X595432D01*
G01X593492Y111125D02*
X594052Y110565D01*
G01X593492Y120400D02*
Y111125D01*
G01X572284Y103108D02*
X573266Y102126D01*
G01X572284Y121941D02*
Y103108D01*
G01X549966Y106274D02*
X550666Y105574D01*
G01X549966Y110774D02*
Y106274D01*
G01X550420Y111228D02*
X549966Y110774D01*
G01X550420Y116347D02*
Y111228D01*
G01X569784Y102207D02*
X570499Y101492D01*
G01X569784Y121409D02*
Y102207D01*
G01X553180Y138013D02*
X569784Y121409D01*
G01X553179Y138013D02*
X553180D01*
G01X552160Y139032D02*
X553179Y138013D01*
G01X551368Y139032D02*
X552160D01*
G01X550460Y138124D02*
X551368Y139032D01*
G01X549668Y138124D02*
X550460D01*
G01X548649Y139143D02*
X549668Y138124D01*
G01X548649Y139935D02*
Y139143D01*
G01X549557Y140843D02*
X548649Y139935D01*
G01X549557Y141635D02*
Y140843D01*
G01X548538Y142654D02*
X549557Y141635D01*
G01X547746Y142654D02*
X548538D01*
G01X546838Y141746D02*
X547746Y142654D01*
G01X546046Y141746D02*
X546838D01*
G01X545027Y142765D02*
X546046Y141746D01*
G01X545027Y143557D02*
Y142765D01*
G01X545935Y144465D02*
X545027Y143557D01*
G01X545935Y145257D02*
Y144465D01*
G01X544916Y146276D02*
X545935Y145257D01*
G01X544124Y146276D02*
X544916D01*
G01X543216Y145368D02*
X544124Y146276D01*
G01X542424Y145368D02*
X543216D01*
G01X541405Y146387D02*
X542424Y145368D01*
G01X541405Y147179D02*
Y146387D01*
G01X542313Y148087D02*
X541405Y147179D01*
G01X542313Y148879D02*
Y148087D01*
G01X541294Y149898D02*
X542313Y148879D01*
G01X540502Y149898D02*
X541294D01*
G01X598792Y118600D02*
Y95500D01*
G01X567284Y102592D02*
X566784Y102092D01*
G01X567284Y117309D02*
Y102592D01*
G01X565601Y118992D02*
X567284Y117309D01*
G01X565600Y119784D02*
X565601Y118992D01*
G01X566757Y120941D02*
X565600Y119784D01*
G01X566757Y121733D02*
Y120941D01*
G01X565737Y122753D02*
X566757Y121733D01*
G01X564947Y122752D02*
X565737Y122753D01*
G01X563790Y121595D02*
X564947Y122752D01*
G01X562998Y121595D02*
X563790D01*
G01X561979Y122614D02*
X562998Y121595D01*
G01X561978Y123406D02*
X561979Y122614D01*
G01X563135Y124563D02*
X561978Y123406D01*
G01X563135Y125355D02*
Y124563D01*
G01X562115Y126375D02*
X563135Y125355D01*
G01X561325Y126374D02*
X562115Y126375D01*
G01X560168Y125217D02*
X561325Y126374D01*
G01X559376Y125217D02*
X560168D01*
G01X558357Y126236D02*
X559376Y125217D01*
G01X558355Y127737D02*
X558357Y126236D01*
G01X557253Y128839D02*
X558355Y127737D01*
G01X555754Y128839D02*
X557253D01*
G01X553932Y106004D02*
X553366Y105438D01*
G01X553932Y110808D02*
Y106004D01*
G01X553284Y111456D02*
X553932Y110808D01*
G01X553284Y117191D02*
Y111456D01*
G01X564784Y103892D02*
X564192Y103300D01*
G01X564784Y117209D02*
Y103892D01*
G01X585966Y102127D02*
X587266Y100827D01*
G01X585966Y104657D02*
Y102127D01*
G01X586526Y105217D02*
X585966Y104657D01*
G01X588432Y105217D02*
X586526D01*
G01X588992Y105777D02*
X588432Y105217D01*
G01X588992Y107217D02*
Y105777D01*
G01X588432Y107777D02*
X588992Y107217D01*
G01X586526Y107777D02*
X588432D01*
G01X585966Y108337D02*
X586526Y107777D01*
G01X585966Y109777D02*
Y108337D01*
G01X586526Y110337D02*
X585966Y109777D01*
G01X588432Y110337D02*
X586526D01*
G01X588992Y110897D02*
X588432Y110337D01*
G01X588992Y112337D02*
Y110897D01*
G01X588432Y112897D02*
X588992Y112337D01*
G01X586526Y112897D02*
X588432D01*
G01X585966Y113457D02*
X586526Y112897D01*
G01X585966Y114897D02*
Y113457D01*
G01X586526Y115457D02*
X585966Y114897D01*
G01X588432Y115457D02*
X586526D01*
G01X588992Y116017D02*
X588432Y115457D01*
G01X588992Y117457D02*
Y116017D01*
G01X588432Y118017D02*
X588992Y117457D01*
G01X586526Y118017D02*
X588432D01*
G01X585966Y118577D02*
X586526Y118017D01*
G01X585966Y121626D02*
Y118577D01*
G01X558000Y103708D02*
X557292Y103000D01*
G01X558000Y104840D02*
Y103708D01*
G01X556466Y106374D02*
X558000Y104840D01*
G01X556466Y110638D02*
Y106374D01*
G01X558192Y112364D02*
X556466Y110638D01*
G01X558192Y115819D02*
Y112364D01*
G01X560692Y103100D02*
X560192Y102600D01*
G01X560692Y116855D02*
Y103100D01*
G01X551543Y484209D02*
X549112D01*
G01X557266Y489932D02*
X551543Y484209D01*
G01X557266Y491452D02*
Y489932D01*
G01X556892Y491826D02*
X557266Y491452D01*
G01X556892Y497478D02*
Y491826D01*
G01X557255Y497841D02*
X556892Y497478D01*
G01X557255Y500337D02*
Y497841D01*
G01X556492Y501100D02*
X557255Y500337D01*
G01X556492Y508637D02*
Y501100D01*
G01X557255Y509400D02*
X556492Y508637D01*
G01X557255Y511157D02*
Y509400D01*
G01X556755Y511657D02*
X557255Y511157D01*
G01X556755Y516563D02*
Y511657D01*
G01X557892Y517700D02*
X556755Y516563D01*
G01X557892Y519013D02*
Y517700D01*
G01X556992Y519913D02*
X557892Y519013D01*
G01X556992Y527800D02*
Y519913D01*
G01X540360Y470172D02*
Y469310D01*
G01X541350Y472874D02*
X540488D01*
G01X542206Y472018D02*
X541350Y472874D01*
G01X543068Y472018D02*
X542206D01*
G01X544052Y473002D02*
X543068Y472018D01*
G01X544052Y473864D02*
Y473002D01*
G01X543196Y474720D02*
X544052Y473864D01*
G01X543196Y475582D02*
Y474720D01*
G01X544180Y476566D02*
X543196Y475582D01*
G01X545042Y476566D02*
X544180D01*
G01X545898Y475710D02*
X545042Y476566D01*
G01X546760Y475710D02*
X545898D01*
G01X547744Y476694D02*
X546760Y475710D01*
G01X547744Y477556D02*
Y476694D01*
G01X546888Y478412D02*
X547744Y477556D01*
G01X546888Y479274D02*
Y478412D01*
G01X547872Y480258D02*
X546888Y479274D01*
G01X548734Y480258D02*
X547872D01*
G01X549590Y479402D02*
X548734Y480258D01*
G01X550452Y479402D02*
X549590D01*
G01X560692Y489642D02*
X550452Y479402D01*
G01X560692Y497200D02*
Y489642D01*
G01X560292Y497600D02*
X560692Y497200D01*
G01X560292Y509000D02*
Y497600D01*
G01X560055Y509237D02*
X560292Y509000D01*
G01X560055Y511657D02*
Y509237D01*
G01X560655Y512257D02*
X560055Y511657D01*
G01X560655Y516807D02*
Y512257D01*
G01X560105Y517357D02*
X560655Y516807D01*
G01X560105Y519300D02*
Y517357D01*
G01X560392Y519587D02*
X560105Y519300D01*
G01X560392Y527600D02*
Y519587D01*
G01X563806Y517197D02*
Y529586D01*
G01X563415Y516806D02*
X563806Y517197D01*
G01X563415Y511448D02*
Y516806D01*
G01X563806Y511057D02*
X563415Y511448D01*
G01X563806Y487059D02*
Y511057D01*
G01X590492Y519526D02*
Y527700D01*
G01X590266Y519300D02*
X590492Y519526D01*
G01X590266Y517357D02*
Y519300D01*
G01X591066Y516557D02*
X590266Y517357D01*
G01X591066Y512157D02*
Y516557D01*
G01X590166Y511257D02*
X591066Y512157D01*
G01X590166Y509200D02*
Y511257D01*
G01X591158Y508208D02*
X590166Y509200D01*
G01X591158Y507004D02*
Y508208D01*
G01X590548Y506394D02*
X591158Y507004D01*
G01X588664Y506394D02*
X590548D01*
G01X587998Y505728D02*
X588664Y506394D01*
G01X587998Y503748D02*
Y505728D01*
G01X588552Y503194D02*
X587998Y503748D01*
G01X591135Y503194D02*
X588552D01*
G01X591745Y502584D02*
X591135Y503194D01*
G01X591745Y500604D02*
Y502584D01*
G01X591135Y499994D02*
X591745Y500604D01*
G01X588525Y499994D02*
X591135D01*
G01X587915Y499384D02*
X588525Y499994D01*
G01X587915Y497404D02*
Y499384D01*
G01X588525Y496794D02*
X587915Y497404D01*
G01X590548Y496794D02*
X588525D01*
G01X591158Y496184D02*
X590548Y496794D01*
G01X591158Y494893D02*
Y496184D01*
G01X588466Y492201D02*
X591158Y494893D01*
G01X588466Y483950D02*
Y492201D01*
G01X550455Y517357D02*
Y529842D01*
G01X550055Y516957D02*
X550455Y517357D01*
G01X550055Y512057D02*
Y516957D01*
G01X550453Y511659D02*
X550055Y512057D01*
G01X550453Y497639D02*
Y511659D01*
G01X550192Y497378D02*
X550453Y497639D01*
G01X550192Y495100D02*
Y497378D01*
G01X548992Y493900D02*
X550192Y495100D01*
G01X548992Y488787D02*
Y493900D01*
G01X548492Y488287D02*
X548992Y488787D01*
G01X547574Y488287D02*
X548492D01*
G01X567092Y519626D02*
Y527500D01*
G01X566666Y519200D02*
X567092Y519626D01*
G01X566666Y517457D02*
Y519200D01*
G01X566992Y517131D02*
X566666Y517457D01*
G01X566992Y511823D02*
Y517131D01*
G01X566666Y511497D02*
X566992Y511823D01*
G01X566666Y509052D02*
Y511497D01*
G01X567205Y508513D02*
X566666Y509052D01*
G01X567205Y486993D02*
Y508513D01*
G01X594455Y517562D02*
Y529377D01*
G01X593292Y516399D02*
X594455Y517562D01*
G01X593292Y511931D02*
Y516399D01*
G01X594066Y511157D02*
X593292Y511931D01*
G01X594066Y494174D02*
Y511157D01*
G01X590966Y491074D02*
X594066Y494174D01*
G01X590966Y483434D02*
Y491074D01*
G01X570427Y517318D02*
Y529606D01*
G01X569416Y516307D02*
X570427Y517318D01*
G01X569416Y512057D02*
Y516307D01*
G01X570539Y510934D02*
X569416Y512057D01*
G01X570539Y486359D02*
Y510934D01*
G01X573692Y519526D02*
Y528100D01*
G01X573266Y519100D02*
X573692Y519526D01*
G01X573266Y509326D02*
Y519100D01*
G01X573792Y508800D02*
X573266Y509326D01*
G01X573792Y501000D02*
Y508800D01*
G01X573266Y500474D02*
X573792Y501000D01*
G01X573266Y485290D02*
Y500474D01*
G01X596916Y517357D02*
Y529816D01*
G01X597466Y516807D02*
X596916Y517357D01*
G01X597466Y511973D02*
Y516807D01*
G01X596866Y511373D02*
X597466Y511973D01*
G01X596866Y509326D02*
Y511373D01*
G01X596213Y508673D02*
X596866Y509326D01*
G01X596213Y491101D02*
Y508673D01*
G01X595712Y490600D02*
X596213Y491101D01*
G01X593892Y490600D02*
X595712D01*
G01X593092Y489800D02*
X593892Y490600D01*
G01X593092Y488200D02*
Y489800D01*
G01X593592Y487700D02*
X593092Y488200D01*
G01X595813Y487700D02*
X593592D01*
G01X596213Y487300D02*
X595813Y487700D01*
G01X596213Y485774D02*
Y487300D01*
G01X587092Y519774D02*
Y527700D01*
G01X587266Y519600D02*
X587092Y519774D01*
G01X587266Y517357D02*
Y519600D01*
G01X586866Y516957D02*
X587266Y517357D01*
G01X586866Y512057D02*
Y516957D01*
G01X587666Y511257D02*
X586866Y512057D01*
G01X587666Y509674D02*
Y511257D01*
G01X585933Y507941D02*
X587666Y509674D01*
G01X585933Y484601D02*
Y507941D01*
G01X549950Y486332D02*
X548554D01*
G01X553092Y489474D02*
X549950Y486332D01*
G01X553092Y499900D02*
Y489474D01*
G01X553921Y500729D02*
X553092Y499900D01*
G01X553921Y508934D02*
Y500729D01*
G01X553355Y509500D02*
X553921Y508934D01*
G01X553355Y511257D02*
Y509500D01*
G01X554255Y512157D02*
X553355Y511257D01*
G01X554255Y516557D02*
Y512157D01*
G01X553455Y517357D02*
X554255Y516557D01*
G01X553455Y519400D02*
Y517357D01*
G01X553692Y519637D02*
X553455Y519400D01*
G01X553692Y527600D02*
Y519637D01*
G01X557540Y528348D02*
X556992Y527800D01*
G01X557540Y529481D02*
Y528348D01*
G01X556655Y530366D02*
X557540Y529481D01*
G01X556655Y535662D02*
Y530366D01*
G01X557492Y536499D02*
X556655Y535662D01*
G01X557492Y537663D02*
Y536499D01*
G01X556992Y538163D02*
X557492Y537663D01*
G01X556992Y546700D02*
Y538163D01*
G01X557255Y546963D02*
X556992Y546700D01*
G01X557255Y548957D02*
Y546963D01*
G01X556755Y549457D02*
X557255Y548957D01*
G01X556755Y554857D02*
Y549457D01*
G01X557555Y555657D02*
X556755Y554857D01*
G01X557555Y556900D02*
Y555657D01*
G01X556988Y557467D02*
X557555Y556900D01*
G01X556988Y565496D02*
Y557467D01*
G01X557555Y566063D02*
X556988Y565496D01*
G01X557555Y567297D02*
Y566063D01*
G01X556455Y568397D02*
X557555Y567297D01*
G01X556455Y573142D02*
Y568397D01*
G01X557355Y574042D02*
X556455Y573142D01*
G01X557355Y586507D02*
Y574042D01*
G01X553955Y589907D02*
X557355Y586507D01*
G01X560105Y527887D02*
X560392Y527600D01*
G01X560105Y529816D02*
Y527887D01*
G01X560755Y530466D02*
X560105Y529816D01*
G01X560755Y535538D02*
Y530466D01*
G01X560055Y536238D02*
X560755Y535538D01*
G01X560055Y537600D02*
Y536238D01*
G01X560292Y537837D02*
X560055Y537600D01*
G01X560292Y546400D02*
Y537837D01*
G01X560055Y546637D02*
X560292Y546400D01*
G01X560055Y549457D02*
Y546637D01*
G01X560655Y550057D02*
X560055Y549457D01*
G01X560655Y554607D02*
Y550057D01*
G01X560105Y555157D02*
X560655Y554607D01*
G01X560105Y557000D02*
Y555157D01*
G01X560392Y557287D02*
X560105Y557000D01*
G01X560392Y565400D02*
Y557287D01*
G01X560105Y565687D02*
X560392Y565400D01*
G01X560105Y567647D02*
Y565687D01*
G01X560955Y568497D02*
X560105Y567647D01*
G01X560955Y573038D02*
Y568497D01*
G01X559955Y574038D02*
X560955Y573038D01*
G01X559955Y587470D02*
Y574038D01*
G01X558659Y588766D02*
X559955Y587470D01*
G01X563916Y586457D02*
X560766Y589607D01*
G01X563916Y573942D02*
Y586457D01*
G01X562918Y572944D02*
X563916Y573942D01*
G01X562918Y568373D02*
Y572944D01*
G01X563966Y567325D02*
X562918Y568373D01*
G01X563966Y555157D02*
Y567325D01*
G01X563387Y554578D02*
X563966Y555157D01*
G01X563387Y549236D02*
Y554578D01*
G01X563722Y548901D02*
X563387Y549236D01*
G01X563722Y535898D02*
Y548901D01*
G01X563219Y535395D02*
X563722Y535898D01*
G01X563219Y530173D02*
Y535395D01*
G01X563806Y529586D02*
X563219Y530173D01*
G01X590123Y587368D02*
X588777Y588714D01*
G01X590166Y587368D02*
X590123D01*
G01X590166Y584326D02*
Y587368D01*
G01X590492Y584000D02*
X590166Y584326D01*
G01X590492Y575826D02*
Y584000D01*
G01X590166Y575500D02*
X590492Y575826D01*
G01X590166Y574127D02*
Y575500D01*
G01X590832Y573461D02*
X590166Y574127D01*
G01X590832Y568163D02*
Y573461D01*
G01X590266Y567597D02*
X590832Y568163D01*
G01X590266Y565626D02*
Y567597D01*
G01X590492Y565400D02*
X590266Y565626D01*
G01X590492Y557926D02*
Y565400D01*
G01X589792Y557226D02*
X590492Y557926D01*
G01X589792Y555199D02*
Y557226D01*
G01X591066Y553925D02*
X589792Y555199D01*
G01X591066Y549957D02*
Y553925D01*
G01X589792Y548683D02*
X591066Y549957D01*
G01X589792Y547000D02*
Y548683D01*
G01X590492Y546300D02*
X589792Y547000D01*
G01X590492Y539000D02*
Y546300D01*
G01X589853Y538361D02*
X590492Y539000D01*
G01X589853Y536436D02*
Y538361D01*
G01X590966Y535323D02*
X589853Y536436D01*
G01X590966Y530542D02*
Y535323D01*
G01X590266Y529842D02*
X590966Y530542D01*
G01X590266Y527926D02*
Y529842D01*
G01X590492Y527700D02*
X590266Y527926D01*
G01X550508Y586704D02*
X548301Y588911D01*
G01X550508Y573895D02*
Y586704D01*
G01X550006Y573393D02*
X550508Y573895D01*
G01X550006Y568046D02*
Y573393D01*
G01X550655Y567397D02*
X550006Y568046D01*
G01X550655Y554963D02*
Y567397D01*
G01X550090Y554398D02*
X550655Y554963D01*
G01X550090Y549402D02*
Y554398D01*
G01X550509Y548983D02*
X550090Y549402D01*
G01X550509Y536216D02*
Y548983D01*
G01X550055Y535762D02*
X550509Y536216D01*
G01X550055Y530242D02*
Y535762D01*
G01X550455Y529842D02*
X550055Y530242D01*
G01X566566Y587200D02*
X565052Y588714D01*
G01X566566Y584126D02*
Y587200D01*
G01X566992Y583700D02*
X566566Y584126D01*
G01X566992Y575626D02*
Y583700D01*
G01X566566Y575200D02*
X566992Y575626D01*
G01X566566Y573256D02*
Y575200D01*
G01X567166Y572656D02*
X566566Y573256D01*
G01X567166Y568497D02*
Y572656D01*
G01X566666Y567997D02*
X567166Y568497D01*
G01X566666Y565926D02*
Y567997D01*
G01X566992Y565600D02*
X566666Y565926D01*
G01X566992Y557326D02*
Y565600D01*
G01X566666Y557000D02*
X566992Y557326D01*
G01X566666Y555257D02*
Y557000D01*
G01X567092Y554831D02*
X566666Y555257D01*
G01X567092Y548983D02*
Y554831D01*
G01X566566Y548457D02*
X567092Y548983D01*
G01X566566Y546626D02*
Y548457D01*
G01X567092Y546100D02*
X566566Y546626D01*
G01X567092Y538026D02*
Y546100D01*
G01X566566Y537500D02*
X567092Y538026D01*
G01X566566Y535542D02*
Y537500D01*
G01X566916Y535192D02*
X566566Y535542D01*
G01X566916Y530242D02*
Y535192D01*
G01X566666Y529992D02*
X566916Y530242D01*
G01X566666Y527926D02*
Y529992D01*
G01X567092Y527500D02*
X566666Y527926D01*
G01X594034Y586639D02*
X591688Y588985D01*
G01X594034Y573910D02*
Y586639D01*
G01X593140Y573016D02*
X594034Y573910D01*
G01X593140Y568523D02*
Y573016D01*
G01X594201Y567462D02*
X593140Y568523D01*
G01X594201Y555492D02*
Y567462D01*
G01X593253Y554544D02*
X594201Y555492D01*
G01X593253Y549770D02*
Y554544D01*
G01X594287Y548736D02*
X593253Y549770D01*
G01X594287Y536329D02*
Y548736D01*
G01X593142Y535184D02*
X594287Y536329D01*
G01X593142Y530690D02*
Y535184D01*
G01X594455Y529377D02*
X593142Y530690D01*
G01X570483Y586590D02*
X567266Y589807D01*
G01X570483Y574090D02*
Y586590D01*
G01X569589Y573196D02*
X570483Y574090D01*
G01X569589Y568244D02*
Y573196D01*
G01X570455Y567378D02*
X569589Y568244D01*
G01X570455Y555146D02*
Y567378D01*
G01X569416Y554107D02*
X570455Y555146D01*
G01X569416Y549857D02*
Y554107D01*
G01X570483Y548790D02*
X569416Y549857D01*
G01X570483Y536291D02*
Y548790D01*
G01X569533Y535341D02*
X570483Y536291D01*
G01X569533Y530500D02*
Y535341D01*
G01X570427Y529606D02*
X569533Y530500D01*
G01X573266Y586443D02*
X571345Y588364D01*
G01X573266Y584426D02*
Y586443D01*
G01X573692Y584000D02*
X573266Y584426D01*
G01X573692Y575926D02*
Y584000D01*
G01X573266Y575500D02*
X573692Y575926D01*
G01X573266Y566026D02*
Y575500D01*
G01X573692Y565600D02*
X573266Y566026D01*
G01X573692Y557000D02*
Y565600D01*
G01X573266Y556574D02*
X573692Y557000D01*
G01X573266Y546726D02*
Y556574D01*
G01X573792Y546200D02*
X573266Y546726D01*
G01X573792Y538226D02*
Y546200D01*
G01X573266Y537700D02*
X573792Y538226D01*
G01X573266Y528526D02*
Y537700D01*
G01X573692Y528100D02*
X573266Y528526D01*
G01X596766Y587470D02*
X595470Y588766D01*
G01X596766Y574226D02*
Y587470D01*
G01X597766Y573226D02*
X596766Y574226D01*
G01X597766Y568497D02*
Y573226D01*
G01X596916Y567647D02*
X597766Y568497D01*
G01X596916Y555157D02*
Y567647D01*
G01X597466Y554607D02*
X596916Y555157D01*
G01X597466Y550057D02*
Y554607D01*
G01X596866Y549457D02*
X597466Y550057D01*
G01X596866Y536226D02*
Y549457D01*
G01X597566Y535526D02*
X596866Y536226D01*
G01X597566Y530466D02*
Y535526D01*
G01X596916Y529816D02*
X597566Y530466D01*
G01X588041Y585982D02*
X584766Y589257D01*
G01X588041Y584849D02*
Y585982D01*
G01X587092Y583900D02*
X588041Y584849D01*
G01X587092Y575974D02*
Y583900D01*
G01X587666Y575400D02*
X587092Y575974D01*
G01X587666Y574474D02*
Y575400D01*
G01X586393Y573201D02*
X587666Y574474D01*
G01X586393Y568470D02*
Y573201D01*
G01X587611Y567252D02*
X586393Y568470D01*
G01X587611Y566119D02*
Y567252D01*
G01X587092Y565600D02*
X587611Y566119D01*
G01X587092Y557174D02*
Y565600D01*
G01X587813Y556453D02*
X587092Y557174D01*
G01X587813Y555320D02*
Y556453D01*
G01X586592Y554099D02*
X587813Y555320D01*
G01X586592Y550131D02*
Y554099D01*
G01X587666Y549057D02*
X586592Y550131D01*
G01X587666Y546874D02*
Y549057D01*
G01X587092Y546300D02*
X587666Y546874D01*
G01X587092Y538600D02*
Y546300D01*
G01X587666Y538026D02*
X587092Y538600D01*
G01X587666Y536474D02*
Y538026D01*
G01X586866Y535674D02*
X587666Y536474D01*
G01X586866Y530242D02*
Y535674D01*
G01X587266Y529842D02*
X586866Y530242D01*
G01X587266Y527874D02*
Y529842D01*
G01X587092Y527700D02*
X587266Y527874D01*
G01X553455Y527837D02*
X553692Y527600D01*
G01X553455Y529842D02*
Y527837D01*
G01X554155Y530542D02*
X553455Y529842D01*
G01X554155Y535738D02*
Y530542D01*
G01X553355Y536538D02*
X554155Y535738D01*
G01X553355Y537700D02*
Y536538D01*
G01X553692Y538037D02*
X553355Y537700D01*
G01X553692Y546600D02*
Y538037D01*
G01X553355Y546937D02*
X553692Y546600D01*
G01X553355Y549057D02*
Y546937D01*
G01X554255Y549957D02*
X553355Y549057D01*
G01X554255Y554357D02*
Y549957D01*
G01X553155Y555457D02*
X554255Y554357D01*
G01X553155Y557100D02*
Y555457D01*
G01X553692Y557637D02*
X553155Y557100D01*
G01X553692Y565700D02*
Y557637D01*
G01X553455Y565937D02*
X553692Y565700D01*
G01X553455Y567597D02*
Y565937D01*
G01X554021Y568163D02*
X553455Y567597D01*
G01X554021Y573471D02*
Y568163D01*
G01X553355Y574137D02*
X554021Y573471D01*
G01X553355Y587325D02*
Y574137D01*
G01X551966Y588714D02*
X553355Y587325D01*
G01X553608Y605649D02*
X558659Y610700D01*
G01X553608Y595462D02*
Y605649D01*
G01X555313Y593757D02*
X553608Y595462D01*
G01X553955Y592399D02*
Y589907D01*
G01X555313Y593757D02*
X553955Y592399D01*
G01X556385Y604499D02*
X555313D01*
G01X557085Y603799D02*
X556385Y604499D01*
G01X557085Y602525D02*
Y603799D01*
G01X555948Y601388D02*
X557085Y602525D01*
G01X555948Y600312D02*
Y601388D01*
G01X556960Y599300D02*
X555948Y600312D01*
G01X556960Y598100D02*
Y599300D01*
G01X555948Y597088D02*
X556960Y598100D01*
G01X555948Y596012D02*
Y597088D01*
G01X557060Y594900D02*
X555948Y596012D01*
G01X557060Y592267D02*
Y594900D01*
G01X556885Y592092D02*
X557060Y592267D01*
G01X556885Y590400D02*
Y592092D01*
G01X558571Y588714D02*
X556885Y590400D01*
G01X558659Y588714D02*
X558571D01*
G01X558659D02*
Y588766D01*
G01X563978Y610300D02*
X564966D01*
G01X560923Y607245D02*
X563978Y610300D01*
G01X560923Y606057D02*
Y607245D01*
G01X560301Y605435D02*
X560923Y606057D01*
G01X560301Y595462D02*
Y605435D01*
G01X562006Y593757D02*
X560301Y595462D01*
G01X560766Y592517D02*
X562006Y593757D01*
G01X560766Y589607D02*
Y592517D01*
G01X586503Y604499D02*
X585431D01*
G01X587203Y603799D02*
X586503Y604499D01*
G01X587203Y602525D02*
Y603799D01*
G01X586066Y601388D02*
X587203Y602525D01*
G01X586066Y600312D02*
Y601388D01*
G01X587078Y599300D02*
X586066Y600312D01*
G01X587078Y598100D02*
Y599300D01*
G01X586066Y597088D02*
X587078Y598100D01*
G01X586066Y596012D02*
Y597088D01*
G01X587178Y594900D02*
X586066Y596012D01*
G01X587178Y592267D02*
Y594900D01*
G01X587003Y592092D02*
X587178Y592267D01*
G01X587003Y590400D02*
Y592092D01*
G01X588689Y588714D02*
X587003Y590400D01*
G01X588777Y588714D02*
X588689D01*
G01X546915Y605649D02*
X551966Y610700D01*
G01X546915Y595462D02*
Y605649D01*
G01X548620Y593757D02*
X546915Y595462D01*
G01X548301Y593438D02*
X548620Y593757D01*
G01X548301Y588911D02*
Y593438D01*
G01X563078Y604499D02*
X562006D01*
G01X563678Y603899D02*
X563078Y604499D01*
G01X563678Y603001D02*
Y603899D01*
G01X562641Y601964D02*
X563678Y603001D01*
G01X562641Y600736D02*
Y601964D01*
G01X563578Y599799D02*
X562641Y600736D01*
G01X563578Y598401D02*
Y599799D01*
G01X562641Y597464D02*
X563578Y598401D01*
G01X562641Y596136D02*
Y597464D01*
G01X563778Y594999D02*
X562641Y596136D01*
G01X563778Y593100D02*
Y594999D01*
G01X563278Y592600D02*
X563778Y593100D01*
G01X563278Y590400D02*
Y592600D01*
G01X564964Y588714D02*
X563278Y590400D01*
G01X565052Y588714D02*
X564964D01*
G01X590419Y605649D02*
X595470Y610700D01*
G01X590419Y595462D02*
Y605649D01*
G01X592124Y593757D02*
X590419Y595462D01*
G01X591688Y593321D02*
X592124Y593757D01*
G01X591688Y588985D02*
Y593321D01*
G01X570179Y610300D02*
X571345D01*
G01X566994Y607115D02*
X570179Y610300D01*
G01X566994Y595462D02*
Y607115D01*
G01X568699Y593757D02*
X566994Y595462D01*
G01X567266Y592324D02*
X568699Y593757D01*
G01X567266Y589807D02*
Y592324D01*
G01X569679Y604499D02*
X568699D01*
G01X570278Y603900D02*
X569679Y604499D01*
G01X570278Y602700D02*
Y603900D01*
G01X569334Y601756D02*
X570278Y602700D01*
G01X569334Y600544D02*
Y601756D01*
G01X570178Y599700D02*
X569334Y600544D01*
G01X570178Y598000D02*
Y599700D01*
G01X569334Y597156D02*
X570178Y598000D01*
G01X569334Y595736D02*
Y597156D01*
G01X570478Y594592D02*
X569334Y595736D01*
G01X570478Y592999D02*
Y594592D01*
G01X569571Y592092D02*
X570478Y592999D01*
G01X569571Y590400D02*
Y592092D01*
G01X571257Y588714D02*
X569571Y590400D01*
G01X571345Y588714D02*
X571257D01*
G01X571345Y588364D02*
Y588714D01*
G01X593196Y604499D02*
X592124D01*
G01X593896Y603799D02*
X593196Y604499D01*
G01X593896Y602525D02*
Y603799D01*
G01X592759Y601388D02*
X593896Y602525D01*
G01X592759Y600312D02*
Y601388D01*
G01X593771Y599300D02*
X592759Y600312D01*
G01X593771Y598100D02*
Y599300D01*
G01X592759Y597088D02*
X593771Y598100D01*
G01X592759Y596012D02*
Y597088D01*
G01X593871Y594900D02*
X592759Y596012D01*
G01X593871Y592267D02*
Y594900D01*
G01X593696Y592092D02*
X593871Y592267D01*
G01X593696Y590400D02*
Y592092D01*
G01X595382Y588714D02*
X593696Y590400D01*
G01X595470Y588714D02*
X595382D01*
G01X595470Y588766D02*
Y588714D01*
G01X583726Y605649D02*
X588777Y610700D01*
G01X583726Y595462D02*
Y605649D01*
G01X585431Y593757D02*
X583726Y595462D01*
G01X584766Y593092D02*
X585431Y593757D01*
G01X584766Y589257D02*
Y593092D01*
G01X549692Y604499D02*
X548620D01*
G01X550392Y603799D02*
X549692Y604499D01*
G01X550392Y602525D02*
Y603799D01*
G01X549255Y601388D02*
X550392Y602525D01*
G01X549255Y600312D02*
Y601388D01*
G01X550267Y599300D02*
X549255Y600312D01*
G01X550267Y598100D02*
Y599300D01*
G01X549255Y597088D02*
X550267Y598100D01*
G01X549255Y596012D02*
Y597088D01*
G01X550367Y594900D02*
X549255Y596012D01*
G01X550367Y592267D02*
Y594900D01*
G01X550192Y592092D02*
X550367Y592267D01*
G01X550192Y590400D02*
Y592092D01*
G01X551878Y588714D02*
X550192Y590400D01*
G01X551966Y588714D02*
X551878D01*
G01X781700Y-3233D02*
X782567Y-4100D01*
G01X781700Y-932D02*
Y-3233D01*
G01X780067Y701D02*
X781700Y-932D01*
G01X780067Y2000D02*
Y701D01*
G01X781417Y3350D02*
X780067Y2000D01*
G01X781417Y4250D02*
Y3350D01*
G01X780167Y5500D02*
X781417Y4250D01*
G01X780167Y6699D02*
Y5500D01*
G01X781700Y8232D02*
X780167Y6699D01*
G01X781700Y10200D02*
Y8232D01*
G01X778800Y13100D02*
X781700Y10200D01*
G01X778800Y16036D02*
Y13100D01*
G01X779921Y17157D02*
X778800Y16036D01*
G01X780638Y29611D02*
Y34239D01*
G01X781788Y28461D02*
X780638Y29611D01*
G01X781788Y25789D02*
Y28461D01*
G01X779488Y23489D02*
X781788Y25789D01*
G01X779488Y18912D02*
Y23489D01*
G01X779921Y18479D02*
X779488Y18912D01*
G01X779921Y17157D02*
Y18479D01*
G01Y-7779D02*
Y-9901D01*
G01X781800Y-5900D02*
X779921Y-7779D01*
G01X783200Y-5900D02*
X781800D01*
G01X784656Y-4444D02*
X783200Y-5900D01*
G01X784656Y-3100D02*
Y-4444D01*
G01X784040Y-2484D02*
X784656Y-3100D01*
G01X784040Y10641D02*
Y-2484D01*
G01X782567Y12114D02*
X784040Y10641D01*
G01X784488Y25189D02*
Y37300D01*
G01X781988Y22689D02*
X784488Y25189D01*
G01X781988Y16688D02*
Y22689D01*
G01X780494Y15194D02*
X781988Y16688D01*
G01X780494Y14187D02*
Y15194D01*
G01X782567Y12114D02*
X780494Y14187D01*
G01X775100Y-3012D02*
X776188Y-4100D01*
G01X775100Y-1132D02*
Y-3012D01*
G01X773667Y301D02*
X775100Y-1132D01*
G01X773667Y1500D02*
Y301D01*
G01X775167Y3000D02*
X773667Y1500D01*
G01X775167Y4200D02*
Y3000D01*
G01X773717Y5650D02*
X775167Y4200D01*
G01X773717Y7049D02*
Y5650D01*
G01X775100Y8432D02*
X773717Y7049D01*
G01X775100Y10301D02*
Y8432D01*
G01X772300Y13101D02*
X775100Y10301D01*
G01X772300Y16229D02*
Y13101D01*
G01X773228Y17157D02*
X772300Y16229D01*
G01X774288Y29411D02*
Y34587D01*
G01X775188Y28511D02*
X774288Y29411D01*
G01X775188Y27087D02*
Y28511D01*
G01X773228Y25127D02*
X775188Y27087D01*
G01X773228Y17157D02*
Y25127D01*
G01Y-8347D02*
Y-9901D01*
G01X775475Y-6100D02*
X773228Y-8347D01*
G01X776699Y-6100D02*
X775475D01*
G01X778275Y-4524D02*
X776699Y-6100D01*
G01X778275Y-2900D02*
Y-4524D01*
G01X777500Y-2125D02*
X778275Y-2900D01*
G01X777500Y10888D02*
Y-2125D01*
G01X776274Y12114D02*
X777500Y10888D01*
G01X778000Y28156D02*
Y37400D01*
G01X775466Y16692D02*
X778000Y28156D01*
G01X774400Y15626D02*
X775466Y16692D01*
G01X774400Y13988D02*
Y15626D01*
G01X776274Y12114D02*
X774400Y13988D01*
G01X781800Y93588D02*
X780100Y95288D01*
G01X781800Y92100D02*
Y93588D01*
G01X780638Y90938D02*
X781800Y92100D01*
G01X780638Y86714D02*
Y90938D01*
G01X781988Y85364D02*
X780638Y86714D01*
G01X781988Y84100D02*
Y85364D01*
G01X781200Y83312D02*
X781988Y84100D01*
G01X781200Y75600D02*
Y83312D01*
G01X781988Y74812D02*
X781200Y75600D01*
G01X781988Y73389D02*
Y74812D01*
G01X780638Y72039D02*
X781988Y73389D01*
G01X780638Y67411D02*
Y72039D01*
G01X781988Y66061D02*
X780638Y67411D01*
G01X781988Y54488D02*
Y66061D01*
G01X780638Y53138D02*
X781988Y54488D01*
G01X780638Y48914D02*
Y53138D01*
G01X781988Y47564D02*
X780638Y48914D01*
G01X781988Y46200D02*
Y47564D01*
G01X781400Y45612D02*
X781988Y46200D01*
G01X781400Y37500D02*
Y45612D01*
G01X781988Y36912D02*
X781400Y37500D01*
G01X781988Y35589D02*
Y36912D01*
G01X780638Y34239D02*
X781988Y35589D01*
G01X784488Y94600D02*
X782600Y96488D01*
G01X784488Y84000D02*
Y94600D01*
G01X785100Y83388D02*
X784488Y84000D01*
G01X785100Y75600D02*
Y83388D01*
G01X784488Y74988D02*
X785100Y75600D01*
G01X784488Y46012D02*
Y74988D01*
G01X785054Y45446D02*
X784488Y46012D01*
G01X785054Y37866D02*
Y45446D01*
G01X784488Y37300D02*
X785054Y37866D01*
G01X775100Y92026D02*
Y154301D01*
G01X774288Y91214D02*
X775100Y92026D01*
G01X774288Y86414D02*
Y91214D01*
G01X775288Y85414D02*
X774288Y86414D01*
G01X775288Y83988D02*
Y85414D01*
G01X774600Y83300D02*
X775288Y83988D01*
G01X774600Y75400D02*
Y83300D01*
G01X775288Y74712D02*
X774600Y75400D01*
G01X775288Y73099D02*
Y74712D01*
G01X774288Y72099D02*
X775288Y73099D01*
G01X774288Y67111D02*
Y72099D01*
G01X775188Y66211D02*
X774288Y67111D01*
G01X775188Y54314D02*
Y66211D01*
G01X774288Y53414D02*
X775188Y54314D01*
G01X774288Y48614D02*
Y53414D01*
G01X775288Y47614D02*
X774288Y48614D01*
G01X775288Y46300D02*
Y47614D01*
G01X774600Y45612D02*
X775288Y46300D01*
G01X774600Y37800D02*
Y45612D01*
G01X775288Y37112D02*
X774600Y37800D01*
G01X775288Y35587D02*
Y37112D01*
G01X774288Y34587D02*
X775288Y35587D01*
G01X777600Y93160D02*
Y153993D01*
G01X778138Y90360D02*
X777600Y93160D01*
G01X778138Y87500D02*
Y90360D01*
G01X778106Y87266D02*
X778138Y87500D01*
G01X777788Y84900D02*
X778106Y87266D01*
G01X777788Y84000D02*
Y84900D01*
G01X778000Y83788D02*
X777788Y84000D01*
G01X778000Y66144D02*
Y83788D01*
G01X777888Y64800D02*
X778000Y66144D01*
G01X777888Y53864D02*
Y64800D01*
G01X778100Y53652D02*
X777888Y53864D01*
G01X778100Y48626D02*
Y53652D01*
G01X777900Y48426D02*
X778100Y48626D01*
G01X777900Y46200D02*
Y48426D01*
G01X778400Y45700D02*
X777900Y46200D01*
G01X778400Y37800D02*
Y45700D01*
G01X778000Y37400D02*
X778400Y37800D01*
G01X784300Y155967D02*
Y157957D01*
G01X783133Y154800D02*
X784300Y155967D01*
G01X781143Y154800D02*
X783133D01*
G01X780100Y153757D02*
X781143Y154800D01*
G01X780100Y95288D02*
Y153757D01*
G01X782600Y151601D02*
X787399Y156400D01*
G01X782600Y96488D02*
Y151601D01*
G01X775100Y154301D02*
X887429Y266630D01*
G01X777600Y153993D02*
X794254Y170647D01*
G01X785343Y159000D02*
X788101D01*
G01X784300Y157957D02*
X785343Y159000D01*
G01X781800Y445395D02*
Y498800D01*
G01X784895Y442300D02*
X781800Y445395D01*
G01X786901Y442300D02*
X784895D01*
G01X779300Y445185D02*
Y497900D01*
G01X784934Y439551D02*
X779300Y445185D01*
G01X786949Y439551D02*
X784934D01*
G01X784300Y464400D02*
Y499300D01*
G01X785800Y462900D02*
X784300Y464400D01*
G01X785800Y461300D02*
Y462900D01*
G01X784300Y459800D02*
X785800Y461300D01*
G01X784300Y451948D02*
Y459800D01*
G01X784860Y451388D02*
X784300Y451948D01*
G01X790840Y451388D02*
X784860D01*
G01Y448828D02*
X790840D01*
G01X784300Y448268D02*
X784860Y448828D01*
G01X784300Y445800D02*
Y448268D01*
G01X785200Y444900D02*
X784300Y445800D01*
G01X789700Y444900D02*
X785200D01*
G01X776800Y445003D02*
Y495384D01*
G01X784603Y437200D02*
X776800Y445003D01*
G01X786500Y437200D02*
X784603D01*
G01X800400Y423300D02*
X786500Y437200D01*
G01X781600Y519788D02*
Y527200D01*
G01X782100Y519288D02*
X781600Y519788D01*
G01X782100Y517901D02*
Y519288D01*
G01X780767Y516568D02*
X782100Y517901D01*
G01X780767Y511932D02*
Y516568D01*
G01X781988Y510711D02*
X780767Y511932D01*
G01X781988Y509388D02*
Y510711D01*
G01X780034Y507434D02*
X781988Y509388D01*
G01X780034Y500566D02*
Y507434D01*
G01X781800Y498800D02*
X780034Y500566D01*
G01X778300Y519812D02*
Y527700D01*
G01X777888Y519400D02*
X778300Y519812D01*
G01X777888Y517457D02*
Y519400D01*
G01X778138Y517207D02*
X777888Y517457D01*
G01X778138Y511747D02*
Y517207D01*
G01X777645Y511254D02*
X778138Y511747D01*
G01X777645Y499555D02*
Y511254D01*
G01X779300Y497900D02*
X777645Y499555D01*
G01X785000Y519400D02*
Y527500D01*
G01X784488Y518888D02*
X785000Y519400D01*
G01X784488Y508812D02*
Y518888D01*
G01X784900Y508400D02*
X784488Y508812D01*
G01X784900Y506842D02*
Y508400D01*
G01X784290Y506232D02*
X784900Y506842D01*
G01X783080Y506232D02*
X784290D01*
G01X782470Y505622D02*
X783080Y506232D01*
G01X782470Y503642D02*
Y505622D01*
G01X783080Y503032D02*
X782470Y503642D01*
G01X784290Y503032D02*
X783080D01*
G01X784900Y502422D02*
X784290Y503032D01*
G01X784900Y499900D02*
Y502422D01*
G01X784300Y499300D02*
X784900Y499900D01*
G01X775188Y518256D02*
Y528650D01*
G01X774288Y516083D02*
X775188Y518256D01*
G01X774288Y512677D02*
Y516083D01*
G01X774816Y511400D02*
X774288Y512677D01*
G01X774982Y511000D02*
X774816Y511400D01*
G01X775100Y510716D02*
X774982Y511000D01*
G01X775100Y499488D02*
Y510716D01*
G01X775419Y498717D02*
X775100Y499488D01*
G01X776800Y495384D02*
X775419Y498717D01*
G01X781838Y586457D02*
X778488Y589807D01*
G01X781838Y584638D02*
Y586457D01*
G01X781600Y584400D02*
X781838Y584638D01*
G01X781600Y575838D02*
Y584400D01*
G01X781838Y575600D02*
X781600Y575838D01*
G01X781838Y574239D02*
Y575600D01*
G01X780688Y573089D02*
X781838Y574239D01*
G01X780688Y568367D02*
Y573089D01*
G01X781788Y567267D02*
X780688Y568367D01*
G01X781788Y565588D02*
Y567267D01*
G01X781600Y565400D02*
X781788Y565588D01*
G01X781600Y557288D02*
Y565400D01*
G01X781788Y557100D02*
X781600Y557288D01*
G01X781788Y555257D02*
Y557100D01*
G01X780638Y554107D02*
X781788Y555257D01*
G01X780638Y549857D02*
Y554107D01*
G01X781988Y548507D02*
X780638Y549857D01*
G01X781988Y546688D02*
Y548507D01*
G01X781600Y546300D02*
X781988Y546688D01*
G01X781600Y538088D02*
Y546300D01*
G01X781988Y537700D02*
X781600Y538088D01*
G01X781988Y536588D02*
Y537700D01*
G01X780638Y535238D02*
X781988Y536588D01*
G01X780638Y530617D02*
Y535238D01*
G01X781988Y529267D02*
X780638Y530617D01*
G01X781988Y527588D02*
Y529267D01*
G01X781600Y527200D02*
X781988Y527588D01*
G01X777788Y587200D02*
X776274Y588714D01*
G01X777788Y584512D02*
Y587200D01*
G01X778300Y584000D02*
X777788Y584512D01*
G01X778300Y575712D02*
Y584000D01*
G01X777788Y575200D02*
X778300Y575712D01*
G01X777788Y573256D02*
Y575200D01*
G01X778388Y572656D02*
X777788Y573256D01*
G01X778388Y568497D02*
Y572656D01*
G01X777888Y567997D02*
X778388Y568497D01*
G01X777888Y565612D02*
Y567997D01*
G01X778300Y565200D02*
X777888Y565612D01*
G01X778300Y557612D02*
Y565200D01*
G01X777888Y557200D02*
X778300Y557612D01*
G01X777888Y555257D02*
Y557200D01*
G01X778138Y555007D02*
X777888Y555257D01*
G01X778138Y548807D02*
Y555007D01*
G01X777788Y548457D02*
X778138Y548807D01*
G01X777788Y547012D02*
Y548457D01*
G01X778300Y546500D02*
X777788Y547012D01*
G01X778300Y538100D02*
Y546500D01*
G01X777788Y537588D02*
X778300Y538100D01*
G01X777788Y535542D02*
Y537588D01*
G01X778138Y535192D02*
X777788Y535542D01*
G01X778138Y530242D02*
Y535192D01*
G01X777888Y529992D02*
X778138Y530242D01*
G01X777888Y528112D02*
Y529992D01*
G01X778300Y527700D02*
X777888Y528112D01*
G01X784488Y586443D02*
X782567Y588364D01*
G01X784488Y584112D02*
Y586443D01*
G01X784900Y583700D02*
X784488Y584112D01*
G01X784900Y576012D02*
Y583700D01*
G01X784488Y575600D02*
X784900Y576012D01*
G01X784488Y565912D02*
Y575600D01*
G01X784900Y565500D02*
X784488Y565912D01*
G01X784900Y556600D02*
Y565500D01*
G01X784488Y556188D02*
X784900Y556600D01*
G01X784488Y546612D02*
Y556188D01*
G01X785000Y546100D02*
X784488Y546612D01*
G01X785000Y538200D02*
Y546100D01*
G01X784488Y537688D02*
X785000Y538200D01*
G01X784488Y528012D02*
Y537688D01*
G01X785000Y527500D02*
X784488Y528012D01*
G01X774234Y587825D02*
X772763Y589296D01*
G01X774933Y586137D02*
X774234Y587825D01*
G01X774933Y574251D02*
Y586137D01*
G01X774363Y572875D02*
X774933Y574251D01*
G01X774363Y568552D02*
Y572875D01*
G01X775188Y566560D02*
X774363Y568552D01*
G01X775188Y555672D02*
Y566560D01*
G01X774461Y553917D02*
X775188Y555672D01*
G01X774461Y550288D02*
Y553917D01*
G01X775100Y548745D02*
X774461Y550288D01*
G01X775100Y536824D02*
Y548745D01*
G01X774288Y534863D02*
X775100Y536824D01*
G01X774288Y530824D02*
Y534863D01*
G01X775188Y528650D02*
X774288Y530824D01*
G01X778216Y605949D02*
X782567Y610300D01*
G01X778216Y595462D02*
Y605949D01*
G01X779921Y593757D02*
X778216Y595462D01*
G01X778488Y592324D02*
X779921Y593757D01*
G01X778488Y589807D02*
Y592324D01*
G01X774300Y604499D02*
X773228D01*
G01X774900Y603899D02*
X774300Y604499D01*
G01X774900Y603001D02*
Y603899D01*
G01X773863Y601964D02*
X774900Y603001D01*
G01X773863Y600736D02*
Y601964D01*
G01X774800Y599799D02*
X773863Y600736D01*
G01X774800Y598401D02*
Y599799D01*
G01X773863Y597464D02*
X774800Y598401D01*
G01X773863Y596136D02*
Y597464D01*
G01X775000Y594999D02*
X773863Y596136D01*
G01X775000Y593100D02*
Y594999D01*
G01X774500Y592600D02*
X775000Y593100D01*
G01X774500Y590400D02*
Y592600D01*
G01X776186Y588714D02*
X774500Y590400D01*
G01X776274Y588714D02*
X776186D01*
G01X780901Y604499D02*
X779921D01*
G01X781500Y603900D02*
X780901Y604499D01*
G01X781500Y602700D02*
Y603900D01*
G01X780556Y601756D02*
X781500Y602700D01*
G01X780556Y600544D02*
Y601756D01*
G01X781400Y599700D02*
X780556Y600544D01*
G01X781400Y598000D02*
Y599700D01*
G01X780556Y597156D02*
X781400Y598000D01*
G01X780556Y595736D02*
Y597156D01*
G01X781700Y594592D02*
X780556Y595736D01*
G01X781700Y592999D02*
Y594592D01*
G01X780793Y592092D02*
X781700Y592999D01*
G01X780793Y590400D02*
Y592092D01*
G01X782479Y588714D02*
X780793Y590400D01*
G01X782567Y588714D02*
X782479D01*
G01X782567Y588364D02*
Y588714D01*
G01X771523Y605635D02*
X776188Y610300D01*
G01X771523Y595462D02*
Y605635D01*
G01X773228Y593757D02*
X771523Y595462D01*
G01X772763Y593292D02*
X773228Y593757D01*
G01X772763Y589296D02*
Y593292D01*
G01X818511Y-3233D02*
X819378Y-4100D01*
G01X818511Y-932D02*
Y-3233D01*
G01X816878Y701D02*
X818511Y-932D01*
G01X816878Y2000D02*
Y701D01*
G01X818228Y3350D02*
X816878Y2000D01*
G01X818228Y4250D02*
Y3350D01*
G01X816978Y5500D02*
X818228Y4250D01*
G01X816978Y6699D02*
Y5500D01*
G01X818511Y8232D02*
X816978Y6699D01*
G01X818511Y10200D02*
Y8232D01*
G01X815611Y13100D02*
X818511Y10200D01*
G01X815611Y16036D02*
Y13100D01*
G01X816732Y17157D02*
X815611Y16036D01*
G01X817449Y29601D02*
Y34249D01*
G01X818599Y28451D02*
X817449Y29601D01*
G01X818599Y26599D02*
Y28451D01*
G01X816732Y24732D02*
X818599Y26599D01*
G01X816732Y17157D02*
Y24732D01*
G01X798088Y28911D02*
Y35087D01*
G01X798688Y28311D02*
X798088Y28911D01*
G01X798688Y19192D02*
Y28311D01*
G01X796653Y17157D02*
X798688Y19192D01*
G01X795725Y16229D02*
X796653Y17157D01*
G01X795725Y13101D02*
Y16229D01*
G01X798767Y10059D02*
X795725Y13101D01*
G01X798767Y8674D02*
Y10059D01*
G01X797092Y6999D02*
X798767Y8674D01*
G01X797092Y5876D02*
Y6999D01*
G01X798592Y4376D02*
X797092Y5876D01*
G01X798592Y3024D02*
Y4376D01*
G01X797092Y1524D02*
X798592Y3024D01*
G01X797092Y301D02*
Y1524D01*
G01X798525Y-1132D02*
X797092Y301D01*
G01X798525Y-2226D02*
Y-1132D01*
G01X799999Y-3700D02*
X798525Y-2226D01*
G01X808688Y29249D02*
Y34911D01*
G01X808138Y28699D02*
X808688Y29249D01*
G01X808138Y25638D02*
Y28699D01*
G01X807000Y24500D02*
X808138Y25638D01*
G01X807000Y23200D02*
Y24500D01*
G01X808138Y22062D02*
X807000Y23200D01*
G01X808138Y18964D02*
Y22062D01*
G01X804788Y15614D02*
X808138Y18964D01*
G01X804788Y14018D02*
Y15614D01*
G01X806692Y12114D02*
X804788Y14018D01*
G01X808081Y10725D02*
X806692Y12114D01*
G01X808081Y-2288D02*
Y10725D01*
G01X808693Y-2900D02*
X808081Y-2288D01*
G01X808693Y-4300D02*
Y-2900D01*
G01X806893Y-6100D02*
X808693Y-4300D01*
G01X805893Y-6100D02*
X806893D01*
G01X804593Y-7400D02*
X805893Y-6100D01*
G01X804593Y-8654D02*
Y-7400D01*
G01X803346Y-9901D02*
X804593Y-8654D01*
G01X839099Y29499D02*
Y34401D01*
G01X838299Y28699D02*
X839099Y29499D01*
G01X838299Y20678D02*
Y28699D01*
G01X836449Y18828D02*
X838299Y20678D01*
G01X836449Y17464D02*
Y18828D01*
G01X834999Y16014D02*
X836449Y17464D01*
G01X834999Y13925D02*
Y16014D01*
G01X836810Y12114D02*
X834999Y13925D01*
G01X838199Y10725D02*
X836810Y12114D01*
G01X838199Y-2288D02*
Y10725D01*
G01X838811Y-2900D02*
X838199Y-2288D01*
G01X838811Y-4300D02*
Y-2900D01*
G01X837011Y-6100D02*
X838811Y-4300D01*
G01X836011Y-6100D02*
X837011D01*
G01X834711Y-7400D02*
X836011Y-6100D01*
G01X834711Y-8654D02*
Y-7400D01*
G01X833464Y-9901D02*
X834711Y-8654D01*
G01X814949Y28849D02*
Y33800D01*
G01X814100Y28000D02*
X814949Y28849D01*
G01X814100Y18399D02*
Y28000D01*
G01X811200Y15499D02*
X814100Y18399D01*
G01X811200Y13999D02*
Y15499D01*
G01X813085Y12114D02*
X811200Y13999D01*
G01X814311Y10888D02*
X813085Y12114D01*
G01X814311Y-2125D02*
Y10888D01*
G01X815086Y-2900D02*
X814311Y-2125D01*
G01X815086Y-4524D02*
Y-2900D01*
G01X813510Y-6100D02*
X815086Y-4524D01*
G01X812286Y-6100D02*
X813510D01*
G01X810039Y-8347D02*
X812286Y-6100D01*
G01X810039Y-9901D02*
Y-8347D01*
G01X845499Y29249D02*
Y34601D01*
G01X844949Y28699D02*
X845499Y29249D01*
G01X844949Y20200D02*
Y28699D01*
G01X843042Y18293D02*
X844949Y20200D01*
G01X843042Y17057D02*
Y18293D01*
G01X841599Y15614D02*
X843042Y17057D01*
G01X841599Y14018D02*
Y15614D01*
G01X843503Y12114D02*
X841599Y14018D01*
G01X844892Y10725D02*
X843503Y12114D01*
G01X844892Y-2288D02*
Y10725D01*
G01X845504Y-2900D02*
X844892Y-2288D01*
G01X845504Y-4300D02*
Y-2900D01*
G01X843704Y-6100D02*
X845504Y-4300D01*
G01X842704Y-6100D02*
X843704D01*
G01X841404Y-7400D02*
X842704Y-6100D01*
G01X841404Y-8654D02*
Y-7400D01*
G01X840157Y-9901D02*
X841404Y-8654D01*
G01X816732Y-7779D02*
Y-9901D01*
G01X818611Y-5900D02*
X816732Y-7779D01*
G01X820011Y-5900D02*
X818611D01*
G01X821467Y-4444D02*
X820011Y-5900D01*
G01X821467Y-3100D02*
Y-4444D01*
G01X820851Y-2484D02*
X821467Y-3100D01*
G01X820851Y10641D02*
Y-2484D01*
G01X819378Y12114D02*
X820851Y10641D01*
G01X821299Y25499D02*
Y37200D01*
G01X818799Y22999D02*
X821299Y25499D01*
G01X818799Y16698D02*
Y22999D01*
G01X817305Y15204D02*
X818799Y16698D01*
G01X817305Y14187D02*
Y15204D01*
G01X819378Y12114D02*
X817305Y14187D01*
G01X811099Y29401D02*
Y34299D01*
G01X811999Y28501D02*
X811099Y29401D01*
G01X811999Y19117D02*
Y28501D01*
G01X810039Y17157D02*
X811999Y19117D01*
G01X809111Y16229D02*
X810039Y17157D01*
G01X809111Y13101D02*
Y16229D01*
G01X811911Y10301D02*
X809111Y13101D01*
G01X811911Y8432D02*
Y10301D01*
G01X810528Y7049D02*
X811911Y8432D01*
G01X810528Y5650D02*
Y7049D01*
G01X811978Y4200D02*
X810528Y5650D01*
G01X811978Y3000D02*
Y4200D01*
G01X810478Y1500D02*
X811978Y3000D01*
G01X810478Y301D02*
Y1500D01*
G01X811911Y-1132D02*
X810478Y301D01*
G01X811911Y-3012D02*
Y-1132D01*
G01X812999Y-4100D02*
X811911Y-3012D01*
G01X846850Y-8347D02*
Y-9901D01*
G01X849097Y-6100D02*
X846850Y-8347D01*
G01X847910Y15514D02*
X851100Y18704D01*
G01X847910Y14100D02*
Y15514D01*
G01X849896Y12114D02*
X847910Y14100D01*
G01X847289Y301D02*
X848722Y-1132D01*
G01X847289Y1500D02*
Y301D01*
G01X848789Y3000D02*
X847289Y1500D01*
G01X847339Y5650D02*
X848789Y4200D01*
G01X847339Y7049D02*
Y5650D01*
G01X848722Y8432D02*
X847339Y7049D01*
G01X845922Y13101D02*
X848722Y10301D01*
G01X845922Y16229D02*
Y13101D01*
G01X846850Y17157D02*
X845922Y16229D01*
G01X847910Y29391D02*
Y34299D01*
G01X848810Y28491D02*
X847910Y29391D01*
G01X846850Y18149D02*
X848810Y20109D01*
G01X846850Y17157D02*
Y18149D01*
G01X832536Y16229D02*
X833464Y17157D01*
G01X832536Y13101D02*
Y16229D01*
G01X835578Y10059D02*
X832536Y13101D01*
G01X835578Y8674D02*
Y10059D01*
G01X833903Y6999D02*
X835578Y8674D01*
G01X833903Y5876D02*
Y6999D01*
G01X835403Y4376D02*
X833903Y5876D01*
G01X835403Y3024D02*
Y4376D01*
G01X833903Y1524D02*
X835403Y3024D01*
G01X833903Y301D02*
Y1524D01*
G01X835336Y-1132D02*
X833903Y301D01*
G01X835336Y-2226D02*
Y-1132D01*
G01X836810Y-3700D02*
X835336Y-2226D01*
G01X834899Y29099D02*
Y34899D01*
G01X835300Y28698D02*
X834899Y29099D01*
G01X835300Y21215D02*
Y28698D01*
G01X833464Y19379D02*
X835300Y21215D01*
G01X833464Y17157D02*
Y19379D01*
G01X801388Y10725D02*
X799999Y12114D01*
G01X801388Y-2288D02*
Y10725D01*
G01X802000Y-2900D02*
X801388Y-2288D01*
G01X802000Y-4300D02*
Y-2900D01*
G01X800200Y-6100D02*
X802000Y-4300D01*
G01X799200Y-6100D02*
X800200D01*
G01X797900Y-7400D02*
X799200Y-6100D01*
G01X797900Y-8654D02*
Y-7400D01*
G01X796653Y-9901D02*
X797900Y-8654D01*
G01X802288Y29287D02*
Y34611D01*
G01X801500Y28499D02*
X802288Y29287D01*
G01X801500Y19000D02*
Y28499D01*
G01X798150Y15650D02*
X801500Y19000D01*
G01X798150Y13963D02*
Y15650D01*
G01X799999Y12114D02*
X798150Y13963D01*
G01X804788Y28999D02*
Y34687D01*
G01X805588Y28199D02*
X804788Y28999D01*
G01X805588Y27000D02*
Y28199D01*
G01X804300Y25712D02*
X805588Y27000D01*
G01X804300Y18111D02*
Y25712D01*
G01X803346Y17157D02*
X804300Y18111D01*
G01X802225Y16036D02*
X803346Y17157D01*
G01X802225Y13100D02*
Y16036D01*
G01X805567Y9758D02*
X802225Y13100D01*
G01X805567Y8700D02*
Y9758D01*
G01X803767Y6900D02*
X805567Y8700D01*
G01X803767Y5325D02*
Y6900D01*
G01X804967Y4125D02*
X803767Y5325D01*
G01X804967Y2999D02*
Y4125D01*
G01X803767Y1799D02*
X804967Y2999D01*
G01X803767Y426D02*
Y1799D01*
G01X805125Y-932D02*
X803767Y426D01*
G01X805125Y-2133D02*
Y-932D01*
G01X806692Y-3700D02*
X805125Y-2133D01*
G01X841599Y28999D02*
Y34899D01*
G01X842399Y28199D02*
X841599Y28999D01*
G01X842399Y21499D02*
Y28199D01*
G01X840157Y19257D02*
X842399Y21499D01*
G01X840157Y17157D02*
Y19257D01*
G01X839036Y16036D02*
X840157Y17157D01*
G01X839036Y13100D02*
Y16036D01*
G01X842378Y9758D02*
X839036Y13100D01*
G01X842378Y8700D02*
Y9758D01*
G01X840578Y6900D02*
X842378Y8700D01*
G01X840578Y5325D02*
Y6900D01*
G01X841778Y4125D02*
X840578Y5325D01*
G01X841778Y2999D02*
Y4125D01*
G01X840578Y1799D02*
X841778Y2999D01*
G01X840578Y426D02*
Y1799D01*
G01X841936Y-932D02*
X840578Y426D01*
G01X841936Y-2133D02*
Y-932D01*
G01X843503Y-3700D02*
X841936Y-2133D01*
G01X818600Y92149D02*
Y100468D01*
G01X817449Y90998D02*
X818600Y92149D01*
G01X817449Y86714D02*
Y90998D01*
G01X818799Y85364D02*
X817449Y86714D01*
G01X818799Y84300D02*
Y85364D01*
G01X818100Y83601D02*
X818799Y84300D01*
G01X818100Y75300D02*
Y83601D01*
G01X818799Y74601D02*
X818100Y75300D01*
G01X818799Y73499D02*
Y74601D01*
G01X817449Y72149D02*
X818799Y73499D01*
G01X817449Y67401D02*
Y72149D01*
G01X818799Y66051D02*
X817449Y67401D01*
G01X818799Y54598D02*
Y66051D01*
G01X817449Y53248D02*
X818799Y54598D01*
G01X817449Y48914D02*
Y53248D01*
G01X818799Y47564D02*
X817449Y48914D01*
G01X818799Y46299D02*
Y47564D01*
G01X818000Y45500D02*
X818799Y46299D01*
G01X818000Y37599D02*
Y45500D01*
G01X818799Y36800D02*
X818000Y37599D01*
G01X818799Y35599D02*
Y36800D01*
G01X817449Y34249D02*
X818799Y35599D01*
G01X798488Y91614D02*
Y98812D01*
G01X798088Y91214D02*
X798488Y91614D01*
G01X798088Y86514D02*
Y91214D01*
G01X798888Y85714D02*
X798088Y86514D01*
G01X798888Y84100D02*
Y85714D01*
G01X798100Y83312D02*
X798888Y84100D01*
G01X798100Y75500D02*
Y83312D01*
G01X798888Y74712D02*
X798100Y75500D01*
G01X798888Y73487D02*
Y74712D01*
G01X798088Y72687D02*
X798888Y73487D01*
G01X798088Y66899D02*
Y72687D01*
G01X798488Y66499D02*
X798088Y66899D01*
G01X798488Y53814D02*
Y66499D01*
G01X798088Y53414D02*
X798488Y53814D01*
G01X798088Y48714D02*
Y53414D01*
G01X798888Y47914D02*
X798088Y48714D01*
G01X798888Y46300D02*
Y47914D01*
G01X798300Y45712D02*
X798888Y46300D01*
G01X798300Y37600D02*
Y45712D01*
G01X798888Y37012D02*
X798300Y37600D01*
G01X798888Y35887D02*
Y37012D01*
G01X798088Y35087D02*
X798888Y35887D01*
G01X807800Y94139D02*
X808796Y95135D01*
G01X807800Y92262D02*
Y94139D01*
G01X808788Y91274D02*
X807800Y92262D01*
G01X808788Y86614D02*
Y91274D01*
G01X808088Y85914D02*
X808788Y86614D01*
G01X808088Y84012D02*
Y85914D01*
G01X808500Y83600D02*
X808088Y84012D01*
G01X808500Y75612D02*
Y83600D01*
G01X808088Y75200D02*
X808500Y75612D01*
G01X808088Y73011D02*
Y75200D01*
G01X808638Y72461D02*
X808088Y73011D01*
G01X808638Y66999D02*
Y72461D01*
G01X808138Y66499D02*
X808638Y66999D01*
G01X808138Y53914D02*
Y66499D01*
G01X808599Y53453D02*
X808138Y53914D01*
G01X808599Y48575D02*
Y53453D01*
G01X808088Y48064D02*
X808599Y48575D01*
G01X808088Y46112D02*
Y48064D01*
G01X808700Y45500D02*
X808088Y46112D01*
G01X808700Y37712D02*
Y45500D01*
G01X808088Y37100D02*
X808700Y37712D01*
G01X808088Y35511D02*
Y37100D01*
G01X808688Y34911D02*
X808088Y35511D01*
G01X838299Y91714D02*
Y108102D01*
G01X838999Y91014D02*
X838299Y91714D01*
G01X838999Y86514D02*
Y91014D01*
G01X838199Y85714D02*
X838999Y86514D01*
G01X838199Y84100D02*
Y85714D01*
G01X838800Y83499D02*
X838199Y84100D01*
G01X838800Y75500D02*
Y83499D01*
G01X838199Y74899D02*
X838800Y75500D01*
G01X838199Y73201D02*
Y74899D01*
G01X839099Y72301D02*
X838199Y73201D01*
G01X839099Y67299D02*
Y72301D01*
G01X838299Y66499D02*
X839099Y67299D01*
G01X838299Y53914D02*
Y66499D01*
G01X838999Y53214D02*
X838299Y53914D01*
G01X838999Y48714D02*
Y53214D01*
G01X838199Y47914D02*
X838999Y48714D01*
G01X838199Y46101D02*
Y47914D01*
G01X838600Y45700D02*
X838199Y46101D01*
G01X838600Y37701D02*
Y45700D01*
G01X838199Y37300D02*
X838600Y37701D01*
G01X838199Y35301D02*
Y37300D01*
G01X839099Y34401D02*
X838199Y35301D01*
G01X814949Y87700D02*
Y95600D01*
G01X814897Y87266D02*
X814949Y87700D01*
G01X814599Y84800D02*
X814897Y87266D01*
G01X814599Y84100D02*
Y84800D01*
G01X815200Y83499D02*
X814599Y84100D01*
G01X815200Y76100D02*
Y83499D01*
G01X815024Y75500D02*
X815200Y76100D01*
G01X814700Y74400D02*
X815024Y75500D01*
G01X814700Y73900D02*
Y74400D01*
G01X814949Y71600D02*
X814700Y73900D01*
G01X814949Y66649D02*
Y71600D01*
G01X814699Y66399D02*
X814949Y66649D01*
G01X814699Y53864D02*
Y66399D01*
G01X814949Y53614D02*
X814699Y53864D01*
G01X814949Y49900D02*
Y53614D01*
G01X814599Y47500D02*
X814949Y49900D01*
G01X814599Y46301D02*
Y47500D01*
G01X815200Y45700D02*
X814599Y46301D01*
G01X815200Y38001D02*
Y45700D01*
G01X814800Y37601D02*
X815200Y38001D01*
G01X814800Y34822D02*
Y37601D01*
G01X814847Y34500D02*
X814800Y34822D01*
G01X814949Y33800D02*
X814847Y34500D01*
G01X844999Y91874D02*
Y112100D01*
G01X845599Y91274D02*
X844999Y91874D01*
G01X845599Y86614D02*
Y91274D01*
G01X844899Y85914D02*
X845599Y86614D01*
G01X844899Y83900D02*
Y85914D01*
G01X845500Y83299D02*
X844899Y83900D01*
G01X845500Y75800D02*
Y83299D01*
G01X844899Y75199D02*
X845500Y75800D01*
G01X844899Y73101D02*
Y75199D01*
G01X845499Y72501D02*
X844899Y73101D01*
G01X845499Y67049D02*
Y72501D01*
G01X844949Y66499D02*
X845499Y67049D01*
G01X844949Y53864D02*
Y66499D01*
G01X845599Y53214D02*
X844949Y53864D01*
G01X845599Y48814D02*
Y53214D01*
G01X844899Y48114D02*
X845599Y48814D01*
G01X844899Y46100D02*
Y48114D01*
G01X845600Y45399D02*
X844899Y46100D01*
G01X845600Y37500D02*
Y45399D01*
G01X844899Y36799D02*
X845600Y37500D01*
G01X844899Y35201D02*
Y36799D01*
G01X845499Y34601D02*
X844899Y35201D01*
G01X821299Y83800D02*
Y101516D01*
G01X821900Y83199D02*
X821299Y83800D01*
G01X821900Y75400D02*
Y83199D01*
G01X821299Y74799D02*
X821900Y75400D01*
G01X821299Y46251D02*
Y74799D01*
G01X821900Y45650D02*
X821299Y46251D01*
G01X821900Y37801D02*
Y45650D01*
G01X821299Y37200D02*
X821900Y37801D01*
G01X812088Y92087D02*
Y147071D01*
G01X811200Y91199D02*
X812088Y92087D01*
G01X811200Y86313D02*
Y91199D01*
G01X811900Y85613D02*
X811200Y86313D01*
G01X811900Y83900D02*
Y85613D01*
G01X811600Y83600D02*
X811900Y83900D01*
G01X811600Y75300D02*
Y83600D01*
G01X811900Y75000D02*
X811600Y75300D01*
G01X811900Y72900D02*
Y75000D01*
G01X811100Y72100D02*
X811900Y72900D01*
G01X811100Y67100D02*
Y72100D01*
G01X811900Y66300D02*
X811100Y67100D01*
G01X811900Y54215D02*
Y66300D01*
G01X811200Y53515D02*
X811900Y54215D01*
G01X811200Y48513D02*
Y53515D01*
G01X811900Y47813D02*
X811200Y48513D01*
G01X811900Y46000D02*
Y47813D01*
G01X811100Y45200D02*
X811900Y46000D01*
G01X811100Y37700D02*
Y45200D01*
G01X811900Y36900D02*
X811100Y37700D01*
G01X811900Y35100D02*
Y36900D01*
G01X811099Y34299D02*
X811900Y35100D01*
G01X847910Y91214D02*
X849200Y92504D01*
G01X847910Y86414D02*
Y91214D01*
G01X848910Y85414D02*
X847910Y86414D01*
G01X848200Y83490D02*
X848910Y84200D01*
G01X848200Y75500D02*
Y83490D01*
G01X848910Y74790D02*
X848200Y75500D01*
G01X847910Y72099D02*
X848910Y73099D01*
G01X847910Y67191D02*
Y72099D01*
G01X848810Y66291D02*
X847910Y67191D01*
G01Y53414D02*
X848810Y54314D01*
G01X847910Y48614D02*
Y53414D01*
G01X848910Y47614D02*
X847910Y48614D01*
G01X848200Y45600D02*
X848910Y46310D01*
G01X848200Y37910D02*
Y45600D01*
G01X848910Y37200D02*
X848200Y37910D01*
G01X847910Y34299D02*
X848910Y35299D01*
G01X835299Y91614D02*
Y106602D01*
G01X834899Y91214D02*
X835299Y91614D01*
G01X834899Y86514D02*
Y91214D01*
G01X835699Y85714D02*
X834899Y86514D01*
G01X835699Y84200D02*
Y85714D01*
G01X835100Y83601D02*
X835699Y84200D01*
G01X835100Y75500D02*
Y83601D01*
G01X835699Y74901D02*
X835100Y75500D01*
G01X835699Y73399D02*
Y74901D01*
G01X834899Y72599D02*
X835699Y73399D01*
G01X834899Y66899D02*
Y72599D01*
G01X835299Y66499D02*
X834899Y66899D01*
G01X835299Y53814D02*
Y66499D01*
G01X834899Y53414D02*
X835299Y53814D01*
G01X834899Y48714D02*
Y53414D01*
G01X835699Y47914D02*
X834899Y48714D01*
G01X835699Y46299D02*
Y47914D01*
G01X834900Y45500D02*
X835699Y46299D01*
G01X834900Y37799D02*
Y45500D01*
G01X835699Y37000D02*
X834900Y37799D01*
G01X835699Y35699D02*
Y37000D01*
G01X834899Y34899D02*
X835699Y35699D01*
G01X801488Y91714D02*
Y104600D01*
G01X802188Y91014D02*
X801488Y91714D01*
G01X802188Y86514D02*
Y91014D01*
G01X801388Y85714D02*
X802188Y86514D01*
G01X801388Y83900D02*
Y85714D01*
G01X801900Y83388D02*
X801388Y83900D01*
G01X801900Y75300D02*
Y83388D01*
G01X801388Y74788D02*
X801900Y75300D01*
G01X801388Y73111D02*
Y74788D01*
G01X802288Y72211D02*
X801388Y73111D01*
G01X802288Y67299D02*
Y72211D01*
G01X801488Y66499D02*
X802288Y67299D01*
G01X801488Y53914D02*
Y66499D01*
G01X802188Y53214D02*
X801488Y53914D01*
G01X802188Y48714D02*
Y53214D01*
G01X801388Y47914D02*
X802188Y48714D01*
G01X801388Y46312D02*
Y47914D01*
G01X802100Y45600D02*
X801388Y46312D01*
G01X802100Y37612D02*
Y45600D01*
G01X801388Y36900D02*
X802100Y37612D01*
G01X801388Y35511D02*
Y36900D01*
G01X802288Y34611D02*
X801388Y35511D01*
G01X805300Y91726D02*
Y100801D01*
G01X804688Y91114D02*
X805300Y91726D01*
G01X804688Y86414D02*
Y91114D01*
G01X805288Y85814D02*
X804688Y86414D01*
G01X805288Y84100D02*
Y85814D01*
G01X804800Y83612D02*
X805288Y84100D01*
G01X804800Y75400D02*
Y83612D01*
G01X805288Y74912D02*
X804800Y75400D01*
G01X805288Y73087D02*
Y74912D01*
G01X804788Y72587D02*
X805288Y73087D01*
G01X804788Y66799D02*
Y72587D01*
G01X805638Y65949D02*
X804788Y66799D01*
G01X805638Y54264D02*
Y65949D01*
G01X804688Y53314D02*
X805638Y54264D01*
G01X804688Y48614D02*
Y53314D01*
G01X805288Y48014D02*
X804688Y48614D01*
G01X805288Y46288D02*
Y48014D01*
G01X804700Y45700D02*
X805288Y46288D01*
G01X804700Y37388D02*
Y45700D01*
G01X805288Y36800D02*
X804700Y37388D01*
G01X805288Y35187D02*
Y36800D01*
G01X804788Y34687D02*
X805288Y35187D01*
G01X841974Y91589D02*
Y114674D01*
G01X841499Y91114D02*
X841974Y91589D01*
G01X841499Y86414D02*
Y91114D01*
G01X842099Y85814D02*
X841499Y86414D01*
G01X842099Y84000D02*
Y85814D01*
G01X841600Y83501D02*
X842099Y84000D01*
G01X841600Y75400D02*
Y83501D01*
G01X842099Y74901D02*
X841600Y75400D01*
G01X842099Y73099D02*
Y74901D01*
G01X841599Y72599D02*
X842099Y73099D01*
G01X841599Y66799D02*
Y72599D01*
G01X842449Y65949D02*
X841599Y66799D01*
G01X842449Y54264D02*
Y65949D01*
G01X841499Y53314D02*
X842449Y54264D01*
G01X841499Y48614D02*
Y53314D01*
G01X842099Y48014D02*
X841499Y48614D01*
G01X842099Y46300D02*
Y48014D01*
G01X841500Y45701D02*
X842099Y46300D01*
G01X841500Y37500D02*
Y45701D01*
G01X842099Y36901D02*
X841500Y37500D01*
G01X842099Y35399D02*
Y36901D01*
G01X841599Y34899D02*
X842099Y35399D01*
G01X817849Y145760D02*
X840473Y168384D01*
G01X817849Y101219D02*
Y145760D01*
G01X818600Y100468D02*
X817849Y101219D01*
G01X799100Y148584D02*
X814208Y163692D01*
G01X799100Y111800D02*
Y148584D01*
G01X798300Y111000D02*
X799100Y111800D01*
G01X796800Y111000D02*
X798300D01*
G01X795900Y111900D02*
X796800Y111000D01*
G01X795900Y124300D02*
Y111900D01*
G01X795100Y125100D02*
X795900Y124300D01*
G01X793500Y125100D02*
X795100D01*
G01X792700Y124300D02*
X793500Y125100D01*
G01X792700Y104600D02*
Y124300D01*
G01X798488Y98812D02*
X792700Y104600D01*
G01X808796Y148130D02*
X866402Y205736D01*
G01X808796Y95135D02*
Y148130D01*
G01X842400Y143784D02*
X869203Y170587D01*
G01X842400Y120300D02*
Y143784D01*
G01X841600Y119500D02*
X842400Y120300D01*
G01X840000Y119500D02*
X841600D01*
G01X839200Y120300D02*
X840000Y119500D01*
G01X839200Y131100D02*
Y120300D01*
G01X838400Y131900D02*
X839200Y131100D01*
G01X836800Y131900D02*
X838400D01*
G01X836000Y131100D02*
X836800Y131900D01*
G01X836000Y110401D02*
Y131100D01*
G01X838299Y108102D02*
X836000Y110401D01*
G01X814949Y146396D02*
X902995Y234442D01*
G01X814949Y99100D02*
Y146396D01*
G01X816000Y98049D02*
X814949Y99100D01*
G01X816000Y96651D02*
Y98049D01*
G01X814949Y95600D02*
X816000Y96651D01*
G01X844999Y112100D02*
X849118Y116219D01*
G01X819861Y144236D02*
X839425Y163800D01*
G01X819861Y102954D02*
Y144236D01*
G01X821299Y101516D02*
X819861Y102954D01*
G01X812088Y147071D02*
X901959Y236942D01*
G01X845374Y150688D02*
X864028Y169342D01*
G01X844582Y150688D02*
X845374D01*
G01X843281Y151989D02*
X844582Y150688D01*
G01X842489Y151989D02*
X843281D01*
G01X841470Y150970D02*
X842489Y151989D01*
G01X841470Y150178D02*
Y150970D01*
G01X842771Y148877D02*
X841470Y150178D01*
G01X842771Y148085D02*
Y148877D01*
G01X839900Y145214D02*
X842771Y148085D01*
G01X839900Y135500D02*
Y145214D01*
G01X839100Y134700D02*
X839900Y135500D01*
G01X837500Y134700D02*
X839100D01*
G01X836700Y135500D02*
X837500Y134700D01*
G01X836700Y142500D02*
Y135500D01*
G01X835900Y143300D02*
X836700Y142500D01*
G01X834300Y143300D02*
X835900D01*
G01X833500Y142500D02*
X834300Y143300D01*
G01X833500Y118709D02*
Y142500D01*
G01X832800Y118009D02*
X833500Y118709D01*
G01X830365Y118009D02*
X832800D01*
G01X829565Y117209D02*
X830365Y118009D01*
G01X829565Y115609D02*
Y117209D01*
G01X830365Y114809D02*
X829565Y115609D01*
G01X832900Y114809D02*
X830365D01*
G01X833700Y114009D02*
X832900Y114809D01*
G01X833700Y112409D02*
Y114009D01*
G01X832900Y111609D02*
X833700Y112409D01*
G01X830365Y111609D02*
X832900D01*
G01X829565Y110809D02*
X830365Y111609D01*
G01X829565Y109209D02*
Y110809D01*
G01X830365Y108409D02*
X829565Y109209D01*
G01X833492Y108409D02*
X830365D01*
G01X835299Y106602D02*
X833492Y108409D01*
G01X804041Y149685D02*
X823970Y169614D01*
G01X804041Y147790D02*
Y149685D01*
G01X803481Y147230D02*
X804041Y147790D01*
G01X801760Y147230D02*
X803481D01*
G01X801200Y146670D02*
X801760Y147230D01*
G01X801200Y145230D02*
Y146670D01*
G01X801760Y144670D02*
X801200Y145230D01*
G01X803481Y144670D02*
X801760D01*
G01X804041Y144110D02*
X803481Y144670D01*
G01X804041Y142670D02*
Y144110D01*
G01X803481Y142110D02*
X804041Y142670D01*
G01X801760Y142110D02*
X803481D01*
G01X801200Y141550D02*
X801760Y142110D01*
G01X801200Y140110D02*
Y141550D01*
G01X801760Y139550D02*
X801200Y140110D01*
G01X803481Y139550D02*
X801760D01*
G01X804041Y138990D02*
X803481Y139550D01*
G01X804041Y137041D02*
Y138990D01*
G01X801200Y134200D02*
X804041Y137041D01*
G01X801200Y108360D02*
Y134200D01*
G01X800640Y107800D02*
X801200Y108360D01*
G01X796043Y107800D02*
X800640D01*
G01X795200Y106957D02*
X796043Y107800D01*
G01X795200Y105900D02*
Y106957D01*
G01X796000Y105100D02*
X795200Y105900D01*
G01X800988Y105100D02*
X796000D01*
G01X801488Y104600D02*
X800988Y105100D01*
G01X806436Y149153D02*
X836111Y178828D01*
G01X806436Y131779D02*
Y149153D01*
G01X805876Y131219D02*
X806436Y131779D01*
G01X804260Y131219D02*
X805876D01*
G01X803700Y130659D02*
X804260Y131219D01*
G01X803700Y129219D02*
Y130659D01*
G01X804260Y128659D02*
X803700Y129219D01*
G01X805876Y128659D02*
X804260D01*
G01X806436Y128099D02*
X805876Y128659D01*
G01X806436Y101937D02*
Y128099D01*
G01X805300Y100801D02*
X806436Y101937D01*
G01X848058Y144808D02*
X848637Y144229D01*
G01X847266Y144808D02*
X848058D01*
G01X844700Y142242D02*
X847266Y144808D01*
G01X844700Y117400D02*
Y142242D01*
G01X841974Y114674D02*
X844700Y117400D01*
G01X799672Y173329D02*
X887973Y261630D01*
G01X799672Y167739D02*
Y173329D01*
G01X799171Y167238D02*
X799672Y167739D01*
G01X795243Y167238D02*
X799171D01*
G01X794500Y166495D02*
X795243Y167238D01*
G01X794500Y164500D02*
Y166495D01*
G01X793800Y163800D02*
X794500Y164500D01*
G01X790143Y163800D02*
X793800D01*
G01X789000Y162657D02*
X790143Y163800D01*
G01X789000Y159899D02*
Y162657D01*
G01X788101Y159000D02*
X789000Y159899D01*
G01X846513Y174424D02*
X903631Y231542D01*
G01X846513Y173562D02*
Y174424D01*
G01X847856Y172219D02*
X846513Y173562D01*
G01X847856Y171356D02*
Y172219D01*
G01X846992Y170492D02*
X847856Y171356D01*
G01X846130Y170492D02*
X846992D01*
G01X844786Y171836D02*
X846130Y170492D01*
G01X843925Y171836D02*
X844786D01*
G01X843061Y170972D02*
X843925Y171836D01*
G01X843061Y170109D02*
Y170972D01*
G01X844354Y168816D02*
X843061Y170109D01*
G01X844354Y167954D02*
Y168816D01*
G01X843490Y167090D02*
X844354Y167954D01*
G01X842629Y167090D02*
X843490D01*
G01X841335Y168384D02*
X842629Y167090D01*
G01X840473Y168384D02*
X841335D01*
G01X818581Y174349D02*
X880882Y236650D01*
G01X818581Y168065D02*
Y174349D01*
G01X816796Y166280D02*
X818581Y168065D01*
G01X815934Y166280D02*
X816796D01*
G01X813504Y168710D02*
X815934Y166280D01*
G01X812642Y168710D02*
X813504D01*
G01X811778Y167846D02*
X812642Y168710D01*
G01X811778Y166984D02*
Y167846D01*
G01X814208Y164554D02*
X811778Y166984D01*
G01X814208Y163692D02*
Y164554D01*
G01X843305Y163800D02*
X850454Y170949D01*
G01X839425Y163800D02*
X843305D01*
G01X801940Y172061D02*
X889009Y259130D01*
G01X801940Y167341D02*
Y172061D01*
G01X798970Y164371D02*
X801940Y167341D01*
G01X797452Y164371D02*
X798970D01*
G01X789481Y156400D02*
X797452Y164371D01*
G01X787399Y156400D02*
X789481D01*
G01X797104Y173497D02*
X887737Y264130D01*
G01X797104Y171207D02*
Y173497D01*
G01X796544Y170647D02*
X797104Y171207D01*
G01X794254Y170647D02*
X796544D01*
G01X831383Y183615D02*
X881308Y233540D01*
G01X831383Y177027D02*
Y183615D01*
G01X830010Y175654D02*
X831383Y177027D01*
G01X829148Y175654D02*
X830010D01*
G01X826993Y177809D02*
X829148Y175654D01*
G01X826131Y177809D02*
X826993D01*
G01X825267Y176945D02*
X826131Y177809D01*
G01X825267Y176083D02*
Y176945D01*
G01X827422Y173928D02*
X825267Y176083D01*
G01X827422Y173066D02*
Y173928D01*
G01X826558Y172202D02*
X827422Y173066D01*
G01X825696Y172202D02*
X826558D01*
G01X823541Y174357D02*
X825696Y172202D01*
G01X822679Y174357D02*
X823541D01*
G01X821815Y173493D02*
X822679Y174357D01*
G01X821815Y172631D02*
Y173493D01*
G01X823970Y170476D02*
X821815Y172631D01*
G01X823970Y169614D02*
Y170476D01*
G01X847946Y196333D02*
X848810Y197197D01*
G01X847946Y195471D02*
Y196333D01*
G01X849919Y193498D02*
X847946Y195471D01*
G01X848193Y191772D02*
X849055D01*
G01X846220Y193745D02*
X848193Y191772D01*
G01X845358Y193745D02*
X846220D01*
G01X844494Y192881D02*
X845358Y193745D01*
G01X844494Y192019D02*
Y192881D01*
G01X846467Y190046D02*
X844494Y192019D01*
G01X846467Y189184D02*
Y190046D01*
G01X845603Y188320D02*
X846467Y189184D01*
G01X844741Y188320D02*
X845603D01*
G01X842768Y190293D02*
X844741Y188320D01*
G01X841906Y190293D02*
X842768D01*
G01X841042Y189429D02*
X841906Y190293D01*
G01X841042Y188567D02*
Y189429D01*
G01X843015Y186594D02*
X841042Y188567D01*
G01X843015Y185732D02*
Y186594D01*
G01X842151Y184868D02*
X843015Y185732D01*
G01X841289Y184868D02*
X842151D01*
G01X839316Y186841D02*
X841289Y184868D01*
G01X838454Y186841D02*
X839316D01*
G01X837590Y185977D02*
X838454Y186841D01*
G01X837590Y185115D02*
Y185977D01*
G01X839563Y183142D02*
X837590Y185115D01*
G01X839563Y182280D02*
Y183142D01*
G01X838699Y181416D02*
X839563Y182280D01*
G01X837837Y181416D02*
X838699D01*
G01X835864Y183389D02*
X837837Y181416D01*
G01X835002Y183389D02*
X835864D01*
G01X834138Y182525D02*
X835002Y183389D01*
G01X834138Y181663D02*
Y182525D01*
G01X836111Y179690D02*
X834138Y181663D01*
G01X836111Y178828D02*
Y179690D01*
G01X821300Y398900D02*
X813700Y406500D01*
G01X842101Y398900D02*
X821300D01*
G01X853070Y387931D02*
X842101Y398900D01*
G01X819300Y397000D02*
X811300Y405000D01*
G01X841201Y397000D02*
X819300D01*
G01X851185Y387016D02*
X841201Y397000D01*
G01X822500Y400800D02*
X819150Y404150D01*
G01X843169Y400800D02*
X822500D01*
G01X854955Y389014D02*
X843169Y400800D01*
G01X818601Y394900D02*
X809400Y404101D01*
G01X840601Y394900D02*
X818601D01*
G01X849300Y386201D02*
X840601Y394900D01*
G01X800900Y442100D02*
Y487604D01*
G01X814400Y428600D02*
X800900Y442100D01*
G01X814400Y426600D02*
Y428600D01*
G01X821240Y419760D02*
X814400Y426600D01*
G01X822032Y419760D02*
X821240D01*
G01X826190Y423918D02*
X822032Y419760D01*
G01X826982Y423918D02*
X826190D01*
G01X828001Y422899D02*
X826982Y423918D01*
G01X828001Y422107D02*
Y422899D01*
G01X823843Y417949D02*
X828001Y422107D01*
G01X823843Y417157D02*
Y417949D01*
G01X824862Y416138D02*
X823843Y417157D01*
G01X825654Y416138D02*
X824862D01*
G01X829812Y420296D02*
X825654Y416138D01*
G01X830604Y420296D02*
X829812D01*
G01X831623Y419277D02*
X830604Y420296D01*
G01X831623Y418485D02*
Y419277D01*
G01X827465Y414327D02*
X831623Y418485D01*
G01X827465Y413535D02*
Y414327D01*
G01X828200Y412800D02*
X827465Y413535D01*
G01X845564Y412800D02*
X828200D01*
G01X863900Y394464D02*
X845564Y412800D01*
G01X804500Y424701D02*
X786901Y442300D01*
G01X804500Y422501D02*
Y424701D01*
G01X813700Y413301D02*
X804500Y422501D01*
G01X813700Y406500D02*
Y413301D01*
G01X870160Y439291D02*
X836500Y472951D01*
G01X805900Y460363D02*
Y499000D01*
G01X808081Y458182D02*
X805900Y460363D01*
G01X808081Y456581D02*
Y458182D01*
G01X805900Y454400D02*
X808081Y456581D01*
G01X805900Y451311D02*
Y454400D01*
G01X826019Y431192D02*
X805900Y451311D01*
G01X827051Y431192D02*
X826019D01*
G01X830445Y434586D02*
X827051Y431192D01*
G01X831677Y434586D02*
X830445D01*
G01X844965Y421298D02*
X831677Y434586D01*
G01X844965Y420166D02*
Y421298D01*
G01X843834Y419035D02*
X844965Y420166D01*
G01X842702Y419035D02*
X843834D01*
G01X831477Y430260D02*
X842702Y419035D01*
G01X830145Y430260D02*
X831477D01*
G01X829014Y429129D02*
X830145Y430260D01*
G01X829014Y428197D02*
Y429129D01*
G01X840511Y416700D02*
X829014Y428197D01*
G01X849562Y416700D02*
X840511D01*
G01X815933Y463059D02*
Y466400D01*
G01X884100Y394892D02*
X815933Y463059D01*
G01X802600Y423900D02*
X786949Y439551D01*
G01X802600Y420019D02*
Y423900D01*
G01X804664Y415036D02*
X802600Y420019D01*
G01X806000Y413700D02*
X804664Y415036D01*
G01X810501Y413700D02*
X806000D01*
G01X811300Y412901D02*
X810501Y413700D01*
G01X811300Y405000D02*
Y412901D01*
G01X812900Y462556D02*
Y500100D01*
G01X882200Y393256D02*
X812900Y462556D01*
G01X791400Y450828D02*
X790840Y451388D01*
G01X791400Y449388D02*
Y450828D01*
G01X790840Y448828D02*
X791400Y449388D01*
G01X790400Y444200D02*
X789700Y444900D01*
G01X790400Y441501D02*
Y444200D01*
G01X806500Y425401D02*
X790400Y441501D01*
G01X806500Y423301D02*
Y425401D01*
G01X819150Y410651D02*
X806500Y423301D01*
G01X819150Y404150D02*
Y410651D01*
G01X803400Y450274D02*
Y498700D01*
G01X805924Y447750D02*
X803400Y450274D01*
G01X805924Y446958D02*
Y447750D01*
G01X802779Y443813D02*
X805924Y446958D01*
G01X802779Y443021D02*
Y443813D01*
G01X803798Y442002D02*
X802779Y443021D01*
G01X804590Y442002D02*
X803798D01*
G01X807735Y445147D02*
X804590Y442002D01*
G01X808527Y445147D02*
X807735D01*
G01X809546Y444128D02*
X808527Y445147D01*
G01X809546Y443336D02*
Y444128D01*
G01X806401Y440191D02*
X809546Y443336D01*
G01X806401Y439399D02*
Y440191D01*
G01X807420Y438380D02*
X806401Y439399D01*
G01X808212Y438380D02*
X807420D01*
G01X811357Y441525D02*
X808212Y438380D01*
G01X812149Y441525D02*
X811357D01*
G01X813168Y440506D02*
X812149Y441525D01*
G01X813168Y439714D02*
Y440506D01*
G01X810023Y436569D02*
X813168Y439714D01*
G01X810023Y435777D02*
Y436569D01*
G01X811042Y434758D02*
X810023Y435777D01*
G01X811834Y434758D02*
X811042D01*
G01X814979Y437903D02*
X811834Y434758D01*
G01X815771Y437903D02*
X814979D01*
G01X816790Y436884D02*
X815771Y437903D01*
G01X816790Y436092D02*
Y436884D01*
G01X813645Y432947D02*
X816790Y436092D01*
G01X813645Y432155D02*
Y432947D01*
G01X814664Y431136D02*
X813645Y432155D01*
G01X815456Y431136D02*
X814664D01*
G01X818601Y434281D02*
X815456Y431136D01*
G01X819393Y434281D02*
X818601D01*
G01X820412Y433262D02*
X819393Y434281D01*
G01X820412Y432470D02*
Y433262D01*
G01X817775Y429833D02*
X820412Y432470D01*
G01X817775Y429125D02*
Y429833D01*
G01X818786Y428114D02*
X817775Y429125D01*
G01X819678Y428114D02*
X818786D01*
G01X822223Y430659D02*
X819678Y428114D01*
G01X823015Y430659D02*
X822223D01*
G01X838874Y414800D02*
X823015Y430659D01*
G01X847100Y414800D02*
X838874D01*
G01X866800Y395100D02*
X847100Y414800D01*
G01X822500Y463564D02*
Y465662D01*
G01X888700Y397364D02*
X822500Y463564D01*
G01X808400Y464038D02*
X809596Y465234D01*
G01X808400Y461399D02*
Y464038D01*
G01X828383Y441416D02*
X808400Y461399D01*
G01X828383Y440284D02*
Y441416D01*
G01X827252Y439153D02*
X828383Y440284D01*
G01X826120Y439153D02*
X827252D01*
G01X810752Y454521D02*
X826120Y439153D01*
G01X809620Y454521D02*
X810752D01*
G01X808489Y453390D02*
X809620Y454521D01*
G01X808489Y452258D02*
Y453390D01*
G01X825958Y434789D02*
X808489Y452258D01*
G01X827090Y434789D02*
X825958D01*
G01X830484Y438183D02*
X827090Y434789D01*
G01X831616Y438183D02*
X830484D01*
G01X872300Y397499D02*
X831616Y438183D01*
G01X800400Y420302D02*
Y423300D01*
G01X803018Y413982D02*
X800400Y420302D01*
G01X806925Y410075D02*
X803018Y413982D01*
G01X809400Y404101D02*
X806925Y410075D01*
G01X817900Y464628D02*
X886400Y396128D01*
G01X817900Y492218D02*
Y464628D01*
G01X845200Y519451D02*
Y526800D01*
G01X844949Y519200D02*
X845200Y519451D01*
G01X844949Y517357D02*
Y519200D01*
G01X845800Y516506D02*
X844949Y517357D01*
G01X845800Y512558D02*
Y516506D01*
G01X844899Y511657D02*
X845800Y512558D01*
G01X844899Y499424D02*
Y511657D01*
G01X845506Y498817D02*
X844899Y499424D01*
G01X846612Y498817D02*
X845506D01*
G01X847454Y497975D02*
X846612Y498817D01*
G01X847454Y496375D02*
Y497975D01*
G01X846696Y495617D02*
X847454Y496375D01*
G01X845084Y495617D02*
X846696D01*
G01X844500Y495033D02*
X845084Y495617D01*
G01X844500Y474931D02*
Y495033D01*
G01X845300Y474131D02*
X844500Y474931D01*
G01X846900Y474131D02*
X845300D01*
G01X847700Y474931D02*
X846900Y474131D01*
G01X847700Y490100D02*
Y474931D01*
G01X848500Y490900D02*
X847700Y490100D01*
G01X838500Y519501D02*
Y527600D01*
G01X837894Y518895D02*
X838500Y519501D01*
G01X837894Y517506D02*
Y518895D01*
G01X839099Y516301D02*
X837894Y517506D01*
G01X839099Y512157D02*
Y516301D01*
G01X838100Y511158D02*
X839099Y512157D01*
G01X838100Y509200D02*
Y511158D01*
G01X839000Y508300D02*
X838100Y509200D01*
G01X839000Y474051D02*
Y508300D01*
G01X887709Y425342D02*
X839000Y474051D01*
G01X841800Y520049D02*
Y527700D01*
G01X842900Y518949D02*
X841800Y520049D01*
G01X842900Y517800D02*
Y518949D01*
G01X841599Y516499D02*
X842900Y517800D01*
G01X841599Y511657D02*
Y516499D01*
G01X842500Y510756D02*
X841599Y511657D01*
G01X842500Y509600D02*
Y510756D01*
G01X841800Y508900D02*
X842500Y509600D01*
G01X841800Y474823D02*
Y508900D01*
G01X903146Y413477D02*
X841800Y474823D01*
G01X798300Y519788D02*
Y527700D01*
G01X799043Y519045D02*
X798300Y519788D01*
G01X799043Y517544D02*
Y519045D01*
G01X797500Y516001D02*
X799043Y517544D01*
G01X797500Y512201D02*
Y516001D01*
G01X799100Y510601D02*
X797500Y512201D01*
G01X799100Y509700D02*
Y510601D01*
G01X797400Y508000D02*
X799100Y509700D01*
G01X797400Y500900D02*
Y508000D01*
G01X800900Y497400D02*
X797400Y500900D01*
G01X800900Y491900D02*
Y497400D01*
G01X799500Y490500D02*
X800900Y491900D01*
G01X799500Y489004D02*
Y490500D01*
G01X800900Y487604D02*
X799500Y489004D01*
G01X835299Y517357D02*
Y529842D01*
G01X834899Y516957D02*
X835299Y517357D01*
G01X834899Y512057D02*
Y516957D01*
G01X835300Y511656D02*
X834899Y512057D01*
G01X835300Y508300D02*
Y511656D01*
G01X836500Y507100D02*
X835300Y508300D01*
G01X836500Y472951D02*
Y507100D01*
G01X805900Y517601D02*
Y529154D01*
G01X804788Y516489D02*
X805900Y517601D01*
G01X804788Y511657D02*
Y516489D01*
G01X805288Y511157D02*
X804788Y511657D01*
G01X805288Y508988D02*
Y511157D01*
G01X804750Y508450D02*
X805288Y508988D01*
G01X804750Y500150D02*
Y508450D01*
G01X805900Y499000D02*
X804750Y500150D01*
G01X815100Y520925D02*
Y527364D01*
G01X814337Y520162D02*
X815100Y520925D01*
G01X814337Y517371D02*
Y520162D01*
G01X815417Y516291D02*
X814337Y517371D01*
G01X815417Y512215D02*
Y516291D01*
G01X814699Y511497D02*
X815417Y512215D01*
G01X814699Y509518D02*
Y511497D01*
G01X815959Y508258D02*
X814699Y509518D01*
G01X815959Y506948D02*
Y508258D01*
G01X815391Y506380D02*
X815959Y506948D01*
G01X813700Y506380D02*
X815391D01*
G01X813200Y505880D02*
X813700Y506380D01*
G01X813200Y503680D02*
Y505880D01*
G01X813700Y503180D02*
X813200Y503680D01*
G01X815130Y503180D02*
X813700D01*
G01X815933Y502377D02*
X815130Y503180D01*
G01X815933Y498832D02*
Y502377D01*
G01X814900Y497799D02*
X815933Y498832D01*
G01X814900Y496501D02*
Y497799D01*
G01X815933Y495468D02*
X814900Y496501D01*
G01X815933Y492000D02*
Y495468D01*
G01X814800Y490867D02*
X815933Y492000D01*
G01X814800Y488633D02*
Y490867D01*
G01X815933Y487500D02*
X814800Y488633D01*
G01X815933Y483300D02*
Y487500D01*
G01X815000Y482367D02*
X815933Y483300D01*
G01X815000Y481001D02*
Y482367D01*
G01X815933Y480068D02*
X815000Y481001D01*
G01X815933Y477932D02*
Y480068D01*
G01X814900Y476899D02*
X815933Y477932D01*
G01X814900Y475301D02*
Y476899D01*
G01X815933Y474268D02*
X814900Y475301D01*
G01X815933Y469800D02*
Y474268D01*
G01X814900Y468767D02*
X815933Y469800D01*
G01X814900Y467433D02*
Y468767D01*
G01X815933Y466400D02*
X814900Y467433D01*
G01X811700Y519799D02*
Y527801D01*
G01X811841Y519658D02*
X811700Y519799D01*
G01X811841Y517199D02*
Y519658D01*
G01X811099Y516457D02*
X811841Y517199D01*
G01X811099Y511797D02*
Y516457D01*
G01X811771Y511125D02*
X811099Y511797D01*
G01X811771Y508971D02*
Y511125D01*
G01X810400Y507600D02*
X811771Y508971D01*
G01X810400Y502600D02*
Y507600D01*
G01X812900Y500100D02*
X810400Y502600D01*
G01X802367Y520767D02*
Y527033D01*
G01X801083Y519483D02*
X802367Y520767D01*
G01X801083Y517418D02*
Y519483D01*
G01X802500Y516001D02*
X801083Y517418D01*
G01X802500Y512369D02*
Y516001D01*
G01X801388Y511257D02*
X802500Y512369D01*
G01X801388Y509112D02*
Y511257D01*
G01X802622Y507878D02*
X801388Y509112D01*
G01X802622Y506874D02*
Y507878D01*
G01X802012Y506264D02*
X802622Y506874D01*
G01X799951Y506264D02*
X802012D01*
G01X799341Y505654D02*
X799951Y506264D01*
G01X799341Y503674D02*
Y505654D01*
G01X799951Y503064D02*
X799341Y503674D01*
G01X802012Y503064D02*
X799951D01*
G01X802622Y502454D02*
X802012Y503064D01*
G01X802622Y499478D02*
Y502454D01*
G01X803400Y498700D02*
X802622Y499478D01*
G01X822600Y526029D02*
Y527100D01*
G01X821990Y525419D02*
X822600Y526029D01*
G01X820732Y525419D02*
X821990D01*
G01X820122Y524809D02*
X820732Y525419D01*
G01X820122Y522829D02*
Y524809D01*
G01X820732Y522219D02*
X820122Y522829D01*
G01X821990Y522219D02*
X820732D01*
G01X822600Y521609D02*
X821990Y522219D01*
G01X822600Y519901D02*
Y521609D01*
G01X821299Y518600D02*
X822600Y519901D01*
G01X821299Y511699D02*
Y518600D01*
G01X820700Y511100D02*
X821299Y511699D01*
G01X820700Y509800D02*
Y511100D01*
G01X822500Y508000D02*
X820700Y509800D01*
G01X822500Y506381D02*
Y508000D01*
G01X821890Y505771D02*
X822500Y506381D01*
G01X820658Y505771D02*
X821890D01*
G01X820048Y505161D02*
X820658Y505771D01*
G01X820048Y503181D02*
Y505161D01*
G01X820658Y502571D02*
X820048Y503181D01*
G01X821890Y502571D02*
X820658D01*
G01X822500Y501961D02*
X821890Y502571D01*
G01X822500Y489662D02*
Y501961D01*
G01X821700Y488862D02*
X822500Y489662D01*
G01X820781Y488862D02*
X821700D01*
G01X819925Y488006D02*
X820781Y488862D01*
G01X819925Y486406D02*
Y488006D01*
G01X820669Y485662D02*
X819925Y486406D01*
G01X821700Y485662D02*
X820669D01*
G01X822500Y484862D02*
X821700Y485662D01*
G01X822500Y483262D02*
Y484862D01*
G01X821700Y482462D02*
X822500Y483262D01*
G01X820600Y482462D02*
X821700D01*
G01X819800Y481662D02*
X820600Y482462D01*
G01X819800Y480062D02*
Y481662D01*
G01X820600Y479262D02*
X819800Y480062D01*
G01X821700Y479262D02*
X820600D01*
G01X822500Y478462D02*
X821700Y479262D01*
G01X822500Y476862D02*
Y478462D01*
G01X821700Y476062D02*
X822500Y476862D01*
G01X820753Y476062D02*
X821700D01*
G01X819953Y475262D02*
X820753Y476062D01*
G01X819953Y473662D02*
Y475262D01*
G01X820753Y472862D02*
X819953Y473662D01*
G01X821700Y472862D02*
X820753D01*
G01X822500Y472062D02*
X821700Y472862D01*
G01X822500Y470462D02*
Y472062D01*
G01X821700Y469662D02*
X822500Y470462D01*
G01X820669Y469662D02*
X821700D01*
G01X819869Y468862D02*
X820669Y469662D01*
G01X819869Y467262D02*
Y468862D01*
G01X820669Y466462D02*
X819869Y467262D01*
G01X821700Y466462D02*
X820669D01*
G01X822500Y465662D02*
X821700Y466462D01*
G01X848111Y516658D02*
X848576Y517123D01*
G01X848111Y511596D02*
Y516658D01*
G01X848900Y510807D02*
X848111Y511596D01*
G01X807800Y524156D02*
Y529478D01*
G01X808900Y523056D02*
X807800Y524156D01*
G01X808900Y521596D02*
Y523056D01*
G01X807800Y520496D02*
X808900Y521596D01*
G01X807800Y517695D02*
Y520496D01*
G01X808688Y516807D02*
X807800Y517695D01*
G01X808688Y512257D02*
Y516807D01*
G01X807403Y510972D02*
X808688Y512257D01*
G01X807403Y501397D02*
Y510972D01*
G01X809596Y499204D02*
X807403Y501397D01*
G01X809596Y497234D02*
Y499204D01*
G01X808400Y496038D02*
X809596Y497234D01*
G01X808400Y494034D02*
Y496038D01*
G01X809596Y492838D02*
X808400Y494034D01*
G01X809596Y490834D02*
Y492838D01*
G01X808400Y489638D02*
X809596Y490834D01*
G01X808400Y487634D02*
Y489638D01*
G01X809596Y486438D02*
X808400Y487634D01*
G01X809596Y484434D02*
Y486438D01*
G01X808400Y483238D02*
X809596Y484434D01*
G01X808400Y481234D02*
Y483238D01*
G01X809596Y480038D02*
X808400Y481234D01*
G01X809596Y478034D02*
Y480038D01*
G01X808400Y476838D02*
X809596Y478034D01*
G01X808400Y474834D02*
Y476838D01*
G01X809596Y473638D02*
X808400Y474834D01*
G01X809596Y471634D02*
Y473638D01*
G01X808400Y470438D02*
X809596Y471634D01*
G01X808400Y468434D02*
Y470438D01*
G01X809596Y467238D02*
X808400Y468434D01*
G01X809596Y465234D02*
Y467238D01*
G01X818700Y493018D02*
X817900Y492218D01*
G01X819400Y493018D02*
X818700D01*
G01X820200Y493818D02*
X819400Y493018D01*
G01X820200Y495418D02*
Y493818D01*
G01X819400Y496218D02*
X820200Y495418D01*
G01X818700Y496218D02*
X819400D01*
G01X817900Y497018D02*
X818700Y496218D01*
G01X817900Y508100D02*
Y497018D01*
G01X818500Y508700D02*
X817900Y508100D01*
G01X818500Y511006D02*
Y508700D01*
G01X817449Y512057D02*
X818500Y511006D01*
G01X817449Y516307D02*
Y512057D01*
G01X818799Y517657D02*
X817449Y516307D01*
G01X818799Y519600D02*
Y517657D01*
G01X817607Y520792D02*
X818799Y519600D01*
G01X817607Y526607D02*
Y520792D01*
G01X844799Y587470D02*
X843503Y588766D01*
G01X844799Y584701D02*
Y587470D01*
G01X845600Y583900D02*
X844799Y584701D01*
G01X845600Y577001D02*
Y583900D01*
G01X844400Y575801D02*
X845600Y577001D01*
G01X844400Y574701D02*
Y575801D01*
G01X845799Y573302D02*
X844400Y574701D01*
G01X845799Y568497D02*
Y573302D01*
G01X844500Y567198D02*
X845799Y568497D01*
G01X844500Y565500D02*
Y567198D01*
G01X845200Y564800D02*
X844500Y565500D01*
G01X845200Y558199D02*
Y564800D01*
G01X844400Y557399D02*
X845200Y558199D01*
G01X844400Y555500D02*
Y557399D01*
G01X845499Y554401D02*
X844400Y555500D01*
G01X845499Y550057D02*
Y554401D01*
G01X844899Y549457D02*
X845499Y550057D01*
G01X844899Y547101D02*
Y549457D01*
G01X845200Y546800D02*
X844899Y547101D01*
G01X845200Y538801D02*
Y546800D01*
G01X844600Y538201D02*
X845200Y538801D01*
G01X844600Y536501D02*
Y538201D01*
G01X845599Y535502D02*
X844600Y536501D01*
G01X845599Y530466D02*
Y535502D01*
G01X844600Y529467D02*
X845599Y530466D01*
G01X844600Y527400D02*
Y529467D01*
G01X845200Y526800D02*
X844600Y527400D01*
G01X838156Y587368D02*
X836810Y588714D01*
G01X838199Y587368D02*
X838156D01*
G01X838199Y584600D02*
Y587368D01*
G01X838500Y584299D02*
X838199Y584600D01*
G01X838500Y576800D02*
Y584299D01*
G01X837866Y576166D02*
X838500Y576800D01*
G01X837866Y574534D02*
Y576166D01*
G01X839100Y573300D02*
X837866Y574534D01*
G01X839100Y568398D02*
Y573300D01*
G01X837767Y567065D02*
X839100Y568398D01*
G01X837767Y565933D02*
Y567065D01*
G01X838500Y565200D02*
X837767Y565933D01*
G01X838500Y557801D02*
Y565200D01*
G01X837566Y556867D02*
X838500Y557801D01*
G01X837566Y555534D02*
Y556867D01*
G01X839400Y553700D02*
X837566Y555534D01*
G01X839400Y550258D02*
Y553700D01*
G01X837800Y548658D02*
X839400Y550258D01*
G01X837800Y546900D02*
Y548658D01*
G01X838500Y546200D02*
X837800Y546900D01*
G01X838500Y538701D02*
Y546200D01*
G01X837800Y538001D02*
X838500Y538701D01*
G01X837800Y536701D02*
Y538001D01*
G01X839500Y535001D02*
X837800Y536701D01*
G01X839500Y531043D02*
Y535001D01*
G01X837845Y529388D02*
X839500Y531043D01*
G01X837845Y528255D02*
Y529388D01*
G01X838500Y527600D02*
X837845Y528255D01*
G01X842199Y586507D02*
X838799Y589907D01*
G01X842199Y584599D02*
Y586507D01*
G01X841800Y584200D02*
X842199Y584599D01*
G01X841800Y575899D02*
Y584200D01*
G01X842199Y575500D02*
X841800Y575899D01*
G01X842199Y574042D02*
Y575500D01*
G01X841299Y573142D02*
X842199Y574042D01*
G01X841299Y568397D02*
Y573142D01*
G01X842399Y567297D02*
X841299Y568397D01*
G01X842399Y566099D02*
Y567297D01*
G01X841800Y565500D02*
X842399Y566099D01*
G01X841800Y557799D02*
Y565500D01*
G01X842399Y557200D02*
X841800Y557799D01*
G01X842399Y555657D02*
Y557200D01*
G01X841599Y554857D02*
X842399Y555657D01*
G01X841599Y549457D02*
Y554857D01*
G01X842862Y548194D02*
X841599Y549457D01*
G01X842862Y547062D02*
Y548194D01*
G01X841900Y546100D02*
X842862Y547062D01*
G01X841900Y538699D02*
Y546100D01*
G01X842512Y538087D02*
X841900Y538699D01*
G01X842512Y536611D02*
Y538087D01*
G01X841499Y535598D02*
X842512Y536611D01*
G01X841499Y530366D02*
Y535598D01*
G01X842449Y529416D02*
X841499Y530366D01*
G01X842449Y528349D02*
Y529416D01*
G01X841800Y527700D02*
X842449Y528349D01*
G01X799200Y586045D02*
X795988Y589257D01*
G01X799200Y584800D02*
Y586045D01*
G01X798300Y583900D02*
X799200Y584800D01*
G01X798300Y576088D02*
Y583900D01*
G01X798888Y575500D02*
X798300Y576088D01*
G01X798888Y574242D02*
Y575500D01*
G01X797300Y572654D02*
X798888Y574242D01*
G01X797300Y568785D02*
Y572654D01*
G01X798876Y567209D02*
X797300Y568785D01*
G01X798876Y566076D02*
Y567209D01*
G01X798300Y565500D02*
X798876Y566076D01*
G01X798300Y557388D02*
Y565500D01*
G01X798943Y556745D02*
X798300Y557388D01*
G01X798943Y555144D02*
Y556745D01*
G01X797700Y553901D02*
X798943Y555144D01*
G01X797700Y550245D02*
Y553901D01*
G01X798888Y549057D02*
X797700Y550245D01*
G01X798888Y546788D02*
Y549057D01*
G01X798300Y546200D02*
X798888Y546788D01*
G01X798300Y539200D02*
Y546200D01*
G01X799151Y538349D02*
X798300Y539200D01*
G01X799151Y536851D02*
Y538349D01*
G01X797600Y535300D02*
X799151Y536851D01*
G01X797600Y530730D02*
Y535300D01*
G01X798899Y529431D02*
X797600Y530730D01*
G01X798899Y528299D02*
Y529431D01*
G01X798300Y527700D02*
X798899Y528299D01*
G01X835699Y586357D02*
X832799Y589257D01*
G01X835699Y585099D02*
Y586357D01*
G01X835100Y584500D02*
X835699Y585099D01*
G01X835100Y575799D02*
Y584500D01*
G01X835400Y575499D02*
X835100Y575799D01*
G01X835400Y573943D02*
Y575499D01*
G01X834426Y572969D02*
X835400Y573943D01*
G01X834426Y568470D02*
Y572969D01*
G01X835499Y567397D02*
X834426Y568470D01*
G01X835499Y565899D02*
Y567397D01*
G01X835100Y565500D02*
X835499Y565899D01*
G01X835100Y557699D02*
Y565500D01*
G01X835499Y557300D02*
X835100Y557699D01*
G01X835499Y555357D02*
Y557300D01*
G01X834899Y554757D02*
X835499Y555357D01*
G01X834899Y549857D02*
Y554757D01*
G01X835699Y549057D02*
X834899Y549857D01*
G01X835699Y547099D02*
Y549057D01*
G01X835100Y546500D02*
X835699Y547099D01*
G01X835100Y537999D02*
Y546500D01*
G01X835699Y537400D02*
X835100Y537999D01*
G01X835699Y536498D02*
Y537400D01*
G01X834899Y535698D02*
X835699Y536498D01*
G01X834899Y530242D02*
Y535698D01*
G01X835299Y529842D02*
X834899Y530242D01*
G01X805388Y586507D02*
X801988Y589907D01*
G01X805388Y584588D02*
Y586507D01*
G01X804800Y584000D02*
X805388Y584588D01*
G01X804800Y577200D02*
Y584000D01*
G01X805600Y576400D02*
X804800Y577200D01*
G01X805600Y574254D02*
Y576400D01*
G01X804488Y573142D02*
X805600Y574254D01*
G01X804488Y568397D02*
Y573142D01*
G01X805800Y567085D02*
X804488Y568397D01*
G01X805800Y565500D02*
Y567085D01*
G01X805000Y564700D02*
X805800Y565500D01*
G01X805000Y557688D02*
Y564700D01*
G01X805800Y556888D02*
X805000Y557688D01*
G01X805800Y555401D02*
Y556888D01*
G01X804788Y554389D02*
X805800Y555401D01*
G01X804788Y550013D02*
Y554389D01*
G01X805700Y549101D02*
X804788Y550013D01*
G01X805700Y547400D02*
Y549101D01*
G01X805000Y546700D02*
X805700Y547400D01*
G01X805000Y538700D02*
Y546700D01*
G01X805700Y538000D02*
X805000Y538700D01*
G01X805700Y536700D02*
Y538000D01*
G01X804688Y535688D02*
X805700Y536700D01*
G01X804688Y530366D02*
Y535688D01*
G01X805900Y529154D02*
X804688Y530366D01*
G01X814599Y587200D02*
X813085Y588714D01*
G01X814599Y584301D02*
Y587200D01*
G01X815100Y583800D02*
X814599Y584301D01*
G01X815100Y575901D02*
Y583800D01*
G01X814599Y575400D02*
X815100Y575901D01*
G01X814599Y573256D02*
Y575400D01*
G01X815199Y572656D02*
X814599Y573256D01*
G01X815199Y568497D02*
Y572656D01*
G01X814699Y567997D02*
X815199Y568497D01*
G01X814699Y565901D02*
Y567997D01*
G01X815100Y565500D02*
X814699Y565901D01*
G01X815100Y557501D02*
Y565500D01*
G01X814225Y556626D02*
X815100Y557501D01*
G01X814225Y555141D02*
Y556626D01*
G01X814949Y554417D02*
X814225Y555141D01*
G01X814949Y548807D02*
Y554417D01*
G01X814599Y548457D02*
X814949Y548807D01*
G01X814599Y546701D02*
Y548457D01*
G01X815100Y546200D02*
X814599Y546701D01*
G01X815100Y538547D02*
Y546200D01*
G01X814367Y537814D02*
X815100Y538547D01*
G01X814367Y535774D02*
Y537814D01*
G01X814949Y535192D02*
X814367Y535774D01*
G01X814949Y530242D02*
Y535192D01*
G01X814436Y529729D02*
X814949Y530242D01*
G01X814436Y528028D02*
Y529729D01*
G01X815100Y527364D02*
X814436Y528028D01*
G01X811949Y586457D02*
X808799Y589607D01*
G01X811949Y584049D02*
Y586457D01*
G01X811700Y583800D02*
X811949Y584049D01*
G01X811700Y575849D02*
Y583800D01*
G01X811949Y575600D02*
X811700Y575849D01*
G01X811949Y573942D02*
Y575600D01*
G01X810951Y572944D02*
X811949Y573942D01*
G01X810951Y568249D02*
Y572944D01*
G01X811999Y567201D02*
X810951Y568249D01*
G01X811999Y565699D02*
Y567201D01*
G01X811700Y565400D02*
X811999Y565699D01*
G01X811700Y557299D02*
Y565400D01*
G01X811999Y557000D02*
X811700Y557299D01*
G01X811999Y555157D02*
Y557000D01*
G01X811099Y554257D02*
X811999Y555157D01*
G01X811099Y549557D02*
Y554257D01*
G01X812099Y548557D02*
X811099Y549557D01*
G01X812099Y546399D02*
Y548557D01*
G01X811700Y546000D02*
X812099Y546399D01*
G01X811700Y537999D02*
Y546000D01*
G01X811907Y537792D02*
X811700Y537999D01*
G01X811907Y536050D02*
Y537792D01*
G01X811099Y535242D02*
X811907Y536050D01*
G01X811099Y530402D02*
Y535242D01*
G01X811840Y529661D02*
X811099Y530402D01*
G01X811840Y527941D02*
Y529661D01*
G01X811700Y527801D02*
X811840Y527941D01*
G01X801345Y587368D02*
X799999Y588714D01*
G01X801388Y587368D02*
X801345D01*
G01X801388Y584512D02*
Y587368D01*
G01X801700Y584200D02*
X801388Y584512D01*
G01X801700Y576500D02*
Y584200D01*
G01X800900Y575700D02*
X801700Y576500D01*
G01X800900Y574499D02*
Y575700D01*
G01X802300Y573099D02*
X800900Y574499D01*
G01X802300Y568409D02*
Y573099D01*
G01X801212Y567321D02*
X802300Y568409D01*
G01X801212Y566188D02*
Y567321D01*
G01X801700Y565700D02*
X801212Y566188D01*
G01X801700Y557512D02*
Y565700D01*
G01X800983Y556795D02*
X801700Y557512D01*
G01X800983Y555318D02*
Y556795D01*
G01X802400Y553901D02*
X800983Y555318D01*
G01X802400Y550069D02*
Y553901D01*
G01X801000Y548669D02*
X802400Y550069D01*
G01X801000Y546900D02*
Y548669D01*
G01X801700Y546200D02*
X801000Y546900D01*
G01X801700Y538900D02*
Y546200D01*
G01X801100Y538300D02*
X801700Y538900D01*
G01X801100Y536600D02*
Y538300D01*
G01X802500Y535200D02*
X801100Y536600D01*
G01X802500Y530854D02*
Y535200D01*
G01X801089Y529443D02*
X802500Y530854D01*
G01X801089Y528311D02*
Y529443D01*
G01X802367Y527033D02*
X801089Y528311D01*
G01X821299Y586443D02*
X819378Y588364D01*
G01X821299Y584701D02*
Y586443D01*
G01X821800Y584200D02*
X821299Y584701D01*
G01X821800Y576001D02*
Y584200D01*
G01X821299Y575500D02*
X821800Y576001D01*
G01X821299Y566101D02*
Y575500D01*
G01X821800Y565600D02*
X821299Y566101D01*
G01X821800Y556901D02*
Y565600D01*
G01X821299Y556400D02*
X821800Y556901D01*
G01X821299Y546101D02*
Y556400D01*
G01X821700Y545700D02*
X821299Y546101D01*
G01X821700Y538101D02*
Y545700D01*
G01X821299Y537700D02*
X821700Y538101D01*
G01X821299Y528401D02*
Y537700D01*
G01X822600Y527100D02*
X821299Y528401D01*
G01X848760Y586457D02*
X846425Y588792D01*
G01X848015Y573197D02*
X848575Y573757D01*
G01X848015Y567984D02*
Y573197D01*
G01X848799Y567200D02*
X848015Y567984D01*
G01X848031Y554378D02*
X848659Y555006D01*
G01X848031Y549436D02*
Y554378D01*
G01X848811Y548656D02*
X848031Y549436D01*
G01X847910Y535242D02*
X848726Y536058D01*
G01X847910Y530390D02*
Y535242D01*
G01X848702Y529598D02*
X847910Y530390D01*
G01X807988Y587470D02*
X806692Y588766D01*
G01X807988Y582400D02*
Y587470D01*
G01X808900Y581488D02*
X807988Y582400D01*
G01X808900Y577712D02*
Y581488D01*
G01X807988Y576800D02*
X808900Y577712D01*
G01X807988Y574012D02*
Y576800D01*
G01X808988Y573012D02*
X807988Y574012D01*
G01X808988Y568497D02*
Y573012D01*
G01X808138Y567647D02*
X808988Y568497D01*
G01X808138Y563800D02*
Y567647D01*
G01X809300Y562638D02*
X808138Y563800D01*
G01X809300Y559962D02*
Y562638D01*
G01X808138Y558800D02*
X809300Y559962D01*
G01X808138Y555157D02*
Y558800D01*
G01X808688Y554607D02*
X808138Y555157D01*
G01X808688Y550057D02*
Y554607D01*
G01X807900Y549269D02*
X808688Y550057D01*
G01X807900Y544500D02*
Y549269D01*
G01X809100Y543300D02*
X807900Y544500D01*
G01X809100Y540800D02*
Y543300D01*
G01X807900Y539600D02*
X809100Y540800D01*
G01X807900Y536600D02*
Y539600D01*
G01X808788Y535712D02*
X807900Y536600D01*
G01X808788Y530466D02*
Y535712D01*
G01X807800Y529478D02*
X808788Y530466D01*
G01X818799Y527799D02*
X817607Y526607D01*
G01X818799Y529267D02*
Y527799D01*
G01X817449Y530617D02*
X818799Y529267D01*
G01X817449Y535350D02*
Y530617D01*
G01X818799Y536700D02*
X817449Y535350D01*
G01X818799Y537800D02*
Y536700D01*
G01X818400Y538199D02*
X818799Y537800D01*
G01X818400Y546100D02*
Y538199D01*
G01X818799Y546499D02*
X818400Y546100D01*
G01X818799Y548507D02*
Y546499D01*
G01X817449Y549857D02*
X818799Y548507D01*
G01X817449Y554107D02*
Y549857D01*
G01X818599Y555257D02*
X817449Y554107D01*
G01X818599Y557000D02*
Y555257D01*
G01X818400Y557199D02*
X818599Y557000D01*
G01X818400Y565500D02*
Y557199D01*
G01X818599Y565699D02*
X818400Y565500D01*
G01X818599Y567267D02*
Y565699D01*
G01X817499Y568367D02*
X818599Y567267D01*
G01X817499Y573199D02*
Y568367D01*
G01X818649Y574349D02*
X817499Y573199D01*
G01X818649Y575500D02*
Y574349D01*
G01X818400Y575749D02*
X818649Y575500D01*
G01X818400Y584400D02*
Y575749D01*
G01X818649Y584649D02*
X818400Y584400D01*
G01X818649Y586457D02*
Y584649D01*
G01X815299Y589807D02*
X818649Y586457D01*
G01X843503Y588766D02*
Y588714D01*
G01X841229Y604499D02*
X840157D01*
G01X841929Y603799D02*
X841229Y604499D01*
G01X841929Y602525D02*
Y603799D01*
G01X840792Y601388D02*
X841929Y602525D01*
G01X840792Y600312D02*
Y601388D01*
G01X841804Y599300D02*
X840792Y600312D01*
G01X841804Y598100D02*
Y599300D01*
G01X840792Y597088D02*
X841804Y598100D01*
G01X840792Y596012D02*
Y597088D01*
G01X841904Y594900D02*
X840792Y596012D01*
G01X841904Y592267D02*
Y594900D01*
G01X841729Y592092D02*
X841904Y592267D01*
G01X841729Y590400D02*
Y592092D01*
G01X843415Y588714D02*
X841729Y590400D01*
G01X843503Y588714D02*
X843415D01*
G01X834536Y604499D02*
X833464D01*
G01X835236Y603799D02*
X834536Y604499D01*
G01X835236Y602525D02*
Y603799D01*
G01X834099Y601388D02*
X835236Y602525D01*
G01X834099Y600312D02*
Y601388D01*
G01X835111Y599300D02*
X834099Y600312D01*
G01X835111Y598100D02*
Y599300D01*
G01X834099Y597088D02*
X835111Y598100D01*
G01X834099Y596012D02*
Y597088D01*
G01X835211Y594900D02*
X834099Y596012D01*
G01X835211Y592267D02*
Y594900D01*
G01X835036Y592092D02*
X835211Y592267D01*
G01X835036Y590400D02*
Y592092D01*
G01X836722Y588714D02*
X835036Y590400D01*
G01X836810Y588714D02*
X836722D01*
G01X838799Y592399D02*
X840157Y593757D01*
G01X838799Y589907D02*
Y592399D01*
G01X838452Y605649D02*
X843503Y610700D01*
G01X838452Y595462D02*
Y605649D01*
G01X840157Y593757D02*
X838452Y595462D01*
G01X794948Y605649D02*
X799999Y610700D01*
G01X794948Y595462D02*
Y605649D01*
G01X796653Y593757D02*
X794948Y595462D01*
G01X795988Y593092D02*
X796653Y593757D01*
G01X795988Y589257D02*
Y593092D01*
G01X832799D02*
X833464Y593757D01*
G01X832799Y589257D02*
Y593092D01*
G01X831759Y605649D02*
X836810Y610700D01*
G01X831759Y595462D02*
Y605649D01*
G01X833464Y593757D02*
X831759Y595462D01*
G01X801641Y605649D02*
X806692Y610700D01*
G01X801641Y595462D02*
Y605649D01*
G01X803346Y593757D02*
X801641Y595462D01*
G01X801988Y592399D02*
X803346Y593757D01*
G01X801988Y589907D02*
Y592399D01*
G01X811111Y604499D02*
X810039D01*
G01X811711Y603899D02*
X811111Y604499D01*
G01X811711Y603001D02*
Y603899D01*
G01X810674Y601964D02*
X811711Y603001D01*
G01X810674Y600736D02*
Y601964D01*
G01X811611Y599799D02*
X810674Y600736D01*
G01X811611Y598401D02*
Y599799D01*
G01X810674Y597464D02*
X811611Y598401D01*
G01X810674Y596136D02*
Y597464D01*
G01X811811Y594999D02*
X810674Y596136D01*
G01X811811Y593100D02*
Y594999D01*
G01X811311Y592600D02*
X811811Y593100D01*
G01X811311Y590400D02*
Y592600D01*
G01X812997Y588714D02*
X811311Y590400D01*
G01X813085Y588714D02*
X812997D01*
G01X808334Y605635D02*
X812999Y610300D01*
G01X808334Y595462D02*
Y605635D01*
G01X810039Y593757D02*
X808334Y595462D01*
G01X808799Y592517D02*
X810039Y593757D01*
G01X808799Y589607D02*
Y592517D01*
G01X797725Y604499D02*
X796653D01*
G01X798425Y603799D02*
X797725Y604499D01*
G01X798425Y602525D02*
Y603799D01*
G01X797288Y601388D02*
X798425Y602525D01*
G01X797288Y600312D02*
Y601388D01*
G01X798300Y599300D02*
X797288Y600312D01*
G01X798300Y598100D02*
Y599300D01*
G01X797288Y597088D02*
X798300Y598100D01*
G01X797288Y596012D02*
Y597088D01*
G01X798400Y594900D02*
X797288Y596012D01*
G01X798400Y592267D02*
Y594900D01*
G01X798225Y592092D02*
X798400Y592267D01*
G01X798225Y590400D02*
Y592092D01*
G01X799911Y588714D02*
X798225Y590400D01*
G01X799999Y588714D02*
X799911D01*
G01X817712Y604499D02*
X816732D01*
G01X818311Y603900D02*
X817712Y604499D01*
G01X818311Y602700D02*
Y603900D01*
G01X817367Y601756D02*
X818311Y602700D01*
G01X817367Y600544D02*
Y601756D01*
G01X818211Y599700D02*
X817367Y600544D01*
G01X818211Y598000D02*
Y599700D01*
G01X817367Y597156D02*
X818211Y598000D01*
G01X817367Y595736D02*
Y597156D01*
G01X818511Y594592D02*
X817367Y595736D01*
G01X818511Y592999D02*
Y594592D01*
G01X817604Y592092D02*
X818511Y592999D01*
G01X817604Y590400D02*
Y592092D01*
G01X819290Y588714D02*
X817604Y590400D01*
G01X819378Y588714D02*
X819290D01*
G01X819378Y588364D02*
Y588714D01*
G01X846425Y593332D02*
X846850Y593757D01*
G01X846425Y588792D02*
Y593332D01*
G01X845767Y607245D02*
X848822Y610300D01*
G01X845767Y606057D02*
Y607245D01*
G01X845145Y605435D02*
X845767Y606057D01*
G01X845145Y595462D02*
Y605435D01*
G01X846850Y593757D02*
X845145Y595462D01*
G01X847922Y604499D02*
X846850D01*
G01X848522Y603899D02*
X847922Y604499D01*
G01X847485Y601964D02*
X848522Y603001D01*
G01X847485Y600736D02*
Y601964D01*
G01X848422Y599799D02*
X847485Y600736D01*
G01Y597464D02*
X848422Y598401D01*
G01X847485Y596136D02*
Y597464D01*
G01X848622Y594999D02*
X847485Y596136D01*
G01X848122Y592600D02*
X848622Y593100D01*
G01X848122Y590400D02*
Y592600D01*
G01X849808Y588714D02*
X848122Y590400D01*
G01X804418Y604499D02*
X803346D01*
G01X805118Y603799D02*
X804418Y604499D01*
G01X805118Y602525D02*
Y603799D01*
G01X803981Y601388D02*
X805118Y602525D01*
G01X803981Y600312D02*
Y601388D01*
G01X804993Y599300D02*
X803981Y600312D01*
G01X804993Y598100D02*
Y599300D01*
G01X803981Y597088D02*
X804993Y598100D01*
G01X803981Y596012D02*
Y597088D01*
G01X805093Y594900D02*
X803981Y596012D01*
G01X805093Y592267D02*
Y594900D01*
G01X804918Y592092D02*
X805093Y592267D01*
G01X804918Y590400D02*
Y592092D01*
G01X806604Y588714D02*
X804918Y590400D01*
G01X806692Y588714D02*
X806604D01*
G01X806692Y588766D02*
Y588714D01*
G01X815027Y595462D02*
X816732Y593757D01*
G01X815027Y605949D02*
Y595462D01*
G01X819378Y610300D02*
X815027Y605949D01*
G01X815299Y592324D02*
Y589807D01*
G01X816732Y593757D02*
X815299Y592324D01*
G01X910071Y18828D02*
X911921Y20678D01*
G01X910071Y17464D02*
Y18828D01*
G01X908621Y16014D02*
X910071Y17464D01*
G01X908621Y13925D02*
Y16014D01*
G01X910432Y12114D02*
X908621Y13925D01*
G01X909633Y-6100D02*
X910633D01*
G01X908333Y-7400D02*
X909633Y-6100D01*
G01X908333Y-8654D02*
Y-7400D01*
G01X907086Y-9901D02*
X908333Y-8654D01*
G01X882310Y29249D02*
Y34691D01*
G01X881760Y28699D02*
X882310Y29249D01*
G01X881760Y18964D02*
Y28699D01*
G01X878410Y15614D02*
X881760Y18964D01*
G01X878410Y14018D02*
Y15614D01*
G01X880314Y12114D02*
X878410Y14018D01*
G01X881703Y10725D02*
X880314Y12114D01*
G01X881703Y-2288D02*
Y10725D01*
G01X882315Y-2900D02*
X881703Y-2288D01*
G01X882315Y-4300D02*
Y-2900D01*
G01X880515Y-6100D02*
X882315Y-4300D01*
G01X879515Y-6100D02*
X880515D01*
G01X878215Y-7400D02*
X879515Y-6100D01*
G01X878215Y-8654D02*
Y-7400D01*
G01X876968Y-9901D02*
X878215Y-8654D01*
G01X883661Y-8347D02*
Y-9901D01*
G01X885908Y-6100D02*
X883661Y-8347D01*
G01X887132Y-6100D02*
X885908D01*
G01X888708Y-4524D02*
X887132Y-6100D01*
G01X888708Y-2900D02*
Y-4524D01*
G01X887933Y-2125D02*
X888708Y-2900D01*
G01X887933Y10888D02*
Y-2125D01*
G01X886707Y12114D02*
X887933Y10888D01*
G01X888554Y28832D02*
Y36796D01*
G01X888000Y28278D02*
X888554Y28832D01*
G01X888000Y18793D02*
Y28278D01*
G01X884721Y15514D02*
X888000Y18793D01*
G01X884721Y14100D02*
Y15514D01*
G01X886707Y12114D02*
X884721Y14100D01*
G01X906158Y16229D02*
X907086Y17157D01*
G01X906158Y13101D02*
Y16229D01*
G01X909200Y10059D02*
X906158Y13101D01*
G01X909200Y8674D02*
Y10059D01*
G01X907525Y6999D02*
X909200Y8674D01*
G01X907525Y5876D02*
Y6999D01*
G01X909025Y4376D02*
X907525Y5876D01*
G01X909025Y3024D02*
Y4376D01*
G01X907525Y1524D02*
X909025Y3024D01*
G01X907525Y301D02*
Y1524D01*
G01X908958Y-1132D02*
X907525Y301D01*
G01X908958Y-2226D02*
Y-1132D01*
G01X910432Y-3700D02*
X908958Y-2226D01*
G01X908521Y29099D02*
Y34721D01*
G01X909121Y28499D02*
X908521Y29099D01*
G01X909121Y21414D02*
Y28499D01*
G01X907086Y19379D02*
X909121Y21414D01*
G01X907086Y17157D02*
Y19379D01*
G01X855322Y-3233D02*
X856189Y-4100D01*
G01X855322Y-932D02*
Y-3233D01*
G01X853689Y701D02*
X855322Y-932D01*
G01X853689Y2000D02*
Y701D01*
G01X855039Y3350D02*
X853689Y2000D01*
G01X855039Y4250D02*
Y3350D01*
G01X853789Y5500D02*
X855039Y4250D01*
G01X853789Y6699D02*
Y5500D01*
G01X855322Y8232D02*
X853789Y6699D01*
G01X855322Y10200D02*
Y8232D01*
G01X852422Y13100D02*
X855322Y10200D01*
G01X852422Y16036D02*
Y13100D01*
G01X853543Y17157D02*
X852422Y16036D01*
G01X854260Y29594D02*
Y34259D01*
G01X855410Y28444D02*
X854260Y29594D01*
G01X855410Y26309D02*
Y28444D01*
G01X853543Y24442D02*
X855410Y26309D01*
G01X853543Y17157D02*
Y24442D01*
G01X850321Y-6100D02*
X849097D01*
G01X851897Y-4524D02*
X850321Y-6100D01*
G01X851897Y-2900D02*
Y-4524D01*
G01X851122Y-2125D02*
X851897Y-2900D01*
G01X851122Y10888D02*
Y-2125D01*
G01X849896Y12114D02*
X851122Y10888D01*
G01X851760Y28849D02*
Y35049D01*
G01X851100Y28189D02*
X851760Y28849D01*
G01X851100Y18704D02*
Y28189D01*
G01X848722Y-3012D02*
X849810Y-4100D01*
G01X848722Y-1132D02*
Y-3012D01*
G01X848789Y4200D02*
Y3000D01*
G01X848722Y10301D02*
Y8432D01*
G01X848810Y20109D02*
Y28491D01*
G01X858110Y25311D02*
Y36810D01*
G01X855400Y22601D02*
X858110Y25311D01*
G01X855400Y16500D02*
Y22601D01*
G01X854116Y15216D02*
X855400Y16500D01*
G01X854116Y14187D02*
Y15216D01*
G01X856189Y12114D02*
X854116Y14187D01*
G01X857662Y10641D02*
X856189Y12114D01*
G01X857662Y-2484D02*
Y10641D01*
G01X858278Y-3100D02*
X857662Y-2484D01*
G01X858278Y-4444D02*
Y-3100D01*
G01X856822Y-5900D02*
X858278Y-4444D01*
G01X855422Y-5900D02*
X856822D01*
G01X853543Y-7779D02*
X855422Y-5900D01*
G01X853543Y-9901D02*
Y-7779D01*
G01X869347Y16229D02*
X870275Y17157D01*
G01X869347Y13101D02*
Y16229D01*
G01X872389Y10059D02*
X869347Y13101D01*
G01X872389Y8674D02*
Y10059D01*
G01X870714Y6999D02*
X872389Y8674D01*
G01X870714Y5876D02*
Y6999D01*
G01X872214Y4376D02*
X870714Y5876D01*
G01X872214Y3024D02*
Y4376D01*
G01X870714Y1524D02*
X872214Y3024D01*
G01X870714Y301D02*
Y1524D01*
G01X872147Y-1132D02*
X870714Y301D01*
G01X872147Y-2226D02*
Y-1132D01*
G01X873621Y-3700D02*
X872147Y-2226D01*
G01X871710Y29099D02*
Y34811D01*
G01X872100Y28709D02*
X871710Y29099D01*
G01X872100Y18982D02*
Y28709D01*
G01X870275Y17157D02*
X872100Y18982D01*
G01X882733Y16229D02*
X883661Y17157D01*
G01X882733Y13101D02*
Y16229D01*
G01X885533Y10301D02*
X882733Y13101D01*
G01X885533Y8432D02*
Y10301D01*
G01X884150Y7049D02*
X885533Y8432D01*
G01X884150Y5650D02*
Y7049D01*
G01X885600Y4200D02*
X884150Y5650D01*
G01X885600Y3000D02*
Y4200D01*
G01X884100Y1500D02*
X885600Y3000D01*
G01X884100Y301D02*
Y1500D01*
G01X885533Y-1132D02*
X884100Y301D01*
G01X885533Y-3012D02*
Y-1132D01*
G01X886621Y-4100D02*
X885533Y-3012D01*
G01X884721Y29379D02*
Y34299D01*
G01X885621Y28479D02*
X884721Y29379D01*
G01X885621Y19117D02*
Y28479D01*
G01X883661Y17157D02*
X885621Y19117D01*
G01X894473Y10641D02*
X893000Y12114D01*
G01X894473Y-2484D02*
Y10641D01*
G01X895089Y-3100D02*
X894473Y-2484D01*
G01X895089Y-4444D02*
Y-3100D01*
G01X893633Y-5900D02*
X895089Y-4444D01*
G01X892233Y-5900D02*
X893633D01*
G01X890354Y-7779D02*
X892233Y-5900D01*
G01X890354Y-9901D02*
Y-7779D01*
G01X894921Y25921D02*
Y37221D01*
G01X892421Y23421D02*
X894921Y25921D01*
G01X892421Y16722D02*
Y23421D01*
G01X890927Y15228D02*
X892421Y16722D01*
G01X890927Y14187D02*
Y15228D01*
G01X893000Y12114D02*
X890927Y14187D01*
G01X875500Y29089D02*
Y34901D01*
G01X875100Y28689D02*
X875500Y29089D01*
G01X875100Y19304D02*
Y28689D01*
G01X871810Y16014D02*
X875100Y19304D01*
G01X871810Y13925D02*
Y16014D01*
G01X873621Y12114D02*
X871810Y13925D01*
G01X875010Y10725D02*
X873621Y12114D01*
G01X875010Y-2288D02*
Y10725D01*
G01X875622Y-2900D02*
X875010Y-2288D01*
G01X875622Y-4300D02*
Y-2900D01*
G01X873822Y-6100D02*
X875622Y-4300D01*
G01X872822Y-6100D02*
X873822D01*
G01X871522Y-7400D02*
X872822Y-6100D01*
G01X871522Y-8654D02*
Y-7400D01*
G01X870275Y-9901D02*
X871522Y-8654D01*
G01X878500Y28909D02*
Y35001D01*
G01X878800Y28609D02*
X878500Y28909D01*
G01X878800Y18989D02*
Y28609D01*
G01X876968Y17157D02*
X878800Y18989D01*
G01X875847Y16036D02*
X876968Y17157D01*
G01X875847Y13100D02*
Y16036D01*
G01X879189Y9758D02*
X875847Y13100D01*
G01X879189Y8700D02*
Y9758D01*
G01X877389Y6900D02*
X879189Y8700D01*
G01X877389Y5325D02*
Y6900D01*
G01X878589Y4125D02*
X877389Y5325D01*
G01X878589Y2999D02*
Y4125D01*
G01X877389Y1799D02*
X878589Y2999D01*
G01X877389Y426D02*
Y1799D01*
G01X878747Y-932D02*
X877389Y426D01*
G01X878747Y-2133D02*
Y-932D01*
G01X880314Y-3700D02*
X878747Y-2133D01*
G01X892133Y-3233D02*
X893000Y-4100D01*
G01X892133Y-932D02*
Y-3233D01*
G01X890500Y701D02*
X892133Y-932D01*
G01X890500Y2000D02*
Y701D01*
G01X891850Y3350D02*
X890500Y2000D01*
G01X891850Y4250D02*
Y3350D01*
G01X890600Y5500D02*
X891850Y4250D01*
G01X890600Y6699D02*
Y5500D01*
G01X892133Y8232D02*
X890600Y6699D01*
G01X892133Y10200D02*
Y8232D01*
G01X889233Y13100D02*
X892133Y10200D01*
G01X889233Y16036D02*
Y13100D01*
G01X890354Y17157D02*
X889233Y16036D01*
G01X891200Y29465D02*
Y34400D01*
G01X892221Y28444D02*
X891200Y29465D01*
G01X892221Y26921D02*
Y28444D01*
G01X890354Y25054D02*
X892221Y26921D01*
G01X890354Y17157D02*
Y25054D01*
G01X881461Y92223D02*
Y121699D01*
G01X882410Y91274D02*
X881461Y92223D01*
G01X882410Y86614D02*
Y91274D01*
G01X881710Y85914D02*
X882410Y86614D01*
G01X881710Y84000D02*
Y85914D01*
G01X882100Y83610D02*
X881710Y84000D01*
G01X882100Y75000D02*
Y83610D01*
G01X881710Y74610D02*
X882100Y75000D01*
G01X881710Y73091D02*
Y74610D01*
G01X882260Y72541D02*
X881710Y73091D01*
G01X882260Y66999D02*
Y72541D01*
G01X881760Y66499D02*
X882260Y66999D01*
G01X881760Y53914D02*
Y66499D01*
G01X882221Y53453D02*
X881760Y53914D01*
G01X882221Y48575D02*
Y53453D01*
G01X881710Y48064D02*
X882221Y48575D01*
G01X881710Y46300D02*
Y48064D01*
G01X882400Y45610D02*
X881710Y46300D01*
G01X882400Y37600D02*
Y45610D01*
G01X881710Y36910D02*
X882400Y37600D01*
G01X881710Y35291D02*
Y36910D01*
G01X882310Y34691D02*
X881710Y35291D01*
G01X888550Y86443D02*
Y103350D01*
G01X888400Y86293D02*
X888550Y86443D01*
G01X888400Y83900D02*
Y86293D01*
G01X889000Y83300D02*
X888400Y83900D01*
G01X889000Y75399D02*
Y83300D01*
G01X888500Y74899D02*
X889000Y75399D01*
G01X888500Y64700D02*
Y74899D01*
G01X888321Y64521D02*
X888500Y64700D01*
G01X888321Y53864D02*
Y64521D01*
G01X888571Y53614D02*
X888321Y53864D01*
G01X888571Y48664D02*
Y53614D01*
G01X888221Y48314D02*
X888571Y48664D01*
G01X888221Y46200D02*
Y48314D01*
G01X889700Y44721D02*
X888221Y46200D01*
G01X889700Y37942D02*
Y44721D01*
G01X888554Y36796D02*
X889700Y37942D01*
G01X908921Y91614D02*
Y105627D01*
G01X908521Y91214D02*
X908921Y91614D01*
G01X908521Y86514D02*
Y91214D01*
G01X909321Y85714D02*
X908521Y86514D01*
G01X909321Y84120D02*
Y85714D01*
G01X908700Y83499D02*
X909321Y84120D01*
G01X908700Y75600D02*
Y83499D01*
G01X909321Y74979D02*
X908700Y75600D01*
G01X909321Y73321D02*
Y74979D01*
G01X908521Y72521D02*
X909321Y73321D01*
G01X908521Y66899D02*
Y72521D01*
G01X908921Y66499D02*
X908521Y66899D01*
G01X908921Y53814D02*
Y66499D01*
G01X908521Y53414D02*
X908921Y53814D01*
G01X908521Y48714D02*
Y53414D01*
G01X909321Y47914D02*
X908521Y48714D01*
G01X909321Y46400D02*
Y47914D01*
G01X908600Y45679D02*
X909321Y46400D01*
G01X908600Y37700D02*
Y45679D01*
G01X909321Y36979D02*
X908600Y37700D01*
G01X909321Y35521D02*
Y36979D01*
G01X908521Y34721D02*
X909321Y35521D01*
G01X855400Y92100D02*
Y108316D01*
G01X854260Y90960D02*
X855400Y92100D01*
G01X854260Y86714D02*
Y90960D01*
G01X855610Y85364D02*
X854260Y86714D01*
G01X855610Y84010D02*
Y85364D01*
G01X854800Y83200D02*
X855610Y84010D01*
G01X854800Y75400D02*
Y83200D01*
G01X855610Y74590D02*
X854800Y75400D01*
G01X855610Y73409D02*
Y74590D01*
G01X854260Y72059D02*
X855610Y73409D01*
G01X854260Y67417D02*
Y72059D01*
G01X855610Y66067D02*
X854260Y67417D01*
G01X855610Y54510D02*
Y66067D01*
G01X854260Y53160D02*
X855610Y54510D01*
G01X854260Y48914D02*
Y53160D01*
G01X855610Y47564D02*
X854260Y48914D01*
G01X855610Y46400D02*
Y47564D01*
G01X855000Y45790D02*
X855610Y46400D01*
G01X855000Y37400D02*
Y45790D01*
G01X855610Y36790D02*
X855000Y37400D01*
G01X855610Y35609D02*
Y36790D01*
G01X854260Y34259D02*
X855610Y35609D01*
G01X851743Y91431D02*
Y108957D01*
G01X851760Y91414D02*
X851743Y91431D01*
G01X851760Y86464D02*
Y91414D01*
G01X851410Y86114D02*
X851760Y86464D01*
G01X851410Y83900D02*
Y86114D01*
G01X852000Y83310D02*
X851410Y83900D01*
G01X852000Y75800D02*
Y83310D01*
G01X851410Y75210D02*
X852000Y75800D01*
G01X851410Y73199D02*
Y75210D01*
G01X851760Y72849D02*
X851410Y73199D01*
G01X851760Y66649D02*
Y72849D01*
G01X851510Y66399D02*
X851760Y66649D01*
G01X851510Y53864D02*
Y66399D01*
G01X851760Y53614D02*
X851510Y53864D01*
G01X851760Y48664D02*
Y53614D01*
G01X851410Y48314D02*
X851760Y48664D01*
G01X851410Y46000D02*
Y48314D01*
G01X852000Y45410D02*
X851410Y46000D01*
G01X852000Y37900D02*
Y45410D01*
G01X851410Y37310D02*
X852000Y37900D01*
G01X851410Y35399D02*
Y37310D01*
G01X851760Y35049D02*
X851410Y35399D01*
G01X849200Y92504D02*
Y110528D01*
G01X848910Y84200D02*
Y85414D01*
G01Y73099D02*
Y74790D01*
G01X848810Y54314D02*
Y66291D01*
G01X848910Y46310D02*
Y47614D01*
G01Y35299D02*
Y37200D01*
G01X858110Y94290D02*
X857500Y94900D01*
G01X858110Y84052D02*
Y94290D01*
G01X858700Y83462D02*
X858110Y84052D01*
G01X858700Y75400D02*
Y83462D01*
G01X858110Y74810D02*
X858700Y75400D01*
G01X858110Y46200D02*
Y74810D01*
G01X858800Y45510D02*
X858110Y46200D01*
G01X858800Y37500D02*
Y45510D01*
G01X858110Y36810D02*
X858800Y37500D01*
G01X872100Y91604D02*
Y96556D01*
G01X871710Y91214D02*
X872100Y91604D01*
G01X871710Y86514D02*
Y91214D01*
G01X872510Y85714D02*
X871710Y86514D01*
G01X872510Y84200D02*
Y85714D01*
G01X871800Y83490D02*
X872510Y84200D01*
G01X871800Y75500D02*
Y83490D01*
G01X872510Y74790D02*
X871800Y75500D01*
G01X872510Y73411D02*
Y74790D01*
G01X871710Y72611D02*
X872510Y73411D01*
G01X871710Y66899D02*
Y72611D01*
G01X872110Y66499D02*
X871710Y66899D01*
G01X872110Y53814D02*
Y66499D01*
G01X871710Y53414D02*
X872110Y53814D01*
G01X871710Y48714D02*
Y53414D01*
G01X872100Y48324D02*
X871710Y48714D01*
G01X872100Y46000D02*
Y48324D01*
G01X871700Y45600D02*
X872100Y46000D01*
G01X871700Y37700D02*
Y45600D01*
G01X872100Y37300D02*
X871700Y37700D01*
G01X872100Y35201D02*
Y37300D01*
G01X871710Y34811D02*
X872100Y35201D01*
G01X885621Y92114D02*
Y105027D01*
G01X884721Y91214D02*
X885621Y92114D01*
G01X884721Y86414D02*
Y91214D01*
G01X885721Y85414D02*
X884721Y86414D01*
G01X885721Y84020D02*
Y85414D01*
G01X885200Y83499D02*
X885721Y84020D01*
G01X885200Y75200D02*
Y83499D01*
G01X885721Y74679D02*
X885200Y75200D01*
G01X885721Y73099D02*
Y74679D01*
G01X884721Y72099D02*
X885721Y73099D01*
G01X884721Y67079D02*
Y72099D01*
G01X885621Y66179D02*
X884721Y67079D01*
G01X885621Y54314D02*
Y66179D01*
G01X884721Y53414D02*
X885621Y54314D01*
G01X884721Y48614D02*
Y53414D01*
G01X885721Y47614D02*
X884721Y48614D01*
G01X885721Y46200D02*
Y47614D01*
G01X885200Y45679D02*
X885721Y46200D01*
G01X885200Y37300D02*
Y45679D01*
G01X885721Y36779D02*
X885200Y37300D01*
G01X885721Y35299D02*
Y36779D01*
G01X884721Y34299D02*
X885721Y35299D01*
G01X894921Y83980D02*
Y114796D01*
G01X895500Y83401D02*
X894921Y83980D01*
G01X895500Y75400D02*
Y83401D01*
G01X894921Y74821D02*
X895500Y75400D01*
G01X894921Y46100D02*
Y74821D01*
G01X895500Y45521D02*
X894921Y46100D01*
G01X895500Y37800D02*
Y45521D01*
G01X894921Y37221D02*
X895500Y37800D01*
G01X875100Y91724D02*
Y97077D01*
G01X875810Y91014D02*
X875100Y91724D01*
G01X875810Y86514D02*
Y91014D01*
G01X875010Y85714D02*
X875810Y86514D01*
G01X875010Y83900D02*
Y85714D01*
G01X875600Y83310D02*
X875010Y83900D01*
G01X875600Y75400D02*
Y83310D01*
G01X875010Y74810D02*
X875600Y75400D01*
G01X875010Y73091D02*
Y74810D01*
G01X875910Y72191D02*
X875010Y73091D01*
G01X875910Y67299D02*
Y72191D01*
G01X875110Y66499D02*
X875910Y67299D01*
G01X875110Y53914D02*
Y66499D01*
G01X875810Y53214D02*
X875110Y53914D01*
G01X875810Y48714D02*
Y53214D01*
G01X875100Y48004D02*
X875810Y48714D01*
G01X875100Y46200D02*
Y48004D01*
G01X875400Y45900D02*
X875100Y46200D01*
G01X875400Y37600D02*
Y45900D01*
G01X875100Y37300D02*
X875400Y37600D01*
G01X875100Y35301D02*
Y37300D01*
G01X875500Y34901D02*
X875100Y35301D01*
G01X878961Y91765D02*
Y109611D01*
G01X878310Y91114D02*
X878961Y91765D01*
G01X878310Y86414D02*
Y91114D01*
G01X878910Y85814D02*
X878310Y86414D01*
G01X878910Y84000D02*
Y85814D01*
G01X878500Y83590D02*
X878910Y84000D01*
G01X878500Y75400D02*
Y83590D01*
G01X878910Y74990D02*
X878500Y75400D01*
G01X878910Y73111D02*
Y74990D01*
G01X878410Y72611D02*
X878910Y73111D01*
G01X878410Y66799D02*
Y72611D01*
G01X879260Y65949D02*
X878410Y66799D01*
G01X879260Y54264D02*
Y65949D01*
G01X878310Y53314D02*
X879260Y54264D01*
G01X878310Y48614D02*
Y53314D01*
G01X878910Y48014D02*
X878310Y48614D01*
G01X878910Y46100D02*
Y48014D01*
G01X878344Y45534D02*
X878910Y46100D01*
G01X878344Y37556D02*
Y45534D01*
G01X878910Y36990D02*
X878344Y37556D01*
G01X878910Y35411D02*
Y36990D01*
G01X878500Y35001D02*
X878910Y35411D01*
G01X892421Y92322D02*
Y104827D01*
G01X891071Y90972D02*
X892421Y92322D01*
G01X891071Y86714D02*
Y90972D01*
G01X892421Y85364D02*
X891071Y86714D01*
G01X892421Y84100D02*
Y85364D01*
G01X891900Y83579D02*
X892421Y84100D01*
G01X891900Y75100D02*
Y83579D01*
G01X892421Y74579D02*
X891900Y75100D01*
G01X892421Y73333D02*
Y74579D01*
G01X891100Y72012D02*
X892421Y73333D01*
G01X891100Y67388D02*
Y72012D01*
G01X892300Y66188D02*
X891100Y67388D01*
G01X892300Y54401D02*
Y66188D01*
G01X891071Y53172D02*
X892300Y54401D01*
G01X891071Y48914D02*
Y53172D01*
G01X892200Y47785D02*
X891071Y48914D01*
G01X892200Y46300D02*
Y47785D01*
G01X891800Y45900D02*
X892200Y46300D01*
G01X891800Y37600D02*
Y45900D01*
G01X892200Y37200D02*
X891800Y37600D01*
G01X892200Y35400D02*
Y37200D01*
G01X891200Y34400D02*
X892200Y35400D01*
G01X881461Y126926D02*
X917984Y163449D01*
G01X881461Y125359D02*
Y126926D01*
G01X880851Y124749D02*
X881461Y125359D01*
G01X878769Y124749D02*
X880851D01*
G01X878159Y124139D02*
X878769Y124749D01*
G01X878159Y122919D02*
Y124139D01*
G01X878769Y122309D02*
X878159Y122919D01*
G01X880851Y122309D02*
X878769D01*
G01X881461Y121699D02*
X880851Y122309D01*
G01X887974Y124246D02*
X954700Y190972D01*
G01X887974Y111774D02*
Y124246D01*
G01X888574Y111174D02*
X887974Y111774D01*
G01X888574Y105874D02*
Y111174D01*
G01X888321Y105621D02*
X888574Y105874D01*
G01X888321Y103579D02*
Y105621D01*
G01X888550Y103350D02*
X888321Y103579D01*
G01X909174Y114682D02*
X934138Y139646D01*
G01X909174Y111474D02*
Y114682D01*
G01X908174Y110474D02*
X909174Y111474D01*
G01X908174Y106374D02*
Y110474D01*
G01X908921Y105627D02*
X908174Y106374D01*
G01X864982Y155784D02*
X866001Y156803D01*
G01X864190Y155783D02*
X864982Y155784D01*
G01X863150Y156823D02*
X864190Y155783D01*
G01X861338Y155803D02*
X862358Y156823D01*
G01X861339Y155013D02*
X861338Y155803D01*
G01X862379Y153973D02*
X861339Y155013D01*
G01X862379Y153181D02*
Y153973D01*
G01X861360Y152162D02*
X862379Y153181D01*
G01X860568Y152161D02*
X861360Y152162D01*
G01X859528Y153201D02*
X860568Y152161D01*
G01X858736Y153201D02*
X859528D01*
G01X857600Y152065D02*
X858736Y153201D01*
G01X857600Y149301D02*
Y152065D01*
G01X849118Y140819D02*
X857600Y149301D01*
G01X849118Y116219D02*
Y140819D01*
G01X858200Y135532D02*
X902442Y179774D01*
G01X858200Y111116D02*
Y135532D01*
G01X855400Y108316D02*
X858200Y111116D01*
G01X855700Y136690D02*
X897637Y178627D01*
G01X855700Y112914D02*
Y136690D01*
G01X851743Y108957D02*
X855700Y112914D01*
G01X853200Y138304D02*
X895214Y180318D01*
G01X853200Y114528D02*
Y138304D01*
G01X849200Y110528D02*
X853200Y114528D01*
G01X860700Y134556D02*
X909205Y183061D01*
G01X860700Y110000D02*
Y134556D01*
G01X857500Y106800D02*
X860700Y110000D01*
G01X857500Y94900D02*
Y106800D01*
G01X881791Y141490D02*
X921469Y181168D01*
G01X881791Y140628D02*
Y141490D01*
G01X882995Y139424D02*
X881791Y140628D01*
G01X882995Y138562D02*
Y139424D01*
G01X882131Y137698D02*
X882995Y138562D01*
G01X881269Y137698D02*
X882131D01*
G01X880065Y138902D02*
X881269Y137698D01*
G01X879203Y138902D02*
X880065D01*
G01X878339Y138038D02*
X879203Y138902D01*
G01X878339Y137176D02*
Y138038D01*
G01X879543Y135972D02*
X878339Y137176D01*
G01X879543Y135110D02*
Y135972D01*
G01X878679Y134246D02*
X879543Y135110D01*
G01X877817Y134246D02*
X878679D01*
G01X876613Y135450D02*
X877817Y134246D01*
G01X875751Y135450D02*
X876613D01*
G01X874887Y134586D02*
X875751Y135450D01*
G01X874887Y133724D02*
Y134586D01*
G01X876091Y132520D02*
X874887Y133724D01*
G01X876091Y131658D02*
Y132520D01*
G01X875227Y130794D02*
X876091Y131658D01*
G01X874365Y130794D02*
X875227D01*
G01X873161Y131998D02*
X874365Y130794D01*
G01X872299Y131998D02*
X873161D01*
G01X870810Y130509D02*
X872299Y131998D01*
G01X870810Y97846D02*
Y130509D01*
G01X872100Y96556D02*
X870810Y97846D01*
G01X885461Y125269D02*
X922442Y162250D01*
G01X885461Y111361D02*
Y125269D01*
G01X884774Y110674D02*
X885461Y111361D01*
G01X884774Y105874D02*
Y110674D01*
G01X885621Y105027D02*
X884774Y105874D01*
G01X900800Y127654D02*
X918502Y145356D01*
G01X900800Y120675D02*
Y127654D01*
G01X894921Y114796D02*
X900800Y120675D01*
G01X853491Y151033D02*
X874381Y171923D01*
G01X853491Y150241D02*
Y151033D01*
G01X854070Y149662D02*
X853491Y150241D01*
G01X854070Y148870D02*
Y149662D01*
G01X853051Y147851D02*
X854070Y148870D01*
G01X852259Y147851D02*
X853051D01*
G01X851680Y148430D02*
X852259Y147851D01*
G01X850888Y148430D02*
X851680D01*
G01X849869Y147411D02*
X850888Y148430D01*
G01X849869Y146619D02*
Y147411D01*
G01X850448Y146040D02*
X849869Y146619D01*
G01X850448Y145248D02*
Y146040D01*
G01X849429Y144229D02*
X850448Y145248D01*
G01X848637Y144229D02*
X849429D01*
G01X897177Y153676D02*
X929101Y185600D01*
G01X897177Y152815D02*
Y153676D01*
G01X897705Y152287D02*
X897177Y152815D01*
G01X897705Y151579D02*
Y152287D01*
G01X896687Y150561D02*
X897705Y151579D01*
G01X895979Y150561D02*
X896687D01*
G01X895452Y151088D02*
X895979Y150561D01*
G01X894589Y151088D02*
X895452D01*
G01X888996Y145495D02*
X894589Y151088D01*
G01X888996Y141696D02*
Y145495D01*
G01X873310Y126010D02*
X888996Y141696D01*
G01X873310Y109392D02*
Y126010D01*
G01X873920Y108782D02*
X873310Y109392D01*
G01X874988Y108782D02*
X873920D01*
G01X875598Y108172D02*
X874988Y108782D01*
G01X875598Y106952D02*
Y108172D01*
G01X874988Y106342D02*
X875598Y106952D01*
G01X873920Y106342D02*
X874988D01*
G01X873310Y105732D02*
X873920Y106342D01*
G01X873310Y104512D02*
Y105732D01*
G01X873920Y103902D02*
X873310Y104512D01*
G01X874988Y103902D02*
X873920D01*
G01X875598Y103292D02*
X874988Y103902D01*
G01X875598Y102072D02*
Y103292D01*
G01X874988Y101462D02*
X875598Y102072D01*
G01X873920Y101462D02*
X874988D01*
G01X873310Y100852D02*
X873920Y101462D01*
G01X873310Y98867D02*
Y100852D01*
G01X875100Y97077D02*
X873310Y98867D01*
G01X905380Y155242D02*
X903873Y156749D01*
G01X905380Y154380D02*
Y155242D01*
G01X904516Y153516D02*
X905380Y154380D01*
G01X903654Y153516D02*
X904516D01*
G01X902147Y155023D02*
X903654Y153516D01*
G01X901285Y155023D02*
X902147D01*
G01X900421Y154159D02*
X901285Y155023D01*
G01X900421Y153297D02*
Y154159D01*
G01X901928Y151790D02*
X900421Y153297D01*
G01X901928Y150928D02*
Y151790D01*
G01X895636Y144636D02*
X901928Y150928D01*
G01X894844Y144636D02*
X895636D01*
G01X893886Y145594D02*
X894844Y144636D01*
G01X893094Y145594D02*
X893886D01*
G01X892075Y144575D02*
X893094Y145594D01*
G01X892075Y143783D02*
Y144575D01*
G01X893033Y142825D02*
X892075Y143783D01*
G01X893033Y142033D02*
Y142825D01*
G01X876010Y125010D02*
X893033Y142033D01*
G01X876010Y120254D02*
Y125010D01*
G01X876620Y119644D02*
X876010Y120254D01*
G01X878372Y119644D02*
X876620D01*
G01X878982Y119034D02*
X878372Y119644D01*
G01X878982Y117785D02*
Y119034D01*
G01X878372Y117175D02*
X878982Y117785D01*
G01X876620Y117175D02*
X878372D01*
G01X876010Y116565D02*
X876620Y117175D01*
G01X876010Y115636D02*
Y116565D01*
G01X876620Y115026D02*
X876010Y115636D01*
G01X878372Y115026D02*
X876620D01*
G01X878982Y114416D02*
X878372Y115026D01*
G01X878982Y113441D02*
Y114416D01*
G01X878372Y112831D02*
X878982Y113441D01*
G01X876620Y112831D02*
X878372D01*
G01X876010Y112221D02*
X876620Y112831D01*
G01X876010Y111185D02*
Y112221D01*
G01X877084Y110111D02*
X876010Y111185D01*
G01X878461Y110111D02*
X877084D01*
G01X878961Y109611D02*
X878461Y110111D01*
G01X896443Y126587D02*
X916094Y146238D01*
G01X896443Y125879D02*
Y126587D01*
G01X898889Y123433D02*
X896443Y125879D01*
G01X898889Y122300D02*
Y123433D01*
G01X897653Y121064D02*
X898889Y122300D01*
G01X896524Y121064D02*
X897653D01*
G01X894598Y122990D02*
X896524Y121064D01*
G01X893890Y122990D02*
X894598D01*
G01X892335Y121435D02*
X893890Y122990D01*
G01X892335Y120727D02*
Y121435D01*
G01X894260Y118802D02*
X892335Y120727D01*
G01X894260Y117671D02*
Y118802D01*
G01X892174Y115585D02*
X894260Y117671D01*
G01X892174Y111474D02*
Y115585D01*
G01X891074Y110374D02*
X892174Y111474D01*
G01X891074Y106174D02*
Y110374D01*
G01X892421Y104827D02*
X891074Y106174D01*
G01X876758Y216954D02*
X874603Y219109D01*
G01X876758Y216092D02*
Y216954D01*
G01X875894Y215228D02*
X876758Y216092D01*
G01X875032Y215228D02*
X875894D01*
G01X872877Y217383D02*
X875032Y215228D01*
G01X872015Y217383D02*
X872877D01*
G01X871151Y216519D02*
X872015Y217383D01*
G01X871151Y215657D02*
Y216519D01*
G01X873306Y213502D02*
X871151Y215657D01*
G01X873306Y212640D02*
Y213502D01*
G01X872442Y211776D02*
X873306Y212640D01*
G01X871580Y211776D02*
X872442D01*
G01X869425Y213931D02*
X871580Y211776D01*
G01X868563Y213931D02*
X869425D01*
G01X867699Y213067D02*
X868563Y213931D01*
G01X867699Y212205D02*
Y213067D01*
G01X869854Y210050D02*
X867699Y212205D01*
G01X869854Y209188D02*
Y210050D01*
G01X868990Y208324D02*
X869854Y209188D01*
G01X868128Y208324D02*
X868990D01*
G01X865973Y210479D02*
X868128Y208324D01*
G01X865111Y210479D02*
X865973D01*
G01X864247Y209615D02*
X865111Y210479D01*
G01X864247Y208753D02*
Y209615D01*
G01X866402Y206598D02*
X864247Y208753D01*
G01X866402Y205736D02*
Y206598D01*
G01X907333Y214833D02*
X912436D01*
G01X902000Y209500D02*
X907333Y214833D01*
G01X902000Y208400D02*
Y209500D01*
G01X869203Y175603D02*
X902000Y208400D01*
G01X869203Y170587D02*
Y175603D01*
G01X908200Y205597D02*
X912436Y209833D01*
G01X908200Y202665D02*
Y205597D01*
G01X890532Y184997D02*
X908200Y202665D01*
G01X890532Y184135D02*
Y184997D01*
G01X892018Y182649D02*
X890532Y184135D01*
G01X892018Y181787D02*
Y182649D01*
G01X891154Y180923D02*
X892018Y181787D01*
G01X890292Y180923D02*
X891154D01*
G01X888806Y182409D02*
X890292Y180923D01*
G01X887944Y182409D02*
X888806D01*
G01X887080Y181545D02*
X887944Y182409D01*
G01X887080Y180683D02*
Y181545D01*
G01X888566Y179197D02*
X887080Y180683D01*
G01X888566Y178335D02*
Y179197D01*
G01X887702Y177471D02*
X888566Y178335D01*
G01X886840Y177471D02*
X887702D01*
G01X885354Y178957D02*
X886840Y177471D01*
G01X884492Y178957D02*
X885354D01*
G01X883628Y178093D02*
X884492Y178957D01*
G01X883628Y177231D02*
Y178093D01*
G01X885114Y175745D02*
X883628Y177231D01*
G01X885114Y174883D02*
Y175745D01*
G01X884250Y174019D02*
X885114Y174883D01*
G01X883388Y174019D02*
X884250D01*
G01X881902Y175505D02*
X883388Y174019D01*
G01X881040Y175505D02*
X881902D01*
G01X880176Y174641D02*
X881040Y175505D01*
G01X880176Y173779D02*
Y174641D01*
G01X881662Y172293D02*
X880176Y173779D01*
G01X881662Y171431D02*
Y172293D01*
G01X880798Y170567D02*
X881662Y171431D01*
G01X879936Y170567D02*
X880798D01*
G01X878450Y172053D02*
X879936Y170567D01*
G01X877588Y172053D02*
X878450D01*
G01X876724Y171189D02*
X877588Y172053D01*
G01X876724Y170327D02*
Y171189D01*
G01X878210Y168841D02*
X876724Y170327D01*
G01X878210Y167979D02*
Y168841D01*
G01X877346Y167115D02*
X878210Y167979D01*
G01X876484Y167115D02*
X877346D01*
G01X874998Y168601D02*
X876484Y167115D01*
G01X874136Y168601D02*
X874998D01*
G01X873272Y167737D02*
X874136Y168601D01*
G01X873272Y166875D02*
Y167737D01*
G01X874758Y165389D02*
X873272Y166875D01*
G01X874758Y164527D02*
Y165389D01*
G01X873894Y163663D02*
X874758Y164527D01*
G01X873032Y163663D02*
X873894D01*
G01X871546Y165149D02*
X873032Y163663D01*
G01X870684Y165149D02*
X871546D01*
G01X869820Y164285D02*
X870684Y165149D01*
G01X869820Y163423D02*
Y164285D01*
G01X871391Y161852D02*
X869820Y163423D01*
G01X871391Y160991D02*
Y161852D01*
G01X870527Y160127D02*
X871391Y160991D01*
G01X869664Y160127D02*
X870527D01*
G01X868094Y161697D02*
X869664Y160127D01*
G01X867232Y161697D02*
X868094D01*
G01X864960Y159425D02*
X867232Y161697D01*
G01X864961Y158635D02*
X864960Y159425D01*
G01X866001Y157595D02*
X864961Y158635D01*
G01X866001Y156803D02*
Y157595D01*
G01X862358Y156823D02*
X863150D01*
G01X850454Y174829D02*
X904667Y229042D01*
G01X850454Y170949D02*
Y174829D01*
G01X905328Y187064D02*
X918095Y199831D01*
G01X905328Y186272D02*
Y187064D01*
G01X906736Y184864D02*
X905328Y186272D01*
G01X906736Y184068D02*
Y184864D01*
G01X905156Y182488D02*
X906736Y184068D01*
G01X904294Y182488D02*
X905156D01*
G01X902372Y184410D02*
X904294Y182488D01*
G01X901510Y184410D02*
X902372D01*
G01X900520Y183420D02*
X901510Y184410D01*
G01X900520Y182558D02*
Y183420D01*
G01X902442Y180636D02*
X900520Y182558D01*
G01X902442Y179774D02*
Y180636D01*
G01X897637Y183737D02*
X918556Y204656D01*
G01X897637Y178627D02*
Y183737D01*
G01X895214Y185214D02*
X916688Y206688D01*
G01X895214Y180318D02*
Y185214D01*
G01X907167Y217333D02*
X912436D01*
G01X864028Y174194D02*
X907167Y217333D01*
G01X864028Y169342D02*
Y174194D01*
G01X861104Y209800D02*
X882376Y231072D01*
G01X861104Y203821D02*
Y209800D01*
G01X859411Y202128D02*
X861104Y203821D01*
G01X858549Y202128D02*
X859411D01*
G01X856576Y204101D02*
X858549Y202128D01*
G01X855714Y204101D02*
X856576D01*
G01X854850Y203237D02*
X855714Y204101D01*
G01X854850Y202375D02*
Y203237D01*
G01X856823Y200402D02*
X854850Y202375D01*
G01X856823Y199540D02*
Y200402D01*
G01X855959Y198676D02*
X856823Y199540D01*
G01X855097Y198676D02*
X855959D01*
G01X853124Y200649D02*
X855097Y198676D01*
G01X852262Y200649D02*
X853124D01*
G01X851398Y199785D02*
X852262Y200649D01*
G01X851398Y198923D02*
Y199785D01*
G01X853371Y196950D02*
X851398Y198923D01*
G01X853371Y196088D02*
Y196950D01*
G01X852507Y195224D02*
X853371Y196088D01*
G01X851645Y195224D02*
X852507D01*
G01X849672Y197197D02*
X851645Y195224D01*
G01X848810Y197197D02*
X849672D01*
G01X849919Y192636D02*
Y193498D01*
G01X849055Y191772D02*
X849919Y192636D01*
G01X909205Y187405D02*
X919131Y197331D01*
G01X909205Y183061D02*
Y187405D01*
G01X904267Y205011D02*
X911589Y212333D01*
G01X904267Y201809D02*
Y205011D01*
G01X902437Y199979D02*
X904267Y201809D01*
G01X901575Y199979D02*
X902437D01*
G01X900014Y201540D02*
X901575Y199979D01*
G01X899152Y201540D02*
X900014D01*
G01X898288Y200676D02*
X899152Y201540D01*
G01X898288Y199814D02*
Y200676D01*
G01X899849Y198253D02*
X898288Y199814D01*
G01X899849Y197391D02*
Y198253D01*
G01X898985Y196527D02*
X899849Y197391D01*
G01X898123Y196527D02*
X898985D01*
G01X896562Y198088D02*
X898123Y196527D01*
G01X895700Y198088D02*
X896562D01*
G01X894836Y197224D02*
X895700Y198088D01*
G01X894836Y196362D02*
Y197224D01*
G01X896397Y194801D02*
X894836Y196362D01*
G01X896397Y193939D02*
Y194801D01*
G01X895533Y193075D02*
X896397Y193939D01*
G01X894671Y193075D02*
X895533D01*
G01X893110Y194636D02*
X894671Y193075D01*
G01X892248Y194636D02*
X893110D01*
G01X891384Y193772D02*
X892248Y194636D01*
G01X891384Y192910D02*
Y193772D01*
G01X892945Y191349D02*
X891384Y192910D01*
G01X892945Y190487D02*
Y191349D01*
G01X892081Y189623D02*
X892945Y190487D01*
G01X891219Y189623D02*
X892081D01*
G01X889658Y191184D02*
X891219Y189623D01*
G01X888796Y191184D02*
X889658D01*
G01X887932Y190320D02*
X888796Y191184D01*
G01X887932Y189458D02*
Y190320D01*
G01X889493Y187897D02*
X887932Y189458D01*
G01X889493Y187035D02*
Y187897D01*
G01X888629Y186171D02*
X889493Y187035D01*
G01X887767Y186171D02*
X888629D01*
G01X886206Y187732D02*
X887767Y186171D01*
G01X885344Y187732D02*
X886206D01*
G01X884480Y186868D02*
X885344Y187732D01*
G01X884480Y186006D02*
Y186868D01*
G01X886041Y184445D02*
X884480Y186006D01*
G01X886041Y183583D02*
Y184445D01*
G01X883873Y181415D02*
X886041Y183583D01*
G01X883011Y181415D02*
X883873D01*
G01X881496Y182930D02*
X883011Y181415D01*
G01X880634Y182930D02*
X881496D01*
G01X879770Y182066D02*
X880634Y182930D01*
G01X879770Y181204D02*
Y182066D01*
G01X881285Y179689D02*
X879770Y181204D01*
G01X881285Y178827D02*
Y179689D01*
G01X880421Y177963D02*
X881285Y178827D01*
G01X879559Y177963D02*
X880421D01*
G01X878044Y179478D02*
X879559Y177963D01*
G01X877182Y179478D02*
X878044D01*
G01X876318Y178614D02*
X877182Y179478D01*
G01X876318Y177752D02*
Y178614D01*
G01X877833Y176237D02*
X876318Y177752D01*
G01X877833Y175375D02*
Y176237D01*
G01X876969Y174511D02*
X877833Y175375D01*
G01X876107Y174511D02*
X876969D01*
G01X874592Y176026D02*
X876107Y174511D01*
G01X873730Y176026D02*
X874592D01*
G01X872866Y175162D02*
X873730Y176026D01*
G01X872866Y174300D02*
Y175162D01*
G01X874381Y172785D02*
X872866Y174300D01*
G01X874381Y171923D02*
Y172785D01*
G01X909023Y162761D02*
X913261D01*
G01X907325Y161063D02*
X909023Y162761D01*
G01X907325Y160201D02*
Y161063D01*
G01X908832Y158694D02*
X907325Y160201D01*
G01X908832Y157832D02*
Y158694D01*
G01X907968Y156968D02*
X908832Y157832D01*
G01X907106Y156968D02*
X907968D01*
G01X905599Y158475D02*
X907106Y156968D01*
G01X904737Y158475D02*
X905599D01*
G01X903873Y157611D02*
X904737Y158475D01*
G01X903873Y156749D02*
Y157611D01*
G01X887973Y261630D02*
X909977D01*
G01X903631Y231542D02*
X906736D01*
G01X894611Y248485D02*
X908114D01*
G01X882776Y236650D02*
X894611Y248485D01*
G01X880882Y236650D02*
X882776D01*
G01X901646Y240980D02*
X908695D01*
G01X886250Y225584D02*
X901646Y240980D01*
G01X885388Y225584D02*
X886250D01*
G01X883233Y227739D02*
X885388Y225584D01*
G01X882371Y227739D02*
X883233D01*
G01X881507Y226875D02*
X882371Y227739D01*
G01X881507Y226013D02*
Y226875D01*
G01X883662Y223858D02*
X881507Y226013D01*
G01X883662Y222996D02*
Y223858D01*
G01X882798Y222132D02*
X883662Y222996D01*
G01X881936Y222132D02*
X882798D01*
G01X879781Y224287D02*
X881936Y222132D01*
G01X878919Y224287D02*
X879781D01*
G01X878055Y223423D02*
X878919Y224287D01*
G01X878055Y222561D02*
Y223423D01*
G01X880210Y220406D02*
X878055Y222561D01*
G01X880210Y219544D02*
Y220406D01*
G01X879346Y218680D02*
X880210Y219544D01*
G01X878484Y218680D02*
X879346D01*
G01X876329Y220835D02*
X878484Y218680D01*
G01X875467Y220835D02*
X876329D01*
G01X874603Y219971D02*
X875467Y220835D01*
G01X874603Y219109D02*
Y219971D01*
G01X902995Y234442D02*
X907056D01*
G01X904667Y229042D02*
X906736D01*
G01X901959Y236942D02*
X906858D01*
G01X889009Y259130D02*
X909694D01*
G01X887429Y266630D02*
X908929D01*
G01X887737Y264130D02*
X909976D01*
G01X896312Y245980D02*
X907380D01*
G01X883872Y233540D02*
X896312Y245980D01*
G01X881308Y233540D02*
X883872D01*
G01X898296Y243480D02*
X908617D01*
G01X885888Y231072D02*
X898296Y243480D01*
G01X882376Y231072D02*
X885888D01*
G01X895270Y340500D02*
X851185Y384585D01*
G01X906364Y340500D02*
X895270D01*
G01X894504Y338600D02*
X849300Y383804D01*
G01X906006Y338600D02*
X894504D01*
G01X906800Y398130D02*
Y406745D01*
G01X909107Y395823D02*
X906800Y398130D01*
G01X901600Y402399D02*
X870465Y433534D01*
G01X901600Y393974D02*
Y402399D01*
G01X905285Y390289D02*
X901600Y393974D01*
G01X904000Y396500D02*
Y403571D01*
G01X907200Y393300D02*
X904000Y396500D01*
G01X909099Y393300D02*
X907200D01*
G01X909107Y393292D02*
X909099Y393300D01*
G01X863900Y388600D02*
Y394464D01*
G01X896764Y355736D02*
X863900Y388600D01*
G01X899065Y355736D02*
X896764D01*
G01X853070Y385367D02*
Y387931D01*
G01X896009Y342428D02*
X853070Y385367D01*
G01X902496Y342428D02*
X896009D01*
G01X899200Y401199D02*
X853766Y446633D01*
G01X899200Y391800D02*
Y401199D01*
G01X903211Y387789D02*
X899200Y391800D01*
G01X905605Y387789D02*
X903211D01*
G01X869700Y396562D02*
X849562Y416700D01*
G01X869700Y388600D02*
Y396562D01*
G01X897400Y360900D02*
X869700Y388600D01*
G01X899185Y360900D02*
X897400D01*
G01X899229Y360856D02*
X899185Y360900D01*
G01X884100Y384902D02*
Y394892D01*
G01X898902Y370100D02*
X884100Y384902D01*
G01X902997Y370100D02*
X898902D01*
G01X903166Y369931D02*
X902997Y370100D01*
G01X851185Y384585D02*
Y387016D01*
G01X882200Y384136D02*
Y393256D01*
G01X898936Y367400D02*
X882200Y384136D01*
G01X904029Y367400D02*
X898936D01*
G01X904056Y367427D02*
X904029Y367400D01*
G01X854955Y386148D02*
Y389014D01*
G01X896175Y344928D02*
X854955Y386148D01*
G01X902597Y344928D02*
X896175D01*
G01X866800Y388500D02*
Y395100D01*
G01X896700Y358600D02*
X866800Y388500D01*
G01X898680Y358600D02*
X896700D01*
G01X899044Y358236D02*
X898680Y358600D01*
G01X888700Y385634D02*
Y397364D01*
G01X899134Y375200D02*
X888700Y385634D01*
G01X902824Y375200D02*
X899134D01*
G01X902856Y375168D02*
X902824Y375200D01*
G01X872300Y389100D02*
Y397499D01*
G01X898027Y363373D02*
X872300Y389100D01*
G01X898813Y363373D02*
X898027D01*
G01X849300Y383804D02*
Y386201D01*
G01X902757Y372700D02*
X902856Y372601D01*
G01X898968Y372700D02*
X902757D01*
G01X886400Y385268D02*
X898968Y372700D01*
G01X886400Y396128D02*
Y385268D01*
G01X906800Y413359D02*
X850900Y469259D01*
G01X906800Y410631D02*
Y413359D01*
G01X906162Y409993D02*
X906800Y410631D01*
G01X903494Y409993D02*
X906162D01*
G01X902856Y409355D02*
X903494Y409993D01*
G01X902856Y407965D02*
Y409355D01*
G01X903438Y407383D02*
X902856Y407965D01*
G01X906162Y407383D02*
X903438D01*
G01X906800Y406745D02*
X906162Y407383D01*
G01X887709Y424310D02*
Y425342D01*
G01X886578Y423179D02*
X887709Y424310D01*
G01X885346Y423179D02*
X886578D01*
G01X872728Y435797D02*
X885346Y423179D01*
G01X871596Y435797D02*
X872728D01*
G01X870465Y434666D02*
X871596Y435797D01*
G01X870465Y433534D02*
Y434666D01*
G01X915465Y420959D02*
X864118Y472306D01*
G01X918177Y436023D02*
X873700Y480500D01*
G01X903146Y412345D02*
Y413477D01*
G01X902015Y411214D02*
X903146Y412345D01*
G01X900883Y411214D02*
X902015D01*
G01X889715Y422382D02*
X900883Y411214D01*
G01X888583Y422382D02*
X889715D01*
G01X887452Y421251D02*
X888583Y422382D01*
G01X887452Y420119D02*
Y421251D01*
G01X904000Y403571D02*
X887452Y420119D01*
G01X870160Y438159D02*
Y439291D01*
G01X869029Y437028D02*
X870160Y438159D01*
G01X867897Y437028D02*
X869029D01*
G01X856029Y448896D02*
X867897Y437028D01*
G01X854897Y448896D02*
X856029D01*
G01X853766Y447765D02*
X854897Y448896D01*
G01X853766Y446633D02*
Y447765D01*
G01X912705Y445295D02*
X876300Y481700D01*
G01X907500Y457900D02*
X881100Y484300D01*
G01X913500Y457900D02*
X907500D01*
G01X909810Y416006D02*
X854900Y470916D01*
G01X909810Y405590D02*
Y416006D01*
G01X915307Y400093D02*
X909810Y405590D01*
G01X913580Y419308D02*
X860200Y472688D01*
G01X911695Y417657D02*
X857500Y471852D01*
G01X909289Y461835D02*
X885774Y485350D01*
G01X920665Y461835D02*
X909289D01*
G01X908343Y453259D02*
X878811Y482791D01*
G01X909475Y453259D02*
X908343D01*
G01X911392Y455176D02*
X909475Y453259D01*
G01X850100Y490900D02*
X848500D01*
G01X850900Y490100D02*
X850100Y490900D01*
G01X850900Y469259D02*
Y490100D01*
G01X859287Y526031D02*
Y527413D01*
G01X858057Y524801D02*
X859287Y526031D01*
G01X858057Y522959D02*
Y524801D01*
G01X859600Y521416D02*
X858057Y522959D01*
G01X859600Y520100D02*
Y521416D01*
G01X858057Y518557D02*
X859600Y520100D01*
G01X858057Y508763D02*
Y518557D01*
G01X858900Y507920D02*
X858057Y508763D01*
G01X858900Y499100D02*
Y507920D01*
G01X864118Y493882D02*
X858900Y499100D01*
G01X864118Y491945D02*
Y493882D01*
G01X863508Y491335D02*
X864118Y491945D01*
G01X862697Y491335D02*
X863508D01*
G01X862087Y490725D02*
X862697Y491335D01*
G01X862087Y488745D02*
Y490725D01*
G01X862697Y488135D02*
X862087Y488745D01*
G01X863704Y488135D02*
X862697D01*
G01X864314Y487525D02*
X863704Y488135D01*
G01X864314Y485545D02*
Y487525D01*
G01X863704Y484935D02*
X864314Y485545D01*
G01X862697Y484935D02*
X863704D01*
G01X862087Y484325D02*
X862697Y484935D01*
G01X862087Y482345D02*
Y484325D01*
G01X862697Y481735D02*
X862087Y482345D01*
G01X863508Y481735D02*
X862697D01*
G01X864118Y481125D02*
X863508Y481735D01*
G01X864118Y479145D02*
Y481125D01*
G01X863508Y478535D02*
X864118Y479145D01*
G01X862697Y478535D02*
X863508D01*
G01X862087Y477925D02*
X862697Y478535D01*
G01X862087Y475945D02*
Y477925D01*
G01X862697Y475335D02*
X862087Y475945D01*
G01X863508Y475335D02*
X862697D01*
G01X864118Y474725D02*
X863508Y475335D01*
G01X864118Y472306D02*
Y474725D01*
G01X872110Y517357D02*
Y529842D01*
G01X871300Y516547D02*
X872110Y517357D01*
G01X871300Y512467D02*
Y516547D01*
G01X872555Y511212D02*
X871300Y512467D01*
G01X872555Y509555D02*
Y511212D01*
G01X871134Y508134D02*
X872555Y509555D01*
G01X871134Y501866D02*
Y508134D01*
G01X873700Y499300D02*
X871134Y501866D01*
G01X873700Y480500D02*
Y499300D01*
G01X876261Y525895D02*
Y527131D01*
G01X875651Y525285D02*
X876261Y525895D01*
G01X874961Y525285D02*
X875651D01*
G01X874351Y524675D02*
X874961Y525285D01*
G01X874351Y522695D02*
Y524675D01*
G01X874961Y522085D02*
X874351Y522695D01*
G01X875651Y522085D02*
X874961D01*
G01X876261Y521475D02*
X875651Y522085D01*
G01X876261Y520189D02*
Y521475D01*
G01X874500Y518428D02*
X876261Y520189D01*
G01X874500Y517499D02*
Y518428D01*
G01X875800Y516199D02*
X874500Y517499D01*
G01X875800Y512047D02*
Y516199D01*
G01X874800Y511047D02*
X875800Y512047D01*
G01X874800Y509300D02*
Y511047D01*
G01X876300Y507800D02*
X874800Y509300D01*
G01X876300Y506526D02*
Y507800D01*
G01X875690Y505916D02*
X876300Y506526D01*
G01X874017Y505916D02*
X875690D01*
G01X873407Y505306D02*
X874017Y505916D01*
G01X873407Y503326D02*
Y505306D01*
G01X874017Y502716D02*
X873407Y503326D01*
G01X875690Y502716D02*
X874017D01*
G01X876300Y502106D02*
X875690Y502716D01*
G01X876300Y481700D02*
Y502106D01*
G01X882000Y519440D02*
Y527700D01*
G01X881760Y519200D02*
X882000Y519440D01*
G01X881760Y517357D02*
Y519200D01*
G01X882310Y516807D02*
X881760Y517357D01*
G01X882310Y512257D02*
Y516807D01*
G01X881710Y511657D02*
X882310Y512257D01*
G01X881710Y509190D02*
Y511657D01*
G01X882100Y508800D02*
X881710Y509190D01*
G01X882100Y501100D02*
Y508800D01*
G01X881100Y500100D02*
X882100Y501100D01*
G01X881100Y484300D02*
Y500100D01*
G01X888700Y519999D02*
Y527800D01*
G01X887966Y519265D02*
X888700Y519999D01*
G01X887966Y517234D02*
Y519265D01*
G01X888571Y516629D02*
X887966Y517234D01*
G01X888571Y511747D02*
Y516629D01*
G01X888000Y511176D02*
X888571Y511747D01*
G01X888000Y509600D02*
Y511176D01*
G01X889100Y508500D02*
X888000Y509600D01*
G01X889100Y504299D02*
Y508500D01*
G01X887100Y502299D02*
X889100Y504299D01*
G01X887100Y495300D02*
Y502299D01*
G01X888200Y494200D02*
X887100Y495300D01*
G01X888200Y485596D02*
Y494200D01*
G01X889568Y484228D02*
X888200Y485596D01*
G01X890430Y484228D02*
X889568D01*
G01X890766Y484564D02*
X890430Y484228D01*
G01X891628Y484564D02*
X890766D01*
G01X893029Y483163D02*
X891628Y484564D01*
G01X893029Y482301D02*
Y483163D01*
G01X892693Y481965D02*
X893029Y482301D01*
G01X892693Y481103D02*
Y481965D01*
G01X894094Y479702D02*
X892693Y481103D01*
G01X894956Y479702D02*
X894094D01*
G01X895292Y480038D02*
X894956Y479702D01*
G01X896154Y480038D02*
X895292D01*
G01X897555Y478637D02*
X896154Y480038D01*
G01X897555Y477775D02*
Y478637D01*
G01X897219Y477439D02*
X897555Y477775D01*
G01X897219Y476577D02*
Y477439D01*
G01X898620Y475176D02*
X897219Y476577D01*
G01X899482Y475176D02*
X898620D01*
G01X899818Y475512D02*
X899482Y475176D01*
G01X900680Y475512D02*
X899818D01*
G01X902081Y474111D02*
X900680Y475512D01*
G01X902081Y473249D02*
Y474111D01*
G01X901745Y472913D02*
X902081Y473249D01*
G01X901745Y472051D02*
Y472913D01*
G01X903146Y470650D02*
X901745Y472051D01*
G01X904008Y470650D02*
X903146D01*
G01X904344Y470986D02*
X904008Y470650D01*
G01X905206Y470986D02*
X904344D01*
G01X906607Y469585D02*
X905206Y470986D01*
G01X906607Y468723D02*
Y469585D01*
G01X906271Y468387D02*
X906607Y468723D01*
G01X906271Y467525D02*
Y468387D01*
G01X907672Y466124D02*
X906271Y467525D01*
G01X908534Y466124D02*
X907672D01*
G01X908870Y466460D02*
X908534Y466124D01*
G01X909732Y466460D02*
X908870D01*
G01X912313Y463879D02*
X909732Y466460D01*
G01X895400Y518979D02*
Y528400D01*
G01X894921Y518500D02*
X895400Y518979D01*
G01X894921Y487679D02*
Y518500D01*
G01X912100Y470500D02*
X894921Y487679D01*
G01X848500Y519510D02*
Y527800D01*
G01X848576Y519434D02*
X848500Y519510D01*
G01X848576Y517123D02*
Y519434D01*
G01X848900Y501500D02*
Y510807D01*
G01X851200Y499200D02*
X848900Y501500D01*
G01X851200Y495500D02*
Y499200D01*
G01X854900Y491800D02*
X851200Y495500D01*
G01X854900Y470916D02*
Y491800D01*
G01X855200Y519910D02*
Y527800D01*
G01X855610Y519500D02*
X855200Y519910D01*
G01X855610Y517657D02*
Y519500D01*
G01X854260Y516307D02*
X855610Y517657D01*
G01X854260Y512057D02*
Y516307D01*
G01X855610Y510707D02*
X854260Y512057D01*
G01X855610Y506990D02*
Y510707D01*
G01X856300Y506300D02*
X855610Y506990D01*
G01X856300Y498000D02*
Y506300D01*
G01X860200Y494100D02*
X856300Y498000D01*
G01X860200Y472688D02*
Y494100D01*
G01X852443Y521309D02*
Y526813D01*
G01X851242Y520108D02*
X852443Y521309D01*
G01X851242Y517725D02*
Y520108D01*
G01X852164Y516803D02*
X851242Y517725D01*
G01X852164Y512151D02*
Y516803D01*
G01X851410Y511397D02*
X852164Y512151D01*
G01X851410Y509500D02*
Y511397D01*
G01X852600Y508310D02*
X851410Y509500D01*
G01X852600Y502600D02*
Y508310D01*
G01X853800Y501400D02*
X852600Y502600D01*
G01X853800Y496700D02*
Y501400D01*
G01X857500Y493000D02*
X853800Y496700D01*
G01X857500Y471852D02*
Y493000D01*
G01X885300Y519621D02*
Y527900D01*
G01X885621Y519300D02*
X885300Y519621D01*
G01X885621Y517357D02*
Y519300D01*
G01X884721Y516457D02*
X885621Y517357D01*
G01X884721Y511797D02*
Y516457D01*
G01X885800Y510718D02*
X884721Y511797D01*
G01X885800Y509400D02*
Y510718D01*
G01X885000Y508600D02*
X885800Y509400D01*
G01X885000Y502400D02*
Y508600D01*
G01X884774Y502174D02*
X885000Y502400D01*
G01X884774Y489426D02*
Y502174D01*
G01X885774Y488426D02*
X884774Y489426D01*
G01X885774Y485350D02*
Y488426D01*
G01X908800Y519421D02*
Y527600D01*
G01X908921Y519300D02*
X908800Y519421D01*
G01X908921Y517357D02*
Y519300D01*
G01X908521Y516957D02*
X908921Y517357D01*
G01X908521Y512057D02*
Y516957D01*
G01X909321Y511257D02*
X908521Y512057D01*
G01X909321Y495221D02*
Y511257D01*
G01X908700Y494600D02*
X909321Y495221D01*
G01X908700Y488900D02*
Y494600D01*
G01X916600Y481000D02*
X908700Y488900D01*
G01X878800Y526500D02*
X879600Y527300D01*
G01X878800Y517007D02*
Y526500D01*
G01X878100Y516307D02*
X878800Y517007D01*
G01X878100Y511967D02*
Y516307D01*
G01X878811Y511256D02*
X878100Y511967D01*
G01X878811Y482791D02*
Y511256D01*
G01X892239Y517539D02*
Y529449D01*
G01X891071Y516371D02*
X892239Y517539D01*
G01X891071Y512129D02*
Y516371D01*
G01X892113Y511087D02*
X891071Y512129D01*
G01X892113Y509113D02*
Y511087D01*
G01X890900Y507900D02*
X892113Y509113D01*
G01X890900Y490201D02*
Y507900D01*
G01X892421Y488680D02*
X890900Y490201D01*
G01X892421Y486580D02*
Y488680D01*
G01X913040Y465961D02*
X892421Y486580D01*
G01X858110Y586443D02*
X856189Y588364D01*
G01X858110Y584190D02*
Y586443D01*
G01X858600Y583700D02*
X858110Y584190D01*
G01X858600Y581700D02*
Y583700D01*
G01X857600Y580700D02*
X858600Y581700D01*
G01X857600Y579200D02*
Y580700D01*
G01X858600Y578200D02*
X857600Y579200D01*
G01X858600Y576100D02*
Y578200D01*
G01X858110Y575610D02*
X858600Y576100D01*
G01X858110Y566390D02*
Y575610D01*
G01X858600Y565900D02*
X858110Y566390D01*
G01X858600Y564400D02*
Y565900D01*
G01X857600Y563400D02*
X858600Y564400D01*
G01X857600Y560900D02*
Y563400D01*
G01X858600Y559900D02*
X857600Y560900D01*
G01X858600Y557100D02*
Y559900D01*
G01X858110Y556610D02*
X858600Y557100D01*
G01X858110Y546690D02*
Y556610D01*
G01X859063Y545737D02*
X858110Y546690D01*
G01X859063Y543800D02*
Y545737D01*
G01X858000Y542737D02*
X859063Y543800D01*
G01X858000Y541463D02*
Y542737D01*
G01X859063Y540400D02*
X858000Y541463D01*
G01X859063Y538663D02*
Y540400D01*
G01X858110Y537710D02*
X859063Y538663D01*
G01X858110Y528590D02*
Y537710D01*
G01X859287Y527413D02*
X858110Y528590D01*
G01X872510Y586357D02*
X869610Y589257D01*
G01X872510Y585010D02*
Y586357D01*
G01X871500Y584000D02*
X872510Y585010D01*
G01X871500Y576300D02*
Y584000D01*
G01X872468Y575332D02*
X871500Y576300D01*
G01X872468Y574200D02*
Y575332D01*
G01X871237Y572969D02*
X872468Y574200D01*
G01X871237Y568470D02*
Y572969D01*
G01X872600Y567107D02*
X871237Y568470D01*
G01X872600Y564800D02*
Y567107D01*
G01X872000Y564200D02*
X872600Y564800D01*
G01X872000Y557210D02*
Y564200D01*
G01X872500Y556710D02*
X872000Y557210D01*
G01X872500Y555399D02*
Y556710D01*
G01X871200Y554099D02*
X872500Y555399D01*
G01X871200Y550367D02*
Y554099D01*
G01X872510Y549057D02*
X871200Y550367D01*
G01X872510Y547310D02*
Y549057D01*
G01X871700Y546500D02*
X872510Y547310D01*
G01X871700Y539000D02*
Y546500D01*
G01X872700Y538000D02*
X871700Y539000D01*
G01X872700Y536700D02*
Y538000D01*
G01X871710Y535710D02*
X872700Y536700D01*
G01X871710Y530242D02*
Y535710D01*
G01X872110Y529842D02*
X871710Y530242D01*
G01X874600Y587735D02*
X873621Y588714D01*
G01X874600Y585500D02*
Y587735D01*
G01X875300Y584800D02*
X874600Y585500D01*
G01X875300Y582100D02*
Y584800D01*
G01X874100Y580900D02*
X875300Y582100D01*
G01X874100Y579400D02*
Y580900D01*
G01X875300Y578200D02*
X874100Y579400D01*
G01X875300Y576600D02*
Y578200D01*
G01X874567Y575867D02*
X875300Y576600D01*
G01X874567Y574434D02*
Y575867D01*
G01X876000Y573001D02*
X874567Y574434D01*
G01X876000Y568499D02*
Y573001D01*
G01X874717Y567216D02*
X876000Y568499D01*
G01X874717Y566083D02*
Y567216D01*
G01X875300Y565500D02*
X874717Y566083D01*
G01X875300Y563000D02*
Y565500D01*
G01X874100Y561800D02*
X875300Y563000D01*
G01X874100Y560600D02*
Y561800D01*
G01X875300Y559400D02*
X874100Y560600D01*
G01X875300Y557690D02*
Y559400D01*
G01X874500Y556890D02*
X875300Y557690D01*
G01X874500Y555399D02*
Y556890D01*
G01X876000Y553899D02*
X874500Y555399D01*
G01X876000Y550047D02*
Y553899D01*
G01X874800Y548847D02*
X876000Y550047D01*
G01X874800Y546600D02*
Y548847D01*
G01X875400Y546000D02*
X874800Y546600D01*
G01X875400Y544200D02*
Y546000D01*
G01X874404Y543204D02*
X875400Y544200D01*
G01X874404Y541596D02*
Y543204D01*
G01X875400Y540600D02*
X874404Y541596D01*
G01X875400Y539300D02*
Y540600D01*
G01X874700Y538600D02*
X875400Y539300D01*
G01X874700Y536600D02*
Y538600D01*
G01X875810Y535490D02*
X874700Y536600D01*
G01X875810Y530542D02*
Y535490D01*
G01X874700Y529432D02*
X875810Y530542D01*
G01X874700Y528692D02*
Y529432D01*
G01X876261Y527131D02*
X874700Y528692D01*
G01X881610Y587470D02*
X880314Y588766D01*
G01X881610Y584790D02*
Y587470D01*
G01X882000Y584400D02*
X881610Y584790D01*
G01X882000Y575790D02*
Y584400D01*
G01X881610Y575400D02*
X882000Y575790D01*
G01X881610Y574190D02*
Y575400D01*
G01X882610Y573190D02*
X881610Y574190D01*
G01X882610Y568497D02*
Y573190D01*
G01X881760Y567647D02*
X882610Y568497D01*
G01X881760Y565740D02*
Y567647D01*
G01X882000Y565500D02*
X881760Y565740D01*
G01X882000Y557140D02*
Y565500D01*
G01X881760Y556900D02*
X882000Y557140D01*
G01X881760Y555157D02*
Y556900D01*
G01X882310Y554607D02*
X881760Y555157D01*
G01X882310Y550057D02*
Y554607D01*
G01X881710Y549457D02*
X882310Y550057D01*
G01X881710Y546590D02*
Y549457D01*
G01X882000Y546300D02*
X881710Y546590D01*
G01X882000Y544400D02*
Y546300D01*
G01X881200Y543600D02*
X882000Y544400D01*
G01X881200Y541300D02*
Y543600D01*
G01X882000Y540500D02*
X881200Y541300D01*
G01X882000Y537790D02*
Y540500D01*
G01X881710Y537500D02*
X882000Y537790D01*
G01X881710Y536190D02*
Y537500D01*
G01X882410Y535490D02*
X881710Y536190D01*
G01X882410Y530466D02*
Y535490D01*
G01X881760Y529816D02*
X882410Y530466D01*
G01X881760Y527940D02*
Y529816D01*
G01X882000Y527700D02*
X881760Y527940D01*
G01X888221Y587200D02*
X886707Y588714D01*
G01X888221Y584379D02*
Y587200D01*
G01X888700Y583900D02*
X888221Y584379D01*
G01X888700Y576199D02*
Y583900D01*
G01X887900Y575399D02*
X888700Y576199D01*
G01X887900Y574001D02*
Y575399D01*
G01X888821Y573080D02*
X887900Y574001D01*
G01X888821Y568421D02*
Y573080D01*
G01X887600Y567200D02*
X888821Y568421D01*
G01X887600Y565300D02*
Y567200D01*
G01X888700Y564200D02*
X887600Y565300D01*
G01X888700Y557999D02*
Y564200D01*
G01X887900Y557199D02*
X888700Y557999D01*
G01X887900Y555678D02*
Y557199D01*
G01X888571Y555007D02*
X887900Y555678D01*
G01X888571Y549871D02*
Y555007D01*
G01X887700Y549000D02*
X888571Y549871D01*
G01X887700Y547100D02*
Y549000D01*
G01X888700Y546100D02*
X887700Y547100D01*
G01X888700Y537879D02*
Y546100D01*
G01X888000Y537179D02*
X888700Y537879D01*
G01X888000Y535763D02*
Y537179D01*
G01X888571Y535192D02*
X888000Y535763D01*
G01X888571Y530242D02*
Y535192D01*
G01X888321Y529992D02*
X888571Y530242D01*
G01X888321Y528179D02*
Y529992D01*
G01X888700Y527800D02*
X888321Y528179D01*
G01X894921Y586443D02*
X893000Y588364D01*
G01X894921Y584579D02*
Y586443D01*
G01X895400Y584100D02*
X894921Y584579D01*
G01X895400Y576099D02*
Y584100D01*
G01X894921Y575620D02*
X895400Y576099D01*
G01X894921Y566079D02*
Y575620D01*
G01X895400Y565600D02*
X894921Y566079D01*
G01X895400Y556979D02*
Y565600D01*
G01X894921Y556500D02*
X895400Y556979D01*
G01X894921Y546779D02*
Y556500D01*
G01X895400Y546300D02*
X894921Y546779D01*
G01X895400Y538179D02*
Y546300D01*
G01X894921Y537700D02*
X895400Y538179D01*
G01X894921Y528879D02*
Y537700D01*
G01X895400Y528400D02*
X894921Y528879D01*
G01X848760Y584660D02*
Y586457D01*
G01X848575Y584475D02*
X848760Y584660D01*
G01X848575Y573757D02*
Y584475D01*
G01X848799Y566099D02*
Y567200D01*
G01X848659Y565959D02*
X848799Y566099D01*
G01X848659Y555006D02*
Y565959D01*
G01X848811Y546511D02*
Y548656D01*
G01X848500Y546200D02*
X848811Y546511D01*
G01X848500Y538010D02*
Y546200D01*
G01X848726Y537784D02*
X848500Y538010D01*
G01X848726Y536058D02*
Y537784D01*
G01X848702Y528002D02*
Y529598D01*
G01X848500Y527800D02*
X848702Y528002D01*
G01X855460Y586457D02*
X852110Y589807D01*
G01X855460Y584560D02*
Y586457D01*
G01X855200Y584300D02*
X855460Y584560D01*
G01X855200Y575860D02*
Y584300D01*
G01X855460Y575600D02*
X855200Y575860D01*
G01X855460Y574259D02*
Y575600D01*
G01X854310Y573109D02*
X855460Y574259D01*
G01X854310Y568367D02*
Y573109D01*
G01X855410Y567267D02*
X854310Y568367D01*
G01X855410Y565910D02*
Y567267D01*
G01X855200Y565700D02*
X855410Y565910D01*
G01X855200Y557610D02*
Y565700D01*
G01X855410Y557400D02*
X855200Y557610D01*
G01X855410Y555257D02*
Y557400D01*
G01X854260Y554107D02*
X855410Y555257D01*
G01X854260Y549857D02*
Y554107D01*
G01X855610Y548507D02*
X854260Y549857D01*
G01X855610Y546510D02*
Y548507D01*
G01X855200Y546100D02*
X855610Y546510D01*
G01X855200Y538900D02*
Y546100D01*
G01X855610Y538490D02*
X855200Y538900D01*
G01X855610Y536610D02*
Y538490D01*
G01X854260Y535260D02*
X855610Y536610D01*
G01X854260Y530617D02*
Y535260D01*
G01X855610Y529267D02*
X854260Y530617D01*
G01X855610Y528210D02*
Y529267D01*
G01X855200Y527800D02*
X855610Y528210D01*
G01X851410Y587790D02*
X850486Y588714D01*
G01X851410Y584790D02*
Y587790D01*
G01X852600Y583600D02*
X851410Y584790D01*
G01X852600Y582500D02*
Y583600D01*
G01X851300Y581200D02*
X852600Y582500D01*
G01X851300Y579900D02*
Y581200D01*
G01X852600Y578600D02*
X851300Y579900D01*
G01X852600Y577000D02*
Y578600D01*
G01X851158Y575558D02*
X852600Y577000D01*
G01X851158Y573998D02*
Y575558D01*
G01X852010Y573146D02*
X851158Y573998D01*
G01X852010Y568497D02*
Y573146D01*
G01X851270Y567757D02*
X852010Y568497D01*
G01X851270Y565674D02*
Y567757D01*
G01X851900Y565044D02*
X851270Y565674D01*
G01X851900Y557390D02*
Y565044D01*
G01X851242Y556732D02*
X851900Y557390D01*
G01X851242Y555197D02*
Y556732D01*
G01X852136Y554303D02*
X851242Y555197D01*
G01X852136Y549183D02*
Y554303D01*
G01X851270Y548317D02*
X852136Y549183D01*
G01X851270Y546430D02*
Y548317D01*
G01X852303Y545397D02*
X851270Y546430D01*
G01X852303Y539245D02*
Y545397D01*
G01X851046Y537988D02*
X852303Y539245D01*
G01X851046Y536144D02*
Y537988D01*
G01X851996Y535194D02*
X851046Y536144D01*
G01X851996Y530478D02*
Y535194D01*
G01X851510Y529992D02*
X851996Y530478D01*
G01X851510Y527746D02*
Y529992D01*
G01X852443Y526813D02*
X851510Y527746D01*
G01X885571Y586457D02*
X882421Y589607D01*
G01X885571Y584171D02*
Y586457D01*
G01X885300Y583900D02*
X885571Y584171D01*
G01X885300Y575999D02*
Y583900D01*
G01X885571Y575728D02*
X885300Y575999D01*
G01X885571Y573942D02*
Y575728D01*
G01X884573Y572944D02*
X885571Y573942D01*
G01X884573Y568227D02*
Y572944D01*
G01X885621Y567179D02*
X884573Y568227D01*
G01X885621Y565721D02*
Y567179D01*
G01X885300Y565400D02*
X885621Y565721D01*
G01X885300Y557901D02*
Y565400D01*
G01X886076Y557125D02*
X885300Y557901D01*
G01X886076Y555576D02*
Y557125D01*
G01X884721Y554221D02*
X886076Y555576D01*
G01X884721Y549557D02*
Y554221D01*
G01X885721Y548557D02*
X884721Y549557D01*
G01X885721Y547021D02*
Y548557D01*
G01X885300Y546600D02*
X885721Y547021D01*
G01X885300Y538221D02*
Y546600D01*
G01X885721Y537800D02*
X885300Y538221D01*
G01X885721Y536242D02*
Y537800D01*
G01X884721Y535242D02*
X885721Y536242D01*
G01X884721Y530378D02*
Y535242D01*
G01X885883Y529216D02*
X884721Y530378D01*
G01X885883Y528483D02*
Y529216D01*
G01X885300Y527900D02*
X885883Y528483D01*
G01X909321Y586379D02*
X906400Y589300D01*
G01X909321Y584921D02*
Y586379D01*
G01X908800Y584400D02*
X909321Y584921D01*
G01X908800Y576021D02*
Y584400D01*
G01X909321Y575500D02*
X908800Y576021D01*
G01X909321Y574242D02*
Y575500D01*
G01X908048Y572969D02*
X909321Y574242D01*
G01X908048Y568470D02*
Y572969D01*
G01X909121Y567397D02*
X908048Y568470D01*
G01X909121Y566121D02*
Y567397D01*
G01X908800Y565800D02*
X909121Y566121D01*
G01X908800Y557721D02*
Y565800D01*
G01X909121Y557400D02*
X908800Y557721D01*
G01X909121Y555357D02*
Y557400D01*
G01X908521Y554757D02*
X909121Y555357D01*
G01X908521Y549857D02*
Y554757D01*
G01X909321Y549057D02*
X908521Y549857D01*
G01X909321Y546521D02*
Y549057D01*
G01X908754Y545954D02*
X909321Y546521D01*
G01X908754Y538747D02*
Y545954D01*
G01X909321Y538180D02*
X908754Y538747D01*
G01X909321Y536522D02*
Y538180D01*
G01X908521Y535722D02*
X909321Y536522D01*
G01X908521Y530242D02*
Y535722D01*
G01X908921Y529842D02*
X908521Y530242D01*
G01X908921Y527721D02*
Y529842D01*
G01X908800Y527600D02*
X908921Y527721D01*
G01X876800Y588100D02*
X875610Y589290D01*
G01X878201Y588100D02*
X876800D01*
G01X879200Y587101D02*
X878201Y588100D01*
G01X879200Y585100D02*
Y587101D01*
G01X878300Y584200D02*
X879200Y585100D01*
G01X878300Y576900D02*
Y584200D01*
G01X879400Y575800D02*
X878300Y576900D01*
G01X879400Y574500D02*
Y575800D01*
G01X878110Y573210D02*
X879400Y574500D01*
G01X878110Y568397D02*
Y573210D01*
G01X879600Y566907D02*
X878110Y568397D01*
G01X879600Y565100D02*
Y566907D01*
G01X878700Y564200D02*
X879600Y565100D01*
G01X878700Y558400D02*
Y564200D01*
G01X879600Y557500D02*
X878700Y558400D01*
G01X879600Y555499D02*
Y557500D01*
G01X878410Y554309D02*
X879600Y555499D01*
G01X878410Y550089D02*
Y554309D01*
G01X879400Y549099D02*
X878410Y550089D01*
G01X879400Y547400D02*
Y549099D01*
G01X878100Y546100D02*
X879400Y547400D01*
G01X878100Y538900D02*
Y546100D01*
G01X879273Y537727D02*
X878100Y538900D01*
G01X879273Y536673D02*
Y537727D01*
G01X878000Y535400D02*
X879273Y536673D01*
G01X878000Y530700D02*
Y535400D01*
G01X879600Y529100D02*
X878000Y530700D01*
G01X879600Y527300D02*
Y529100D01*
G01X892000Y586728D02*
X889319Y589409D01*
G01X892000Y575971D02*
Y586728D01*
G01X892169Y575802D02*
X892000Y575971D01*
G01X892169Y574169D02*
Y575802D01*
G01X891121Y573121D02*
X892169Y574169D01*
G01X891121Y568367D02*
Y573121D01*
G01X892221Y567267D02*
X891121Y568367D01*
G01X892221Y555257D02*
Y567267D01*
G01X891071Y554107D02*
X892221Y555257D01*
G01X891071Y549857D02*
Y554107D01*
G01X892196Y548732D02*
X891071Y549857D01*
G01X892196Y536395D02*
Y548732D01*
G01X891071Y535270D02*
X892196Y536395D01*
G01X891071Y530617D02*
Y535270D01*
G01X892239Y529449D02*
X891071Y530617D01*
G01X856189Y588364D02*
Y588714D01*
G01X854523Y604499D02*
X853543D01*
G01X855122Y603900D02*
X854523Y604499D01*
G01X855122Y602700D02*
Y603900D01*
G01X854178Y601756D02*
X855122Y602700D01*
G01X854178Y600544D02*
Y601756D01*
G01X855022Y599700D02*
X854178Y600544D01*
G01X855022Y598000D02*
Y599700D01*
G01X854178Y597156D02*
X855022Y598000D01*
G01X854178Y595736D02*
Y597156D01*
G01X855322Y594592D02*
X854178Y595736D01*
G01X855322Y592999D02*
Y594592D01*
G01X854415Y592092D02*
X855322Y592999D01*
G01X854415Y590400D02*
Y592092D01*
G01X856101Y588714D02*
X854415Y590400D01*
G01X856189Y588714D02*
X856101D01*
G01X868570Y595462D02*
X870275Y593757D01*
G01X868570Y605649D02*
Y595462D01*
G01X873621Y610700D02*
X868570Y605649D01*
G01X869610Y593092D02*
X870275Y593757D01*
G01X869610Y589257D02*
Y593092D01*
G01X870275Y593757D02*
Y593761D01*
G01X908158Y604499D02*
X907086D01*
G01X908858Y603799D02*
X908158Y604499D01*
G01X908858Y602525D02*
Y603799D01*
G01X907721Y601388D02*
X908858Y602525D01*
G01X907721Y600312D02*
Y601388D01*
G01X908733Y599300D02*
X907721Y600312D01*
G01X908733Y598100D02*
Y599300D01*
G01X907721Y597088D02*
X908733Y598100D01*
G01X907721Y596012D02*
Y597088D01*
G01X908833Y594900D02*
X907721Y596012D01*
G01X908833Y592267D02*
Y594900D01*
G01X908658Y592092D02*
X908833Y592267D01*
G01X908658Y590400D02*
Y592092D01*
G01X910344Y588714D02*
X908658Y590400D01*
G01X871347Y604499D02*
X870275D01*
G01X872047Y603799D02*
X871347Y604499D01*
G01X872047Y602525D02*
Y603799D01*
G01X870910Y601388D02*
X872047Y602525D01*
G01X870910Y600312D02*
Y601388D01*
G01X871922Y599300D02*
X870910Y600312D01*
G01X871922Y598100D02*
Y599300D01*
G01X870910Y597088D02*
X871922Y598100D01*
G01X870910Y596012D02*
Y597088D01*
G01X872022Y594900D02*
X870910Y596012D01*
G01X872022Y592267D02*
Y594900D01*
G01X871847Y592092D02*
X872022Y592267D01*
G01X871847Y590400D02*
Y592092D01*
G01X873533Y588714D02*
X871847Y590400D01*
G01X873621Y588714D02*
X873533D01*
G01X878040Y604499D02*
X876968D01*
G01X878740Y603799D02*
X878040Y604499D01*
G01X878740Y602525D02*
Y603799D01*
G01X877603Y601388D02*
X878740Y602525D01*
G01X877603Y600312D02*
Y601388D01*
G01X878615Y599300D02*
X877603Y600312D01*
G01X878615Y598100D02*
Y599300D01*
G01X877603Y597088D02*
X878615Y598100D01*
G01X877603Y596012D02*
Y597088D01*
G01X878715Y594900D02*
X877603Y596012D01*
G01X878715Y592267D02*
Y594900D01*
G01X878540Y592092D02*
X878715Y592267D01*
G01X878540Y590400D02*
Y592092D01*
G01X880226Y588714D02*
X878540Y590400D01*
G01X880314Y588714D02*
X880226D01*
G01X880314Y588766D02*
Y588714D01*
G01X884733Y604499D02*
X883661D01*
G01X885333Y603899D02*
X884733Y604499D01*
G01X885333Y603001D02*
Y603899D01*
G01X884296Y601964D02*
X885333Y603001D01*
G01X884296Y600736D02*
Y601964D01*
G01X885233Y599799D02*
X884296Y600736D01*
G01X885233Y598401D02*
Y599799D01*
G01X884296Y597464D02*
X885233Y598401D01*
G01X884296Y596136D02*
Y597464D01*
G01X885433Y594999D02*
X884296Y596136D01*
G01X885433Y593100D02*
Y594999D01*
G01X884933Y592600D02*
X885433Y593100D01*
G01X884933Y590400D02*
Y592600D01*
G01X886619Y588714D02*
X884933Y590400D01*
G01X886707Y588714D02*
X886619D01*
G01X891334Y604499D02*
X890354D01*
G01X891933Y603900D02*
X891334Y604499D01*
G01X891933Y602700D02*
Y603900D01*
G01X890989Y601756D02*
X891933Y602700D01*
G01X890989Y600544D02*
Y601756D01*
G01X891833Y599700D02*
X890989Y600544D01*
G01X891833Y598000D02*
Y599700D01*
G01X890989Y597156D02*
X891833Y598000D01*
G01X890989Y595736D02*
Y597156D01*
G01X892133Y594592D02*
X890989Y595736D01*
G01X892133Y592999D02*
Y594592D01*
G01X891226Y592092D02*
X892133Y592999D01*
G01X891226Y590400D02*
Y592092D01*
G01X892912Y588714D02*
X891226Y590400D01*
G01X893000Y588714D02*
X892912D01*
G01X893000Y588364D02*
Y588714D01*
G01X848822Y610300D02*
X849810D01*
G01X852110Y592324D02*
X853543Y593757D01*
G01X852110Y589807D02*
Y592324D01*
G01X855023Y610300D02*
X856189D01*
G01X851838Y607115D02*
X855023Y610300D01*
G01X851838Y595462D02*
Y607115D01*
G01X853543Y593757D02*
X851838Y595462D01*
G01X850486Y588714D02*
X849896D01*
G01X848522Y603001D02*
Y603899D01*
G01X848422Y598401D02*
Y599799D01*
G01X848622Y593100D02*
Y594999D01*
G01X849896Y588714D02*
X849808D01*
G01X881956Y605635D02*
X886621Y610300D01*
G01X881956Y595462D02*
Y605635D01*
G01X883661Y593757D02*
X881956Y595462D01*
G01X882421Y592517D02*
X883661Y593757D01*
G01X882421Y589607D02*
Y592517D01*
G01X905381Y605649D02*
X910432Y610700D01*
G01X905381Y595462D02*
Y605649D01*
G01X907086Y593757D02*
X905381Y595462D01*
G01X906400Y593071D02*
X907086Y593757D01*
G01X906400Y589300D02*
Y593071D01*
G01X875610Y592399D02*
X876968Y593757D01*
G01X875610Y589290D02*
Y592399D01*
G01X875263Y605649D02*
X880314Y610700D01*
G01X875263Y595462D02*
Y605649D01*
G01X876968Y593757D02*
X875263Y595462D01*
G01X888649Y605949D02*
X893000Y610300D01*
G01X888649Y595462D02*
Y605949D01*
G01X890354Y593757D02*
X888649Y595462D01*
G01X889319Y592722D02*
X890354Y593757D01*
G01X889319Y589409D02*
Y592722D01*
G01X912721Y29499D02*
Y34379D01*
G01X911621Y28399D02*
X912721Y29499D01*
G01X911621Y25655D02*
Y28399D01*
G01X911921Y25355D02*
X911621Y25655D01*
G01X911921Y20678D02*
Y25355D01*
G01X911821Y10725D02*
X910432Y12114D01*
G01X911821Y-2288D02*
Y10725D01*
G01X912433Y-2900D02*
X911821Y-2288D01*
G01X912433Y-4300D02*
Y-2900D01*
G01X910633Y-6100D02*
X912433Y-4300D01*
G01X922344Y-3012D02*
X923432Y-4100D01*
G01X922344Y10301D02*
Y-3012D01*
G01X919544Y13101D02*
X922344Y10301D01*
G01X919544Y16229D02*
Y13101D01*
G01X920472Y17157D02*
X919544Y16229D01*
G01X927165Y-7779D02*
Y-9901D01*
G01X929044Y-5900D02*
X927165Y-7779D01*
G01X930444Y-5900D02*
X929044D01*
G01X931900Y-4444D02*
X930444Y-5900D01*
G01X931900Y-3100D02*
Y-4444D01*
G01X931284Y-2484D02*
X931900Y-3100D01*
G01X931284Y10641D02*
Y-2484D01*
G01X929811Y12114D02*
X931284Y10641D01*
G01X952337Y-2101D02*
X953936Y-3700D01*
G01X952337Y10706D02*
Y-2101D01*
G01X949344Y13699D02*
X952337Y10706D01*
G01X949344Y15911D02*
Y13699D01*
G01X950590Y17157D02*
X949344Y15911D01*
G01X954137Y31700D02*
X955937Y33500D01*
G01X953137Y31700D02*
X954137D01*
G01X951837Y30400D02*
X953137Y31700D01*
G01X951837Y29146D02*
Y30400D01*
G01X950590Y27899D02*
X951837Y29146D01*
G01X945644Y-2101D02*
X947243Y-3700D01*
G01X945644Y11150D02*
Y-2101D01*
G01X942644Y14150D02*
X945644Y11150D01*
G01X942644Y15904D02*
Y14150D01*
G01X943897Y17157D02*
X942644Y15904D01*
G01X921600Y29027D02*
X920472Y27899D01*
G01X921600Y30581D02*
Y29027D01*
G01X922719Y31700D02*
X921600Y30581D01*
G01X923943Y31700D02*
X922719D01*
G01X925519Y33276D02*
X923943Y31700D01*
G01X920472Y-8347D02*
Y-9901D01*
G01X922719Y-6100D02*
X920472Y-8347D01*
G01X923943Y-6100D02*
X922719D01*
G01X925519Y-4524D02*
X923943Y-6100D01*
G01X925519Y-2900D02*
Y-4524D01*
G01X924744Y-2125D02*
X925519Y-2900D01*
G01X924744Y10888D02*
Y-2125D01*
G01X923518Y12114D02*
X924744Y10888D01*
G01X947444Y31700D02*
X949244Y33500D01*
G01X946444Y31700D02*
X947444D01*
G01X945144Y30400D02*
X946444Y31700D01*
G01X945144Y29146D02*
Y30400D01*
G01X943897Y27899D02*
X945144Y29146D01*
G01X930444Y31900D02*
X931900Y33356D01*
G01X929044Y31900D02*
X930444D01*
G01X927165Y30021D02*
X929044Y31900D01*
G01X927165Y27899D02*
Y30021D01*
G01X919121Y29249D02*
Y34779D01*
G01X918571Y28699D02*
X919121Y29249D01*
G01X918571Y18964D02*
Y28699D01*
G01X915221Y15614D02*
X918571Y18964D01*
G01X915221Y14018D02*
Y15614D01*
G01X917125Y12114D02*
X915221Y14018D01*
G01X918514Y10725D02*
X917125Y12114D01*
G01X918514Y-2288D02*
Y10725D01*
G01X919126Y-2900D02*
X918514Y-2288D01*
G01X919126Y-4300D02*
Y-2900D01*
G01X917326Y-6100D02*
X919126Y-4300D01*
G01X916326Y-6100D02*
X917326D01*
G01X915026Y-7400D02*
X916326Y-6100D01*
G01X915026Y-8654D02*
Y-7400D01*
G01X913779Y-9901D02*
X915026Y-8654D01*
G01X928944Y-3233D02*
X929811Y-4100D01*
G01X928944Y10200D02*
Y-3233D01*
G01X926044Y13100D02*
X928944Y10200D01*
G01X926044Y16036D02*
Y13100D01*
G01X927165Y17157D02*
X926044Y16036D01*
G01X945144Y-8654D02*
X943897Y-9901D01*
G01X945144Y-7400D02*
Y-8654D01*
G01X946444Y-6100D02*
X945144Y-7400D01*
G01X947444Y-6100D02*
X946444D01*
G01X949244Y-4300D02*
X947444Y-6100D01*
G01X949244Y-2900D02*
Y-4300D01*
G01X948632Y-2288D02*
X949244Y-2900D01*
G01X948632Y10725D02*
Y-2288D01*
G01X947243Y12114D02*
X948632Y10725D01*
G01X951837Y-8654D02*
X950590Y-9901D01*
G01X951837Y-7400D02*
Y-8654D01*
G01X953137Y-6100D02*
X951837Y-7400D01*
G01X954137Y-6100D02*
X953137D01*
G01X955937Y-4300D02*
X954137Y-6100D01*
G01X955937Y-2900D02*
Y-4300D01*
G01X955325Y-2288D02*
X955937Y-2900D01*
G01X955325Y10725D02*
Y-2288D01*
G01X953936Y12114D02*
X955325Y10725D01*
G01X915221Y28999D02*
Y34821D01*
G01X916021Y28199D02*
X915221Y28999D01*
G01X916021Y20015D02*
Y28199D01*
G01X913779Y17773D02*
X916021Y20015D01*
G01X913779Y17157D02*
Y17773D01*
G01X912658Y16036D02*
X913779Y17157D01*
G01X912658Y13100D02*
Y16036D01*
G01X916000Y9758D02*
X912658Y13100D01*
G01X916000Y8700D02*
Y9758D01*
G01X914200Y6900D02*
X916000Y8700D01*
G01X914200Y5325D02*
Y6900D01*
G01X915400Y4125D02*
X914200Y5325D01*
G01X915400Y2999D02*
Y4125D01*
G01X914200Y1799D02*
X915400Y2999D01*
G01X914200Y426D02*
Y1799D01*
G01X915558Y-932D02*
X914200Y426D01*
G01X915558Y-2133D02*
Y-932D01*
G01X917125Y-3700D02*
X915558Y-2133D01*
G01X946174Y92174D02*
Y103127D01*
G01X945074Y91074D02*
X946174Y92174D01*
G01X945074Y86774D02*
Y91074D01*
G01X945774Y86074D02*
X945074Y86774D01*
G01X945774Y83974D02*
Y86074D01*
G01X945200Y83400D02*
X945774Y83974D01*
G01X945200Y75374D02*
Y83400D01*
G01X945774Y74800D02*
X945200Y75374D01*
G01X945774Y72875D02*
Y74800D01*
G01X945074Y72175D02*
X945774Y72875D01*
G01X945074Y67109D02*
Y72175D01*
G01X945874Y66309D02*
X945074Y67109D01*
G01X945874Y56934D02*
Y66309D01*
G01X943897Y54957D02*
X945874Y56934D01*
G01X942644Y53704D02*
X943897Y54957D01*
G01X942644Y51950D02*
Y53704D01*
G01X945644Y48950D02*
X942644Y51950D01*
G01X945644Y35699D02*
Y48950D01*
G01X947243Y34100D02*
X945644Y35699D01*
G01X911921Y91714D02*
Y105121D01*
G01X912621Y91014D02*
X911921Y91714D01*
G01X912621Y86514D02*
Y91014D01*
G01X911821Y85714D02*
X912621Y86514D01*
G01X911821Y83800D02*
Y85714D01*
G01X912400Y83221D02*
X911821Y83800D01*
G01X912400Y75700D02*
Y83221D01*
G01X911821Y75121D02*
X912400Y75700D01*
G01X911821Y73179D02*
Y75121D01*
G01X912721Y72279D02*
X911821Y73179D01*
G01X912721Y67299D02*
Y72279D01*
G01X911921Y66499D02*
X912721Y67299D01*
G01X911921Y53914D02*
Y66499D01*
G01X912621Y53214D02*
X911921Y53914D01*
G01X912621Y48714D02*
Y53214D01*
G01X911821Y47914D02*
X912621Y48714D01*
G01X911821Y46200D02*
Y47914D01*
G01X912400Y45621D02*
X911821Y46200D01*
G01X912400Y37700D02*
Y45621D01*
G01X911821Y37121D02*
X912400Y37700D01*
G01X911821Y35279D02*
Y37121D01*
G01X912721Y34379D02*
X911821Y35279D01*
G01X955325Y48525D02*
X953936Y49914D01*
G01X955325Y35512D02*
Y48525D01*
G01X955937Y34900D02*
X955325Y35512D01*
G01X955937Y33500D02*
Y34900D01*
G01X955174Y91674D02*
Y103074D01*
G01X955874Y90974D02*
X955174Y91674D01*
G01X955874Y75859D02*
Y90974D01*
G01X955174Y75159D02*
X955874Y75859D01*
G01X955174Y73227D02*
Y75159D01*
G01X955774Y72627D02*
X955174Y73227D01*
G01X955774Y65374D02*
Y72627D01*
G01X955483Y65083D02*
X955774Y65374D01*
G01X955483Y56783D02*
Y65083D01*
G01X952100Y53400D02*
X955483Y56783D01*
G01X952100Y51750D02*
Y53400D01*
G01X953936Y49914D02*
X952100Y51750D01*
G01X922374Y56859D02*
X920472Y54957D01*
G01X922374Y66227D02*
Y56859D01*
G01X921574Y67027D02*
X922374Y66227D01*
G01X921574Y72159D02*
Y67027D01*
G01X922374Y72959D02*
X921574Y72159D01*
G01X922374Y74726D02*
Y72959D01*
G01X921800Y75300D02*
X922374Y74726D01*
G01X921800Y83426D02*
Y75300D01*
G01X922374Y84000D02*
X921800Y83426D01*
G01X922374Y85574D02*
Y84000D01*
G01X921574Y86374D02*
X922374Y85574D01*
G01X921574Y90974D02*
Y86374D01*
G01X922374Y91774D02*
X921574Y90974D01*
G01X922374Y105074D02*
Y91774D01*
G01X922344Y34788D02*
X923432Y33700D01*
G01X922344Y48101D02*
Y34788D01*
G01X921700Y48745D02*
X922344Y48101D01*
G01X921700Y53729D02*
Y48745D01*
G01X920472Y54957D02*
X921700Y53729D01*
G01X952574Y91874D02*
Y103426D01*
G01X952074Y91374D02*
X952574Y91874D01*
G01X952074Y86374D02*
Y91374D01*
G01X952674Y85774D02*
X952074Y86374D01*
G01X952674Y84000D02*
Y85774D01*
G01X952000Y83326D02*
X952674Y84000D01*
G01X952000Y75300D02*
Y83326D01*
G01X952674Y74626D02*
X952000Y75300D01*
G01X952674Y73275D02*
Y74626D01*
G01X951874Y72475D02*
X952674Y73275D01*
G01X951874Y67259D02*
Y72475D01*
G01X953074Y66059D02*
X951874Y67259D01*
G01X953074Y57441D02*
Y66059D01*
G01X950590Y54957D02*
X953074Y57441D01*
G01X949344Y53711D02*
X950590Y54957D01*
G01X949344Y51499D02*
Y53711D01*
G01X952337Y48506D02*
X949344Y51499D01*
G01X952337Y35699D02*
Y48506D01*
G01X953936Y34100D02*
X952337Y35699D01*
G01X924200Y50596D02*
X923518Y49914D01*
G01X924200Y54700D02*
Y50596D01*
G01X925000Y55500D02*
X924200Y54700D01*
G01X925000Y66985D02*
Y55500D01*
G01X925374Y67359D02*
X925000Y66985D01*
G01X925374Y72659D02*
Y67359D01*
G01X925074Y72959D02*
X925374Y72659D01*
G01X925074Y75174D02*
Y72959D01*
G01X925800Y75900D02*
X925074Y75174D01*
G01X925800Y83374D02*
Y75900D01*
G01X925074Y84100D02*
X925800Y83374D01*
G01X925074Y86074D02*
Y84100D01*
G01X925474Y86474D02*
X925074Y86074D01*
G01X925474Y91174D02*
Y86474D01*
G01X925174Y91474D02*
X925474Y91174D01*
G01X925174Y105628D02*
Y91474D01*
G01X925519Y34900D02*
Y33276D01*
G01X924744Y35675D02*
X925519Y34900D01*
G01X924744Y48688D02*
Y35675D01*
G01X923518Y49914D02*
X924744Y48688D01*
G01X927165Y62850D02*
Y54957D01*
G01X929074Y64759D02*
X927165Y62850D01*
G01X929074Y66225D02*
Y64759D01*
G01X928106Y67193D02*
X929074Y66225D01*
G01X928106Y67195D02*
Y67193D01*
G01X927974Y67327D02*
X928106Y67195D01*
G01X927974Y72275D02*
Y67327D01*
G01X928974Y73275D02*
X927974Y72275D01*
G01X928974Y75126D02*
Y73275D01*
G01X928500Y75600D02*
X928974Y75126D01*
G01X928500Y83526D02*
Y75600D01*
G01X928974Y84000D02*
X928500Y83526D01*
G01X928974Y85474D02*
Y84000D01*
G01X927574Y86874D02*
X928974Y85474D01*
G01X927574Y90674D02*
Y86874D01*
G01X928974Y92074D02*
X927574Y90674D01*
G01X928974Y104874D02*
Y92074D01*
G01X928944Y34567D02*
X929811Y33700D01*
G01X928944Y48000D02*
Y34567D01*
G01X926200Y50744D02*
X928944Y48000D01*
G01X926200Y53992D02*
Y50744D01*
G01X927165Y54957D02*
X926200Y53992D01*
G01X963976Y70776D02*
Y65814D01*
G01X965699Y72499D02*
X963976Y70776D01*
G01X965699Y83501D02*
Y72499D01*
G01X965434Y83766D02*
X965699Y83501D01*
G01X965434Y86034D02*
Y83766D01*
G01X966100Y86700D02*
X965434Y86034D01*
G01X966100Y88400D02*
Y86700D01*
G01X965300Y89200D02*
X966100Y88400D01*
G01X965300Y90800D02*
Y89200D01*
G01X966800Y92300D02*
X965300Y90800D01*
G01X966800Y93616D02*
Y92300D01*
G01X973884Y100700D02*
X966800Y93616D01*
G01X948632Y48525D02*
X947243Y49914D01*
G01X948632Y35512D02*
Y48525D01*
G01X949244Y34900D02*
X948632Y35512D01*
G01X949244Y33500D02*
Y34900D01*
G01X948674Y91712D02*
Y103653D01*
G01X949374Y91012D02*
X948674Y91712D01*
G01X949374Y86674D02*
Y91012D01*
G01X948774Y86074D02*
X949374Y86674D01*
G01X948774Y83926D02*
Y86074D01*
G01X949100Y83600D02*
X948774Y83926D01*
G01X949100Y75600D02*
Y83600D01*
G01X948774Y75274D02*
X949100Y75600D01*
G01X948774Y72659D02*
Y75274D01*
G01X949274Y72159D02*
X948774Y72659D01*
G01X949274Y67059D02*
Y72159D01*
G01X948074Y65859D02*
X949274Y67059D01*
G01X948074Y55857D02*
Y65859D01*
G01X945538Y53321D02*
X948074Y55857D01*
G01X945538Y51619D02*
Y53321D01*
G01X947243Y49914D02*
X945538Y51619D01*
G01X931284Y48441D02*
X929811Y49914D01*
G01X931284Y35316D02*
Y48441D01*
G01X931900Y34700D02*
X931284Y35316D01*
G01X931900Y33356D02*
Y34700D01*
G01X931674Y84000D02*
Y105071D01*
G01X932400Y83274D02*
X931674Y84000D01*
G01X932400Y75600D02*
Y83274D01*
G01X931674Y74874D02*
X932400Y75600D01*
G01X931674Y64259D02*
Y74874D01*
G01X929224Y61809D02*
X931674Y64259D01*
G01X929224Y54474D02*
Y61809D01*
G01X928100Y53350D02*
X929224Y54474D01*
G01X928100Y51625D02*
Y53350D01*
G01X929811Y49914D02*
X928100Y51625D01*
G01X918621Y91874D02*
Y105420D01*
G01X919221Y91274D02*
X918621Y91874D01*
G01X919221Y86614D02*
Y91274D01*
G01X918521Y85914D02*
X919221Y86614D01*
G01X918521Y83900D02*
Y85914D01*
G01X919200Y83221D02*
X918521Y83900D01*
G01X919200Y75300D02*
Y83221D01*
G01X918521Y74621D02*
X919200Y75300D01*
G01X918521Y73179D02*
Y74621D01*
G01X919121Y72579D02*
X918521Y73179D01*
G01X919121Y67049D02*
Y72579D01*
G01X918571Y66499D02*
X919121Y67049D01*
G01X918571Y53864D02*
Y66499D01*
G01X918900Y53535D02*
X918571Y53864D01*
G01X918900Y48493D02*
Y53535D01*
G01X918521Y48114D02*
X918900Y48493D01*
G01X918521Y46179D02*
Y48114D01*
G01X919200Y45500D02*
X918521Y46179D01*
G01X919200Y37579D02*
Y45500D01*
G01X918521Y36900D02*
X919200Y37579D01*
G01X918521Y35379D02*
Y36900D01*
G01X919121Y34779D02*
X918521Y35379D01*
G01X915674Y91667D02*
Y104974D01*
G01X915121Y91114D02*
X915674Y91667D01*
G01X915121Y86414D02*
Y91114D01*
G01X915721Y85814D02*
X915121Y86414D01*
G01X915721Y84000D02*
Y85814D01*
G01X915000Y83279D02*
X915721Y84000D01*
G01X915000Y75400D02*
Y83279D01*
G01X915721Y74679D02*
X915000Y75400D01*
G01X915721Y73121D02*
Y74679D01*
G01X915221Y72621D02*
X915721Y73121D01*
G01X915221Y66799D02*
Y72621D01*
G01X916071Y65949D02*
X915221Y66799D01*
G01X916071Y54264D02*
Y65949D01*
G01X915121Y53314D02*
X916071Y54264D01*
G01X915121Y48614D02*
Y53314D01*
G01X915721Y48014D02*
X915121Y48614D01*
G01X915721Y46200D02*
Y48014D01*
G01X915154Y45633D02*
X915721Y46200D01*
G01X915154Y37746D02*
Y45633D01*
G01X915721Y37179D02*
X915154Y37746D01*
G01X915721Y35321D02*
Y37179D01*
G01X915221Y34821D02*
X915721Y35321D01*
G01X945274Y110150D02*
X944497Y110927D01*
G01X945274Y104027D02*
Y110150D01*
G01X946174Y103127D02*
X945274Y104027D01*
G01X940700Y152029D02*
X980326Y191655D01*
G01X940700Y142672D02*
Y152029D01*
G01X911774Y113746D02*
X940700Y142672D01*
G01X911774Y111474D02*
Y113746D01*
G01X912574Y110674D02*
X911774Y111474D01*
G01X912574Y105774D02*
Y110674D01*
G01X911921Y105121D02*
X912574Y105774D01*
G01X934300Y149165D02*
X978000Y192865D01*
G01X934300Y147250D02*
Y149165D01*
G01X937629Y143921D02*
X934300Y147250D01*
G01X937629Y143129D02*
Y143921D01*
G01X936695Y142195D02*
X937629Y143129D01*
G01X935903Y142195D02*
X936695D01*
G01X932638Y145460D02*
X935903Y142195D01*
G01X931776Y145460D02*
X932638D01*
G01X930912Y144596D02*
X931776Y145460D01*
G01X930912Y143734D02*
Y144596D01*
G01X934138Y140508D02*
X930912Y143734D01*
G01X934138Y139646D02*
Y140508D01*
G01X955874Y105596D02*
X953786Y107684D01*
G01X955874Y103774D02*
Y105596D01*
G01X955174Y103074D02*
X955874Y103774D01*
G01X921574Y105874D02*
X922374Y105074D01*
G01X921574Y111225D02*
Y105874D01*
G01X920472Y112327D02*
X921574Y111225D01*
G01X950590Y105410D02*
Y109700D01*
G01X952574Y103426D02*
X950590Y105410D01*
G01X923518Y107284D02*
X925174Y105628D01*
G01X927874Y105974D02*
X928974Y104874D01*
G01X927874Y111618D02*
Y105974D01*
G01X927165Y112327D02*
X927874Y111618D01*
G01X948674Y103653D02*
X947243Y105084D01*
G01X931674Y105071D02*
X929811Y106934D01*
G01X953700Y148600D02*
Y157957D01*
G01X918474Y113374D02*
X953700Y148600D01*
G01X918474Y111274D02*
Y113374D01*
G01X919142Y110606D02*
X918474Y111274D01*
G01X919142Y105941D02*
Y110606D01*
G01X918621Y105420D02*
X919142Y105941D01*
G01X918502Y147702D02*
X960500Y189700D01*
G01X918502Y145356D02*
Y147702D01*
G01X916094Y148830D02*
X957600Y190336D01*
G01X916094Y146238D02*
Y148830D01*
G01X947663Y155457D02*
X982826Y190620D01*
G01X947663Y154665D02*
Y155457D01*
G01X950768Y151560D02*
X947663Y154665D01*
G01X950768Y150768D02*
Y151560D01*
G01X949749Y149749D02*
X950768Y150768D01*
G01X948957Y149749D02*
X949749D01*
G01X945852Y152854D02*
X948957Y149749D01*
G01X945060Y152854D02*
X945852D01*
G01X943200Y150994D02*
X945060Y152854D01*
G01X943200Y141636D02*
Y150994D01*
G01X915674Y114110D02*
X943200Y141636D01*
G01X915674Y111174D02*
Y114110D01*
G01X915074Y110574D02*
X915674Y111174D01*
G01X915074Y105574D02*
Y110574D01*
G01X915674Y104974D02*
X915074Y105574D01*
G01X939920Y184194D02*
Y186920D01*
G01X938788Y183062D02*
X939920Y184194D01*
G01X937208Y183062D02*
X938788D01*
G01X936708Y182562D02*
X937208Y183062D01*
G01X936708Y180982D02*
Y182562D01*
G01X935359Y179633D02*
X936708Y180982D01*
G01X934186Y179633D02*
X935359D01*
G01X933119Y180700D02*
X934186Y179633D01*
G01X930800Y180700D02*
X933119D01*
G01X929779Y179679D02*
X930800Y180700D01*
G01X929779Y178817D02*
Y179679D01*
G01X931753Y176843D02*
X929779Y178817D01*
G01X931753Y175981D02*
Y176843D01*
G01X930889Y175117D02*
X931753Y175981D01*
G01X930027Y175117D02*
X930889D01*
G01X929071Y176073D02*
X930027Y175117D01*
G01X928279Y176073D02*
X929071D01*
G01X922672Y170466D02*
X928279Y176073D01*
G01X920566Y170466D02*
X922672D01*
G01X917984Y167884D02*
X920566Y170466D01*
G01X917984Y163449D02*
Y167884D01*
G01X954700Y201636D02*
X956000Y202936D01*
G01X954700Y190972D02*
Y201636D01*
G01X918095Y199831D02*
X918296D01*
G01X918556Y204656D02*
Y204941D01*
G01X916688Y206688D02*
Y206810D01*
G01X953700Y157957D02*
X985326Y189583D01*
G01X919131Y197331D02*
X919945D01*
G01X931741Y191440D02*
X933097D01*
G01X927509Y187208D02*
X931741Y191440D01*
G01X926647Y187208D02*
X927509D01*
G01X925299Y188556D02*
X926647Y187208D01*
G01X924437Y188556D02*
X925299D01*
G01X923573Y187692D02*
X924437Y188556D01*
G01X923573Y186830D02*
Y187692D01*
G01X924921Y185482D02*
X923573Y186830D01*
G01X924921Y184620D02*
Y185482D01*
G01X924057Y183756D02*
X924921Y184620D01*
G01X923195Y183756D02*
X924057D01*
G01X921847Y185104D02*
X923195Y183756D01*
G01X920985Y185104D02*
X921847D01*
G01X920121Y184240D02*
X920985Y185104D01*
G01X920121Y183378D02*
Y184240D01*
G01X921469Y182030D02*
X920121Y183378D01*
G01X921469Y181168D02*
Y182030D01*
G01X951500Y201980D02*
X954120Y204600D01*
G01X951500Y199700D02*
Y201980D01*
G01X948700Y196900D02*
X951500Y199700D01*
G01X948700Y193100D02*
Y196900D01*
G01X949700Y192100D02*
X948700Y193100D01*
G01X949700Y189508D02*
Y192100D01*
G01X925837Y165645D02*
X949700Y189508D01*
G01X924705Y165645D02*
X925837D01*
G01X923971Y166379D02*
X924705Y165645D01*
G01X923179Y166379D02*
X923971D01*
G01X921708Y164908D02*
X923179Y166379D01*
G01X921708Y164116D02*
Y164908D01*
G01X922442Y163382D02*
X921708Y164116D01*
G01X922442Y162250D02*
Y163382D01*
G01X960500Y196533D02*
X965732Y201765D01*
G01X960500Y189700D02*
Y196533D01*
G01X911589Y212333D02*
X912436D01*
G01X930733Y185600D02*
X934570Y189437D01*
G01X929101Y185600D02*
X930733D01*
G01X931569Y182900D02*
X938139Y189470D01*
G01X929801Y182900D02*
X931569D01*
G01X915606Y168705D02*
X929801Y182900D01*
G01X915606Y165106D02*
Y168705D01*
G01X913261Y162761D02*
X915606Y165106D01*
G01X957600Y197503D02*
X963497Y203400D01*
G01X957600Y190336D02*
Y197503D01*
G01X917084Y401870D02*
X911695Y407259D01*
G01X965300Y461387D02*
X959916Y466771D01*
G01X965300Y434300D02*
Y461387D01*
G01X980856Y418744D02*
X965300Y434300D01*
G01X915465Y411380D02*
Y420959D01*
G01X920480Y406365D02*
X915465Y411380D01*
G01X919309Y436023D02*
X918177D01*
G01X919627Y436341D02*
X919309Y436023D01*
G01X920759Y436341D02*
X919627D01*
G01X921890Y435210D02*
X920759Y436341D01*
G01X921890Y434078D02*
Y435210D01*
G01X921272Y433460D02*
X921890Y434078D01*
G01X921272Y432328D02*
Y433460D01*
G01X922411Y431189D02*
X921272Y432328D01*
G01X923543Y431189D02*
X922411D01*
G01X925561Y433207D02*
X923543Y431189D01*
G01X926693Y433207D02*
X925561D01*
G01X927824Y432076D02*
X926693Y433207D01*
G01X927824Y430944D02*
Y432076D01*
G01X926106Y429226D02*
X927824Y430944D01*
G01X926106Y428094D02*
Y429226D01*
G01X927900Y426300D02*
X926106Y428094D01*
G01X927900Y415597D02*
Y426300D01*
G01X932706Y410791D02*
X927900Y415597D01*
G01X953900Y464500D02*
X953135Y465265D01*
G01X953900Y460500D02*
Y464500D01*
G01X955066Y459334D02*
X953900Y460500D01*
G01X956198Y459334D02*
X955066D01*
G01X957316Y460452D02*
X956198Y459334D01*
G01X958448Y460452D02*
X957316D01*
G01X959579Y459321D02*
X958448Y460452D01*
G01X959579Y458189D02*
Y459321D01*
G01X958461Y457071D02*
X959579Y458189D01*
G01X958461Y455939D02*
Y457071D01*
G01X960300Y454100D02*
X958461Y455939D01*
G01X960300Y432100D02*
Y454100D01*
G01X975483Y416917D02*
X960300Y432100D01*
G01X913837Y445295D02*
X912705D01*
G01X915655Y447113D02*
X913837Y445295D01*
G01X916787Y447113D02*
X915655D01*
G01X917918Y445982D02*
X916787Y447113D01*
G01X917918Y444850D02*
Y445982D01*
G01X916000Y442932D02*
X917918Y444850D01*
G01X916000Y441800D02*
Y442932D01*
G01X917131Y440669D02*
X916000Y441800D01*
G01X918263Y440669D02*
X917131D01*
G01X920181Y442587D02*
X918263Y440669D01*
G01X921313Y442587D02*
X920181D01*
G01X922675Y441225D02*
X921313Y442587D01*
G01X922675Y440093D02*
Y441225D01*
G01X922257Y439675D02*
X922675Y440093D01*
G01X922257Y438543D02*
Y439675D01*
G01X923388Y437412D02*
X922257Y438543D01*
G01X924520Y437412D02*
X923388D01*
G01X924938Y437830D02*
X924520Y437412D01*
G01X926070Y437830D02*
X924938D01*
G01X930400Y433500D02*
X926070Y437830D01*
G01X930400Y416633D02*
Y433500D01*
G01X934724Y412309D02*
X930400Y416633D01*
G01X914652Y456748D02*
X913500Y457900D01*
G01X915784Y456748D02*
X914652D01*
G01X917797Y458761D02*
X915784Y456748D01*
G01X919049Y458761D02*
X917797D01*
G01X920180Y457630D02*
X919049Y458761D01*
G01X920180Y456618D02*
Y457630D01*
G01X918047Y454485D02*
X920180Y456618D01*
G01X918047Y453353D02*
Y454485D01*
G01X919317Y452083D02*
X918047Y453353D01*
G01X920449Y452083D02*
X919317D01*
G01X922689Y454323D02*
X920449Y452083D01*
G01X923870Y454323D02*
X922689D01*
G01X925001Y453192D02*
X923870Y454323D01*
G01X925001Y452109D02*
Y453192D01*
G01X922712Y449820D02*
X925001Y452109D01*
G01X922712Y448688D02*
Y449820D01*
G01X923843Y447557D02*
X922712Y448688D01*
G01X924975Y447557D02*
X923843D01*
G01X926973Y449555D02*
X924975Y447557D01*
G01X928154Y449555D02*
X926973D01*
G01X929285Y448424D02*
X928154Y449555D01*
G01X929285Y447341D02*
Y448424D01*
G01X927238Y445294D02*
X929285Y447341D01*
G01X927238Y444162D02*
Y445294D01*
G01X928369Y443031D02*
X927238Y444162D01*
G01X929501Y443031D02*
X928369D01*
G01X930919Y444449D02*
X929501Y443031D01*
G01X932051Y444449D02*
X930919D01*
G01X935500Y441000D02*
X932051Y444449D01*
G01X935500Y419443D02*
Y441000D01*
G01X938279Y416664D02*
X935500Y419443D01*
G01X922221Y463879D02*
X912313D01*
G01X942100Y444000D02*
X922221Y463879D01*
G01X942100Y425000D02*
Y444000D01*
G01X956483Y410617D02*
X942100Y425000D01*
G01X956483Y403882D02*
Y410617D01*
G01X930981Y463787D02*
Y464919D01*
G01X930863Y463669D02*
X930981Y463787D01*
G01X930863Y462537D02*
Y463669D01*
G01X931994Y461406D02*
X930863Y462537D01*
G01X933126Y461406D02*
X931994D01*
G01X933244Y461524D02*
X933126Y461406D01*
G01X934376Y461524D02*
X933244D01*
G01X935507Y460393D02*
X934376Y461524D01*
G01X935507Y459261D02*
Y460393D01*
G01X935389Y459143D02*
X935507Y459261D01*
G01X935389Y458011D02*
Y459143D01*
G01X936520Y456880D02*
X935389Y458011D01*
G01X937652Y456880D02*
X936520D01*
G01X937770Y456998D02*
X937652Y456880D01*
G01X938902Y456998D02*
X937770D01*
G01X940033Y455867D02*
X938902Y456998D01*
G01X940033Y454735D02*
Y455867D01*
G01X939915Y454617D02*
X940033Y454735D01*
G01X939915Y453485D02*
Y454617D01*
G01X941046Y452354D02*
X939915Y453485D01*
G01X942178Y452354D02*
X941046D01*
G01X942296Y452472D02*
X942178Y452354D01*
G01X943428Y452472D02*
X942296D01*
G01X947200Y448700D02*
X943428Y452472D01*
G01X947200Y427100D02*
Y448700D01*
G01X961783Y412517D02*
X947200Y427100D01*
G01X961783Y404426D02*
Y412517D01*
G01X913580Y409729D02*
Y419308D01*
G01X918712Y404597D02*
X913580Y409729D01*
G01X911695Y407259D02*
Y417657D01*
G01X939600Y442900D02*
X920665Y461835D01*
G01X939600Y423900D02*
Y442900D01*
G01X953983Y409517D02*
X939600Y423900D01*
G01X953983Y403882D02*
Y409517D01*
G01X962800Y461214D02*
X938014Y486000D01*
G01X962800Y433200D02*
Y461214D01*
G01X978356Y417644D02*
X962800Y433200D01*
G01X951200Y463600D02*
X933800Y481000D01*
G01X951200Y459400D02*
Y463600D01*
G01X957700Y452900D02*
X951200Y459400D01*
G01X957700Y431100D02*
Y452900D01*
G01X972983Y415817D02*
X957700Y431100D01*
G01X912524Y455176D02*
X911392D01*
G01X913655Y454045D02*
X912524Y455176D01*
G01X913655Y452913D02*
Y454045D01*
G01X911738Y450996D02*
X913655Y452913D01*
G01X911738Y449864D02*
Y450996D01*
G01X912657Y448945D02*
X911738Y449864D01*
G01X913787Y448945D02*
X912657D01*
G01X915622Y450781D02*
X913787Y448945D01*
G01X916752Y450781D02*
X915622D01*
G01X928253Y439280D02*
X916752Y450781D01*
G01X929383Y439280D02*
X928253D01*
G01X930736Y440632D02*
X929383Y439280D01*
G01X931866Y440632D02*
X930736D01*
G01X932999Y439499D02*
X931866Y440632D01*
G01X932999Y438369D02*
Y439499D01*
G01X931646Y437017D02*
X932999Y438369D01*
G01X931646Y435887D02*
Y437017D01*
G01X932900Y434633D02*
X931646Y435887D01*
G01X932900Y418507D02*
Y434633D01*
G01X936511Y414896D02*
X932900Y418507D01*
G01X944600Y445100D02*
X923739Y465961D01*
G01X944600Y426100D02*
Y445100D01*
G01X959283Y411417D02*
X944600Y426100D01*
G01X959283Y404426D02*
Y411417D01*
G01X945700Y494800D02*
X944000Y493100D01*
G01X945700Y502100D02*
Y494800D01*
G01X946132Y502532D02*
X945700Y502100D01*
G01X946132Y511257D02*
Y502532D01*
G01X945332Y512057D02*
X946132Y511257D01*
G01X945332Y516957D02*
Y512057D01*
G01X945932Y517557D02*
X945332Y516957D01*
G01X945932Y519400D02*
Y517557D01*
G01X945600Y519732D02*
X945932Y519400D01*
G01X945600Y527900D02*
Y519732D01*
G01X918800Y519329D02*
Y527900D01*
G01X918571Y519100D02*
X918800Y519329D01*
G01X918571Y517357D02*
Y519100D01*
G01X919121Y516807D02*
X918571Y517357D01*
G01X919121Y512257D02*
Y516807D01*
G01X918521Y511657D02*
X919121Y512257D01*
G01X918521Y497405D02*
Y511657D01*
G01X919000Y496926D02*
X918521Y497405D01*
G01X919000Y494800D02*
Y496926D01*
G01X921800Y492000D02*
X919000Y494800D01*
G01X921800Y490500D02*
Y492000D01*
G01X923700Y488600D02*
X921800Y490500D01*
G01X938087Y488600D02*
X923700D01*
G01X943213Y483474D02*
X938087Y488600D01*
G01X944075Y483474D02*
X943213D01*
G01X945519Y484920D02*
X944075Y483474D01*
G01X946382Y484920D02*
X945519D01*
G01X947783Y483519D02*
X946382Y484920D01*
G01X947783Y482658D02*
Y483519D01*
G01X946338Y481211D02*
X947783Y482658D01*
G01X946338Y480349D02*
Y481211D01*
G01X947739Y478948D02*
X946338Y480349D01*
G01X948601Y478948D02*
X947739D01*
G01X950017Y480366D02*
X948601Y478948D01*
G01X950880Y480366D02*
X950017D01*
G01X952281Y478965D02*
X950880Y480366D01*
G01X952281Y478104D02*
Y478965D01*
G01X950864Y476685D02*
X952281Y478104D01*
G01X950864Y475823D02*
Y476685D01*
G01X952265Y474422D02*
X950864Y475823D01*
G01X953127Y474422D02*
X952265D01*
G01X954361Y475658D02*
X953127Y474422D01*
G01X955224Y475658D02*
X954361D01*
G01X956625Y474257D02*
X955224Y475658D01*
G01X956625Y473396D02*
Y474257D01*
G01X955390Y472159D02*
X956625Y473396D01*
G01X955390Y471297D02*
Y472159D01*
G01X956791Y469896D02*
X955390Y471297D01*
G01X957653Y469896D02*
X956791D01*
G01X958200Y470444D02*
X957653Y469896D01*
G01X958440Y470684D02*
X958200Y470444D01*
G01X959302Y470684D02*
X958440D01*
G01X960703Y469283D02*
X959302Y470684D01*
G01X960703Y468421D02*
Y469283D01*
G01X959916Y467633D02*
X960703Y468421D01*
G01X959916Y466771D02*
Y467633D01*
G01X970206Y500394D02*
X973430Y497170D01*
G01X970206Y509866D02*
Y500394D01*
G01X968824Y511248D02*
X970206Y509866D01*
G01X968824Y513599D02*
Y511248D01*
G01X969148Y513923D02*
X968824Y513599D01*
G01X969148Y516890D02*
Y513923D01*
G01X965900Y520138D02*
X969148Y516890D01*
G01X965900Y524300D02*
Y520138D01*
G01X962360Y527840D02*
X965900Y524300D01*
G01X952300Y494900D02*
X950700Y493300D01*
G01X952300Y501901D02*
Y494900D01*
G01X952532Y502133D02*
X952300Y501901D01*
G01X952532Y511157D02*
Y502133D01*
G01X952032Y511657D02*
X952532Y511157D01*
G01X952032Y517057D02*
Y511657D01*
G01X952832Y517857D02*
X952032Y517057D01*
G01X952832Y529497D02*
Y517857D01*
G01X925400Y495544D02*
X923600Y493744D01*
G01X925400Y503200D02*
Y495544D01*
G01X925200Y503400D02*
X925400Y503200D01*
G01X925200Y510825D02*
Y503400D01*
G01X925382Y511007D02*
X925200Y510825D01*
G01X925382Y517207D02*
Y511007D01*
G01X925132Y517457D02*
X925382Y517207D01*
G01X925132Y519400D02*
Y517457D01*
G01X925500Y519768D02*
X925132Y519400D01*
G01X925500Y527900D02*
Y519768D01*
G01X928800Y519832D02*
Y527900D01*
G01X929032Y519600D02*
X928800Y519832D01*
G01X929032Y517457D02*
Y519600D01*
G01X927882Y516307D02*
X929032Y517457D01*
G01X927882Y512057D02*
Y516307D01*
G01X929232Y510707D02*
X927882Y512057D01*
G01X929232Y507109D02*
Y510707D01*
G01X927165Y505042D02*
X929232Y507109D01*
G01X927165Y498644D02*
Y505042D01*
G01X912100Y519479D02*
Y527700D01*
G01X911921Y519300D02*
X912100Y519479D01*
G01X911921Y517357D02*
Y519300D01*
G01X912721Y516557D02*
X911921Y517357D01*
G01X912721Y512157D02*
Y516557D01*
G01X911821Y511257D02*
X912721Y512157D01*
G01X911821Y494879D02*
Y511257D01*
G01X912387Y494313D02*
X911821Y494879D01*
G01X912387Y489114D02*
Y494313D01*
G01X918001Y483500D02*
X912387Y489114D01*
G01X934900Y483500D02*
X918001D01*
G01X936432Y481968D02*
X934900Y483500D01*
G01X937294Y481968D02*
X936432D01*
G01X937825Y482499D02*
X937294Y481968D01*
G01X938687Y482499D02*
X937825D01*
G01X940088Y481098D02*
X938687Y482499D01*
G01X940088Y480236D02*
Y481098D01*
G01X939557Y479705D02*
X940088Y480236D01*
G01X939557Y478843D02*
Y479705D01*
G01X940958Y477442D02*
X939557Y478843D01*
G01X941820Y477442D02*
X940958D01*
G01X942351Y477973D02*
X941820Y477442D01*
G01X943213Y477973D02*
X942351D01*
G01X944614Y476572D02*
X943213Y477973D01*
G01X944614Y475710D02*
Y476572D01*
G01X944083Y475179D02*
X944614Y475710D01*
G01X944083Y474317D02*
Y475179D01*
G01X945484Y472916D02*
X944083Y474317D01*
G01X946346Y472916D02*
X945484D01*
G01X946877Y473447D02*
X946346Y472916D01*
G01X947739Y473447D02*
X946877D01*
G01X949140Y472046D02*
X947739Y473447D01*
G01X949140Y471184D02*
Y472046D01*
G01X948609Y470653D02*
X949140Y471184D01*
G01X948609Y469791D02*
Y470653D01*
G01X950010Y468390D02*
X948609Y469791D01*
G01X950872Y468390D02*
X950010D01*
G01X951403Y468921D02*
X950872Y468390D01*
G01X952265Y468921D02*
X951403D01*
G01X953666Y467520D02*
X952265Y468921D01*
G01X953666Y466658D02*
Y467520D01*
G01X953135Y466127D02*
X953666Y466658D01*
G01X953135Y465265D02*
Y466127D01*
G01X949500Y497001D02*
X947443Y494944D01*
G01X949500Y498700D02*
Y497001D01*
G01X948290Y499910D02*
X949500Y498700D01*
G01X948290Y502190D02*
Y499910D01*
G01X948632Y502532D02*
X948290Y502190D01*
G01X948632Y511257D02*
Y502532D01*
G01X949532Y512157D02*
X948632Y511257D01*
G01X949532Y516557D02*
Y512157D01*
G01X948432Y517657D02*
X949532Y516557D01*
G01X948432Y519100D02*
Y517657D01*
G01X948900Y519568D02*
X948432Y519100D01*
G01X948900Y527900D02*
Y519568D01*
G01X912958Y470500D02*
X912100D01*
G01X913568Y469890D02*
X912958Y470500D01*
G01X913568Y468693D02*
Y469890D01*
G01X914178Y468083D02*
X913568Y468693D01*
G01X916158Y468083D02*
X914178D01*
G01X916768Y468693D02*
X916158Y468083D01*
G01X916768Y470518D02*
Y468693D01*
G01X917378Y471128D02*
X916768Y470518D01*
G01X919358Y471128D02*
X917378D01*
G01X919968Y470518D02*
X919358Y471128D01*
G01X919968Y468693D02*
Y470518D01*
G01X920578Y468083D02*
X919968Y468693D01*
G01X922558Y468083D02*
X920578D01*
G01X923168Y468693D02*
X922558Y468083D01*
G01X923168Y469890D02*
Y468693D01*
G01X923778Y470500D02*
X923168Y469890D01*
G01X925400Y470500D02*
X923778D01*
G01X926455Y469445D02*
X925400Y470500D01*
G01X926455Y468313D02*
Y469445D01*
G01X926337Y468195D02*
X926455Y468313D01*
G01X926337Y467063D02*
Y468195D01*
G01X927468Y465932D02*
X926337Y467063D01*
G01X928600Y465932D02*
X927468D01*
G01X928718Y466050D02*
X928600Y465932D01*
G01X929850Y466050D02*
X928718D01*
G01X930981Y464919D02*
X929850Y466050D01*
G01X922200Y519532D02*
Y527700D01*
G01X922432Y519300D02*
X922200Y519532D01*
G01X922432Y517357D02*
Y519300D01*
G01X921532Y516457D02*
X922432Y517357D01*
G01X921532Y511757D02*
Y516457D01*
G01X922532Y510757D02*
X921532Y511757D01*
G01X922532Y508610D02*
Y510757D01*
G01X920700Y506778D02*
X922532Y508610D01*
G01X920700Y498644D02*
Y506778D01*
G01X956174Y496874D02*
X954000Y494700D01*
G01X956174Y509626D02*
Y496874D01*
G01X955332Y510468D02*
X956174Y509626D01*
G01X955332Y511657D02*
Y510468D01*
G01X955932Y512257D02*
X955332Y511657D01*
G01X955932Y516807D02*
Y512257D01*
G01X955382Y517357D02*
X955932Y516807D01*
G01X955382Y529847D02*
Y517357D01*
G01X932200Y518900D02*
Y527800D01*
G01X931732Y518432D02*
X932200Y518900D01*
G01X931732Y505811D02*
Y518432D01*
G01X929811Y503890D02*
X931732Y505811D01*
G01X929811Y493244D02*
Y503890D01*
G01X915500Y519671D02*
Y527800D01*
G01X916071Y519100D02*
X915500Y519671D01*
G01X916071Y517907D02*
Y519100D01*
G01X915221Y517057D02*
X916071Y517907D01*
G01X915221Y511657D02*
Y517057D01*
G01X915721Y511157D02*
X915221Y511657D01*
G01X915721Y495321D02*
Y511157D01*
G01X915500Y495100D02*
X915721Y495321D01*
G01X915500Y489801D02*
Y495100D01*
G01X919301Y486000D02*
X915500Y489801D01*
G01X938014Y486000D02*
X919301D01*
G01X933800Y481000D02*
X916600D01*
G01X923739Y465961D02*
X913040D01*
G01X945932Y528232D02*
X945600Y527900D01*
G01X945932Y529597D02*
Y528232D01*
G01X944859Y530670D02*
X945932Y529597D01*
G01X944859Y535169D02*
Y530670D01*
G01X946132Y536442D02*
X944859Y535169D01*
G01X946132Y537700D02*
Y536442D01*
G01X945600Y538232D02*
X946132Y537700D01*
G01X945600Y546200D02*
Y538232D01*
G01X946132Y546732D02*
X945600Y546200D01*
G01X946132Y548557D02*
Y546732D01*
G01X943232Y551457D02*
X946132Y548557D01*
G01X943232Y555292D02*
Y551457D01*
G01X943897Y555957D02*
X943232Y555292D01*
G01X918421Y587470D02*
X917125Y588766D01*
G01X918421Y584079D02*
Y587470D01*
G01X918800Y583700D02*
X918421Y584079D01*
G01X918800Y575679D02*
Y583700D01*
G01X918421Y575300D02*
X918800Y575679D01*
G01X918421Y574178D02*
Y575300D01*
G01X919421Y573178D02*
X918421Y574178D01*
G01X919421Y568497D02*
Y573178D01*
G01X918571Y567647D02*
X919421Y568497D01*
G01X918571Y555500D02*
Y567647D01*
G01X918521Y546479D02*
Y549200D01*
G01X918800Y546200D02*
X918521Y546479D01*
G01X918800Y537879D02*
Y546200D01*
G01X918521Y537600D02*
X918800Y537879D01*
G01X918521Y536278D02*
Y537600D01*
G01X919221Y535578D02*
X918521Y536278D01*
G01X919221Y530466D02*
Y535578D01*
G01X918571Y529816D02*
X919221Y530466D01*
G01X918571Y528129D02*
Y529816D01*
G01X918800Y527900D02*
X918571Y528129D01*
G01X962360Y535226D02*
Y527840D01*
G01X960629Y536957D02*
X962360Y535226D01*
G01X951732Y530597D02*
X952832Y529497D01*
G01X951732Y535342D02*
Y530597D01*
G01X952632Y536242D02*
X951732Y535342D01*
G01X952632Y537900D02*
Y536242D01*
G01X952200Y538332D02*
X952632Y537900D01*
G01X952200Y546100D02*
Y538332D01*
G01X952632Y546532D02*
X952200Y546100D01*
G01X952632Y548707D02*
Y546532D01*
G01X949232Y552107D02*
X952632Y548707D01*
G01X949232Y554599D02*
Y552107D01*
G01X950590Y555957D02*
X949232Y554599D01*
G01X925132Y528268D02*
X925500Y527900D01*
G01X925132Y530197D02*
Y528268D01*
G01X925632Y530697D02*
X925132Y530197D01*
G01X925632Y534856D02*
Y530697D01*
G01X925032Y535456D02*
X925632Y534856D01*
G01X925032Y537500D02*
Y535456D01*
G01X925500Y537968D02*
X925032Y537500D01*
G01X925500Y545900D02*
Y537968D01*
G01X925032Y546368D02*
X925500Y545900D01*
G01X925032Y549400D02*
Y546368D01*
G01X923518Y550914D02*
X925032Y549400D01*
G01X925732Y554524D02*
X927165Y555957D01*
G01X925732Y552007D02*
Y554524D01*
G01X929082Y548657D02*
X925732Y552007D01*
G01X929082Y546782D02*
Y548657D01*
G01X928800Y546500D02*
X929082Y546782D01*
G01X928800Y537982D02*
Y546500D01*
G01X929082Y537700D02*
X928800Y537982D01*
G01X929082Y536383D02*
Y537700D01*
G01X927932Y535233D02*
X929082Y536383D01*
G01X927932Y530567D02*
Y535233D01*
G01X929032Y529467D02*
X927932Y530567D01*
G01X929032Y528132D02*
Y529467D01*
G01X928800Y527900D02*
X929032Y528132D01*
G01X911778Y587368D02*
X910432Y588714D01*
G01X911821Y587368D02*
X911778D01*
G01X911821Y584779D02*
Y587368D01*
G01X912100Y584500D02*
X911821Y584779D01*
G01X912100Y575879D02*
Y584500D01*
G01X911821Y575600D02*
X912100Y575879D01*
G01X911821Y574079D02*
Y575600D01*
G01X912487Y573413D02*
X911821Y574079D01*
G01X912487Y568163D02*
Y573413D01*
G01X911921Y567597D02*
X912487Y568163D01*
G01X911921Y565979D02*
Y567597D01*
G01X912100Y565800D02*
X911921Y565979D01*
G01X912100Y557879D02*
Y565800D01*
G01X911621Y557400D02*
X912100Y557879D01*
G01X911621Y555457D02*
Y557400D01*
G01X912721Y554357D02*
X911621Y555457D01*
G01X912721Y549957D02*
Y554357D01*
G01X911821Y549057D02*
X912721Y549957D01*
G01X911821Y546679D02*
Y549057D01*
G01X912100Y546400D02*
X911821Y546679D01*
G01X912100Y537979D02*
Y546400D01*
G01X911821Y537700D02*
X912100Y537979D01*
G01X911821Y536278D02*
Y537700D01*
G01X912621Y535478D02*
X911821Y536278D01*
G01X912621Y530542D02*
Y535478D01*
G01X911921Y529842D02*
X912621Y530542D01*
G01X911921Y527879D02*
Y529842D01*
G01X912100Y527700D02*
X911921Y527879D01*
G01X948732Y528068D02*
X948900Y527900D01*
G01X948732Y529797D02*
Y528068D01*
G01X949298Y530363D02*
X948732Y529797D01*
G01X949298Y535501D02*
Y530363D01*
G01X948632Y536167D02*
X949298Y535501D01*
G01X948632Y537700D02*
Y536167D01*
G01X948900Y537968D02*
X948632Y537700D01*
G01X948900Y546300D02*
Y537968D01*
G01X948632Y546568D02*
X948900Y546300D01*
G01X948632Y549568D02*
Y546568D01*
G01X948589Y549568D02*
X948632D01*
G01X947243Y550914D02*
X948589Y549568D01*
G01X922382Y546782D02*
Y548657D01*
G01X922200Y546600D02*
X922382Y546782D01*
G01X922200Y538182D02*
Y546600D01*
G01X922382Y538000D02*
X922200Y538182D01*
G01X922382Y536142D02*
Y538000D01*
G01X921384Y535144D02*
X922382Y536142D01*
G01X921384Y530517D02*
Y535144D01*
G01X922432Y529469D02*
X921384Y530517D01*
G01X922432Y527932D02*
Y529469D01*
G01X922200Y527700D02*
X922432Y527932D01*
G01X955874Y530339D02*
X955382Y529847D01*
G01X955874Y535926D02*
Y530339D01*
G01X955232Y536568D02*
X955874Y535926D01*
G01X955232Y549670D02*
Y536568D01*
G01X953936Y550966D02*
X955232Y549670D01*
G01X953936Y550914D02*
Y550966D01*
G01X929811Y550564D02*
Y550914D01*
G01X931732Y548643D02*
X929811Y550564D01*
G01X931732Y546768D02*
Y548643D01*
G01X932200Y546300D02*
X931732Y546768D01*
G01X932200Y538168D02*
Y546300D01*
G01X931732Y537700D02*
X932200Y538168D01*
G01X931732Y528268D02*
Y537700D01*
G01X932200Y527800D02*
X931732Y528268D01*
G01X915821Y586507D02*
X912421Y589907D01*
G01X915821Y584821D02*
Y586507D01*
G01X915400Y584400D02*
X915821Y584821D01*
G01X915400Y575921D02*
Y584400D01*
G01X915821Y575500D02*
X915400Y575921D01*
G01X915821Y574042D02*
Y575500D01*
G01X914921Y573142D02*
X915821Y574042D01*
G01X914921Y568397D02*
Y573142D01*
G01X916021Y567297D02*
X914921Y568397D01*
G01X916021Y566221D02*
Y567297D01*
G01X915500Y565700D02*
X916021Y566221D01*
G01X915500Y557421D02*
Y565700D01*
G01X916021Y556900D02*
X915500Y557421D01*
G01X916021Y555657D02*
Y556900D01*
G01X915221Y554857D02*
X916021Y555657D01*
G01X915221Y549457D02*
Y554857D01*
G01X915721Y548957D02*
X915221Y549457D01*
G01X915721Y546621D02*
Y548957D01*
G01X915400Y546300D02*
X915721Y546621D01*
G01X915400Y538121D02*
Y546300D01*
G01X915721Y537800D02*
X915400Y538121D01*
G01X915721Y536422D02*
Y537800D01*
G01X915121Y535822D02*
X915721Y536422D01*
G01X915121Y530366D02*
Y535822D01*
G01X916027Y529460D02*
X915121Y530366D01*
G01X916027Y528327D02*
Y529460D01*
G01X915500Y527800D02*
X916027Y528327D01*
G01X953848Y588714D02*
X953936D01*
G01X952162Y590400D02*
X953848Y588714D01*
G01X952162Y592092D02*
Y590400D01*
G01X952337Y592267D02*
X952162Y592092D01*
G01X952337Y594900D02*
Y592267D01*
G01X951225Y596012D02*
X952337Y594900D01*
G01X951225Y597088D02*
Y596012D01*
G01X952237Y598100D02*
X951225Y597088D01*
G01X952237Y599300D02*
Y598100D01*
G01X951225Y600312D02*
X952237Y599300D01*
G01X951225Y601388D02*
Y600312D01*
G01X952362Y602525D02*
X951225Y601388D01*
G01X952362Y603799D02*
Y602525D01*
G01X951662Y604499D02*
X952362Y603799D01*
G01X950590Y604499D02*
X951662D01*
G01X923430Y588714D02*
X923518D01*
G01X921744Y590400D02*
X923430Y588714D01*
G01X921744Y592600D02*
Y590400D01*
G01X922244Y593100D02*
X921744Y592600D01*
G01X922244Y594999D02*
Y593100D01*
G01X921107Y596136D02*
X922244Y594999D01*
G01X921107Y597464D02*
Y596136D01*
G01X922044Y598401D02*
X921107Y597464D01*
G01X922044Y599799D02*
Y598401D01*
G01X921107Y600736D02*
X922044Y599799D01*
G01X921107Y601964D02*
Y600736D01*
G01X922144Y603001D02*
X921107Y601964D01*
G01X922144Y603899D02*
Y603001D01*
G01X921544Y604499D02*
X922144Y603899D01*
G01X920472Y604499D02*
X921544D01*
G01X914851D02*
X913779D01*
G01X915551Y603799D02*
X914851Y604499D01*
G01X915551Y602525D02*
Y603799D01*
G01X914414Y601388D02*
X915551Y602525D01*
G01X914414Y600312D02*
Y601388D01*
G01X915426Y599300D02*
X914414Y600312D01*
G01X915426Y598100D02*
Y599300D01*
G01X914414Y597088D02*
X915426Y598100D01*
G01X914414Y596012D02*
Y597088D01*
G01X915526Y594900D02*
X914414Y596012D01*
G01X915526Y592267D02*
Y594900D01*
G01X915351Y592092D02*
X915526Y592267D01*
G01X915351Y590400D02*
Y592092D01*
G01X917037Y588714D02*
X915351Y590400D01*
G01X917125Y588714D02*
X917037D01*
G01X917125Y588766D02*
Y588714D01*
G01X918767Y595462D02*
X920472Y593757D01*
G01X918767Y605635D02*
Y595462D01*
G01X923432Y610300D02*
X918767Y605635D01*
G01X928037Y590488D02*
X929811Y588714D01*
G01X928037Y592092D02*
Y590488D01*
G01X928944Y592999D02*
X928037Y592092D01*
G01X928944Y594592D02*
Y592999D01*
G01X927800Y595736D02*
X928944Y594592D01*
G01X927800Y597156D02*
Y595736D01*
G01X928644Y598000D02*
X927800Y597156D01*
G01X928644Y599700D02*
Y598000D01*
G01X927800Y600544D02*
X928644Y599700D01*
G01X927800Y601756D02*
Y600544D01*
G01X928744Y602700D02*
X927800Y601756D01*
G01X928744Y603900D02*
Y602700D01*
G01X928145Y604499D02*
X928744Y603900D01*
G01X927165Y604499D02*
X928145D01*
G01X910432Y588714D02*
X910344D01*
G01X942192Y595462D02*
X943897Y593757D01*
G01X942192Y605649D02*
Y595462D01*
G01X947243Y610700D02*
X942192Y605649D01*
G01X925460Y595462D02*
X927165Y593757D01*
G01X925460Y605949D02*
Y595462D01*
G01X929811Y610300D02*
X925460Y605949D01*
G01X947155Y588714D02*
X947243D01*
G01X945469Y590400D02*
X947155Y588714D01*
G01X945469Y592092D02*
Y590400D01*
G01X945644Y592267D02*
X945469Y592092D01*
G01X945644Y594900D02*
Y592267D01*
G01X944532Y596012D02*
X945644Y594900D01*
G01X944532Y597088D02*
Y596012D01*
G01X945544Y598100D02*
X944532Y597088D01*
G01X945544Y599300D02*
Y598100D01*
G01X944532Y600312D02*
X945544Y599300D01*
G01X944532Y601388D02*
Y600312D01*
G01X945669Y602525D02*
X944532Y601388D01*
G01X945669Y603799D02*
Y602525D01*
G01X944969Y604499D02*
X945669Y603799D01*
G01X943897Y604499D02*
X944969D01*
G01X912074Y605649D02*
X917125Y610700D01*
G01X912074Y595462D02*
Y605649D01*
G01X913779Y593757D02*
X912074Y595462D01*
G01X912421Y592399D02*
X913779Y593757D01*
G01X912421Y589907D02*
Y592399D01*
G01X948885Y595462D02*
X950590Y593757D01*
G01X948885Y605649D02*
Y595462D01*
G01X953936Y610700D02*
X948885Y605649D01*
G01X984054Y-1742D02*
X984055Y-1743D01*
G01X984054Y1854D02*
Y-1742D01*
G01X984664Y2464D02*
X984054Y1854D01*
G01X986898Y2464D02*
X984664D01*
G01X987508Y3074D02*
X986898Y2464D01*
G01X987508Y4974D02*
Y3074D01*
G01X986898Y5584D02*
X987508Y4974D01*
G01X984664Y5584D02*
X986898D01*
G01X984054Y6194D02*
X984664Y5584D01*
G01X984054Y9114D02*
Y6194D01*
G01X987440Y12500D02*
X984054Y9114D01*
G01X995400Y12500D02*
X987440D01*
G01X996519Y13619D02*
X995400Y12500D01*
G01X1000151Y13619D02*
X996519D01*
G01X1002500Y15968D02*
X1000151Y13619D01*
G01X1002500Y29900D02*
Y15968D01*
G01X1006246Y33646D02*
X1002500Y29900D01*
G01X977992Y30730D02*
X980708Y28014D01*
G01X977992Y34140D02*
Y30730D01*
G01X985700Y29660D02*
Y53212D01*
G01X984054Y28014D02*
X985700Y29660D01*
G01X975657Y10756D02*
X974015Y9114D01*
G01X975657Y19719D02*
Y10756D01*
G01X978600Y22662D02*
X975657Y19719D01*
G01X978600Y25400D02*
Y22662D01*
G01X979400Y26200D02*
X978600Y25400D01*
G01X988100Y26200D02*
X979400D01*
G01X989135Y27235D02*
X988100Y26200D01*
G01X989135Y30735D02*
Y27235D01*
G01X992487Y34087D02*
X989135Y30735D01*
G01X974015Y9114D02*
Y-4536D01*
G01X1031975Y29124D02*
X1035932Y25167D01*
G01X1031975Y38425D02*
Y29124D01*
G01X979600Y15949D02*
X980708Y17057D01*
G01X979600Y10900D02*
Y15949D01*
G01X978974Y10274D02*
X979600Y10900D01*
G01X978974Y8126D02*
Y10274D01*
G01X979500Y7600D02*
X978974Y8126D01*
G01X979500Y-2300D02*
Y7600D01*
G01X978858Y-2942D02*
X979500Y-2300D01*
G01X978858Y-5589D02*
Y-2942D01*
G01X980708Y-7439D02*
X978858Y-5589D01*
G01X980708Y-9786D02*
Y-7439D01*
G01X985596Y21945D02*
X980708Y17057D01*
G01X989637Y21945D02*
X985596D01*
G01X992400Y24708D02*
X989637Y21945D01*
G01X992400Y29120D02*
Y24708D01*
G01X996180Y32900D02*
X992400Y29120D01*
G01X999060Y34860D02*
X997100Y32900D01*
G01X984055Y-5355D02*
Y-7108D01*
G01X982200Y-3500D02*
X984055Y-5355D01*
G01X982200Y7800D02*
Y-3500D01*
G01X982419Y8019D02*
X982200Y7800D01*
G01X982419Y11287D02*
Y8019D01*
G01X981938Y11768D02*
X982419Y11287D01*
G01X981938Y13650D02*
Y11768D01*
G01X984055Y15767D02*
X981938Y13650D01*
G01X984055Y17057D02*
Y15767D01*
G01X986481Y19483D02*
X984055Y17057D01*
G01X991608Y19483D02*
X986481D01*
G01X999175Y27050D02*
X991608Y19483D01*
G01X999175Y31275D02*
Y27050D01*
G01X1002500Y34600D02*
X999175Y31275D01*
G01X1006246Y36383D02*
Y33646D01*
G01X1013663Y43800D02*
X1006246Y36383D01*
G01X1020156Y43800D02*
X1013663D01*
G01X1023200Y46844D02*
X1020156Y43800D01*
G01X1023200Y50600D02*
Y46844D01*
G01X1021400Y52400D02*
X1023200Y50600D01*
G01X1021400Y75096D02*
Y52400D01*
G01X1020500Y75996D02*
X1021400Y75096D01*
G01X1020500Y79175D02*
Y75996D01*
G01X1021400Y80075D02*
X1020500Y79175D01*
G01X1021400Y88500D02*
Y80075D01*
G01X1022031Y89131D02*
X1021400Y88500D01*
G01X1022031Y96025D02*
Y89131D01*
G01X974015Y83513D02*
Y84599D01*
G01X975335Y82193D02*
X974015Y83513D01*
G01X975335Y75077D02*
Y82193D01*
G01X974015Y73757D02*
X975335Y75077D01*
G01X974885Y92215D02*
Y96685D01*
G01X975900Y91200D02*
X974885Y92215D01*
G01X975900Y89000D02*
Y91200D01*
G01X974015Y87115D02*
X975900Y89000D01*
G01X974015Y84599D02*
Y87115D01*
G01X978970Y35118D02*
X977992Y34140D01*
G01X978970Y52470D02*
Y35118D01*
G01X980708Y54208D02*
X978970Y52470D01*
G01X980708Y54857D02*
Y54208D01*
G01X992548Y91348D02*
Y101848D01*
G01X992288Y91088D02*
X992548Y91348D01*
G01X992288Y88912D02*
Y91088D01*
G01X992548Y88652D02*
X992288Y88912D01*
G01X992548Y86348D02*
Y88652D01*
G01X991800Y85600D02*
X992548Y86348D01*
G01X991800Y75400D02*
Y85600D01*
G01X992461Y74739D02*
X991800Y75400D01*
G01X992461Y72761D02*
Y74739D01*
G01X992294Y72594D02*
X992461Y72761D01*
G01X992294Y69806D02*
Y72594D01*
G01X992461Y69639D02*
X992294Y69806D01*
G01X992461Y64520D02*
Y69639D01*
G01X989185Y61244D02*
X992461Y64520D01*
G01X983044Y61244D02*
X989185D01*
G01X980708Y58908D02*
X983044Y61244D01*
G01X980708Y54857D02*
Y58908D01*
G01X979600Y91072D02*
Y97300D01*
G01X980708Y89964D02*
X979600Y91072D01*
G01X980708Y87626D02*
Y89964D01*
G01X978430Y85348D02*
X980708Y87626D01*
G01X978430Y81517D02*
Y85348D01*
G01X978996Y80951D02*
X978430Y81517D01*
G01X978996Y72017D02*
Y80951D01*
G01X978386Y71407D02*
X978996Y72017D01*
G01X976832Y71407D02*
X978386D01*
G01X976222Y70797D02*
X976832Y71407D01*
G01X976222Y69407D02*
Y70797D01*
G01X976832Y68797D02*
X976222Y69407D01*
G01X979929Y68797D02*
X976832D01*
G01X980708Y68018D02*
X979929Y68797D01*
G01X980708Y65814D02*
Y68018D01*
G01X985700Y53212D02*
X984055Y54857D01*
G01X998583Y94317D02*
Y101383D01*
G01X999300Y93600D02*
X998583Y94317D01*
G01X999300Y91500D02*
Y93600D01*
G01X998900Y91100D02*
X999300Y91500D01*
G01X998900Y89000D02*
Y91100D01*
G01X999300Y88600D02*
X998900Y89000D01*
G01X999300Y85800D02*
Y88600D01*
G01X998900Y85400D02*
X999300Y85800D01*
G01X998900Y83800D02*
Y85400D01*
G01X999054Y83646D02*
X998900Y83800D01*
G01X999054Y72654D02*
Y83646D01*
G01X998800Y72400D02*
X999054Y72654D01*
G01X998800Y69900D02*
Y72400D01*
G01X999161Y69539D02*
X998800Y69900D01*
G01X999161Y63881D02*
Y69539D01*
G01X998300Y63020D02*
X999161Y63881D01*
G01X998300Y59334D02*
Y63020D01*
G01X996036Y57070D02*
X998300Y59334D01*
G01X986168Y57070D02*
X996036D01*
G01X984055Y54957D02*
X986168Y57070D01*
G01X984055Y54857D02*
Y54957D01*
G01X992487Y39623D02*
Y34087D01*
G01X990650Y41460D02*
X992487Y39623D01*
G01X990650Y43180D02*
Y41460D01*
G01X992470Y45000D02*
X990650Y43180D01*
G01X992470Y47870D02*
Y45000D01*
G01X996700Y52100D02*
X992470Y47870D01*
G01X998420Y52100D02*
X996700D01*
G01X999180Y52860D02*
X998420Y52100D01*
G01X999180Y56670D02*
Y52860D01*
G01X1002500Y59990D02*
X999180Y56670D01*
G01X1002500Y69804D02*
Y59990D01*
G01X1006300Y73604D02*
X1002500Y69804D01*
G01X1006300Y79963D02*
Y73604D01*
G01X1002752Y83511D02*
X1006300Y79963D01*
G01X1002752Y85739D02*
Y83511D01*
G01X1002242Y86249D02*
X1002752Y85739D01*
G01X1002242Y88082D02*
Y86249D01*
G01X1002543Y88383D02*
X1002242Y88082D01*
G01X1002543Y90658D02*
Y88383D01*
G01X1002033Y91168D02*
X1002543Y90658D01*
G01X1002033Y100434D02*
Y91168D01*
G01X1025700Y44700D02*
X1031975Y38425D01*
G01X1025700Y80218D02*
Y44700D01*
G01X1023240Y82678D02*
X1025700Y80218D01*
G01X1023240Y87682D02*
Y82678D01*
G01X1024141Y88583D02*
X1023240Y87682D01*
G01X1024141Y96744D02*
Y88583D01*
G01X982882Y45742D02*
X984054Y46914D01*
G01X982882Y39718D02*
Y45742D01*
G01X984055Y38545D02*
X982882Y39718D01*
G01X984055Y35957D02*
Y38545D01*
G01X981353Y49615D02*
X984054Y46914D01*
G01X981353Y51303D02*
Y49615D01*
G01X982350Y52300D02*
X981353Y51303D01*
G01X982350Y57450D02*
Y52300D01*
G01X984200Y59300D02*
X982350Y57450D01*
G01X990900Y59300D02*
X984200D01*
G01X995714Y64114D02*
X990900Y59300D01*
G01X995714Y69714D02*
Y64114D01*
G01X996100Y70100D02*
X995714Y69714D01*
G01X996100Y72100D02*
Y70100D01*
G01X995800Y72400D02*
X996100Y72100D01*
G01X995800Y83900D02*
Y72400D01*
G01X995900Y84000D02*
X995800Y83900D01*
G01X995900Y85500D02*
Y84000D01*
G01X995641Y85759D02*
X995900Y85500D01*
G01X995641Y88641D02*
Y85759D01*
G01X995900Y88900D02*
X995641Y88641D01*
G01X995900Y91100D02*
Y88900D01*
G01X995600Y91400D02*
X995900Y91100D01*
G01X995600Y93461D02*
Y91400D01*
G01X996139Y94000D02*
X995600Y93461D01*
G01X996139Y119279D02*
Y94000D01*
G01X982800Y88647D02*
X984055Y87392D01*
G01X982800Y91000D02*
Y88647D01*
G01X982000Y91800D02*
X982800Y91000D01*
G01X982000Y95736D02*
Y91800D01*
G01X982881Y74931D02*
X984055Y73757D01*
G01X982881Y86218D02*
Y74931D01*
G01X984055Y87392D02*
X982881Y86218D01*
G01X984055Y94369D02*
X985700Y96014D01*
G01X984055Y92757D02*
Y94369D01*
G01X985400Y91412D02*
X984055Y92757D01*
G01X985400Y89000D02*
Y91412D01*
G01X985966Y88434D02*
X985400Y89000D01*
G01X985966Y86466D02*
Y88434D01*
G01X985600Y86100D02*
X985966Y86466D01*
G01X985600Y83800D02*
Y86100D01*
G01X985782Y83618D02*
X985600Y83800D01*
G01X985782Y67542D02*
Y83618D01*
G01X984054Y65814D02*
X985782Y67542D01*
G01X989100Y93600D02*
Y101900D01*
G01X988600Y93100D02*
X989100Y93600D01*
G01X988600Y91800D02*
Y93100D01*
G01X989500Y90900D02*
X988600Y91800D01*
G01X989500Y88900D02*
Y90900D01*
G01X988900Y88300D02*
X989500Y88900D01*
G01X988900Y86400D02*
Y88300D01*
G01X989500Y85800D02*
X988900Y86400D01*
G01X989500Y75700D02*
Y85800D01*
G01X989015Y75215D02*
X989500Y75700D01*
G01X989015Y72485D02*
Y75215D01*
G01X989500Y72000D02*
X989015Y72485D01*
G01X989500Y67316D02*
Y72000D01*
G01X989121Y66937D02*
X989500Y67316D01*
G01X989121Y64605D02*
Y66937D01*
G01X988017Y63501D02*
X989121Y64605D01*
G01X978848Y63501D02*
X988017D01*
G01X976151Y60804D02*
X978848Y63501D01*
G01X976151Y56751D02*
Y60804D01*
G01X975650Y56250D02*
X976151Y56751D01*
G01X975650Y50850D02*
Y56250D01*
G01X974015Y49215D02*
X975650Y50850D01*
G01X974015Y46914D02*
Y49215D01*
G01Y35957D02*
Y46914D01*
G01X1030200Y78600D02*
Y113644D01*
G01X1033200Y75600D02*
X1030200Y78600D01*
G01X1033200Y74300D02*
Y75600D01*
G01X1031900Y73000D02*
X1033200Y74300D01*
G01X1031900Y64886D02*
Y73000D01*
G01X1035986Y60800D02*
X1031900Y64886D01*
G01X1032300Y80872D02*
Y114374D01*
G01X1034072Y79100D02*
X1032300Y80872D01*
G01X997100Y32900D02*
X996180D01*
G01X999060Y48460D02*
Y34860D01*
G01X1000300Y49700D02*
X999060Y48460D01*
G01X1001300Y49700D02*
X1000300D01*
G01X1005940Y54340D02*
X1001300Y49700D01*
G01X1005940Y61540D02*
Y54340D01*
G01X1011466Y67066D02*
X1005940Y61540D01*
G01X1011466Y73188D02*
Y67066D01*
G01X1008634Y76020D02*
X1011466Y73188D01*
G01X1008634Y83034D02*
Y76020D01*
G01X1009526Y83926D02*
X1008634Y83034D01*
G01X1009526Y96586D02*
Y83926D01*
G01X1002500Y37890D02*
Y34600D01*
G01X1009200Y44590D02*
X1002500Y37890D01*
G01X1009200Y47844D02*
Y44590D01*
G01X1014456Y53100D02*
X1009200Y47844D01*
G01X1018296Y53100D02*
X1014456D01*
G01X1019400Y54204D02*
X1018296Y53100D01*
G01X1019400Y74251D02*
Y54204D01*
G01X1018500Y75151D02*
X1019400Y74251D01*
G01X1018500Y80748D02*
Y75151D01*
G01X1019400Y81648D02*
X1018500Y80748D01*
G01X1019400Y88941D02*
Y81648D01*
G01X1020175Y89716D02*
X1019400Y88941D01*
G01X1020175Y93186D02*
Y89716D01*
G01X1013476Y99893D02*
X1020175Y93186D01*
G01X1033300Y45400D02*
X1037427Y41273D01*
G01X1033300Y50250D02*
Y45400D01*
G01X1028500Y55050D02*
X1033300Y50250D01*
G01X1028500Y71900D02*
Y55050D01*
G01X1027700Y72700D02*
X1028500Y71900D01*
G01X1027700Y84500D02*
Y72700D01*
G01X1027000Y85200D02*
X1027700Y84500D01*
G01X1027000Y98028D02*
Y85200D01*
G01X1030926Y123574D02*
X1048900Y105600D01*
G01X1030926Y190630D02*
Y123574D01*
G01X1015687Y102369D02*
X1022031Y96025D01*
G01X1015687Y198554D02*
Y102369D01*
G01X990596Y132957D02*
Y200519D01*
G01X975000Y117361D02*
X990596Y132957D01*
G01X975000Y109750D02*
Y117361D01*
G01X978950Y105800D02*
X975000Y109750D01*
G01X978950Y100750D02*
Y105800D01*
G01X974885Y96685D02*
X978950Y100750D01*
G01X1001796Y127766D02*
Y199802D01*
G01X994139Y120109D02*
X1001796Y127766D01*
G01X994139Y103439D02*
Y120109D01*
G01X992548Y101848D02*
X994139Y103439D01*
G01X992596Y132128D02*
Y199608D01*
G01X979400Y118932D02*
X992596Y132128D01*
G01X979400Y108250D02*
Y118932D01*
G01X981050Y106600D02*
X979400Y108250D01*
G01X981050Y98750D02*
Y106600D01*
G01X979600Y97300D02*
X981050Y98750D01*
G01X1005796Y124806D02*
Y200081D01*
G01X1003266Y122276D02*
X1005796Y124806D01*
G01X1003266Y121144D02*
Y122276D01*
G01X1006226Y118184D02*
X1003266Y121144D01*
G01X1006226Y117052D02*
Y118184D01*
G01X1005095Y115921D02*
X1006226Y117052D01*
G01X1003963Y115921D02*
X1005095D01*
G01X1000858Y119026D02*
X1003963Y115921D01*
G01X999726Y119026D02*
X1000858D01*
G01X998294Y117594D02*
X999726Y119026D01*
G01X998294Y116506D02*
Y117594D01*
G01X1000750Y114050D02*
X998294Y116506D01*
G01X1000750Y112950D02*
Y114050D01*
G01X999826Y112026D02*
X1000750Y112950D01*
G01X999826Y102626D02*
Y112026D01*
G01X998583Y101383D02*
X999826Y102626D01*
G01X1003026Y101427D02*
X1002033Y100434D01*
G01X1003026Y110024D02*
Y101427D01*
G01X1003657Y110655D02*
X1003026Y110024D01*
G01X1005465Y110655D02*
X1003657D01*
G01X1006226Y109894D02*
X1005465Y110655D01*
G01X1006226Y104434D02*
Y109894D01*
G01X1007026Y103634D02*
X1006226Y104434D01*
G01X1008626Y103634D02*
X1007026D01*
G01X1009426Y104434D02*
X1008626Y103634D01*
G01X1009426Y199064D02*
Y104434D01*
G01X1017726Y103159D02*
X1024141Y96744D01*
G01X1017726Y198724D02*
Y103159D01*
G01X1003796Y126936D02*
X996139Y119279D01*
G01X1003796Y200166D02*
Y126936D01*
G01X983700Y97436D02*
X982000Y95736D01*
G01X983700Y106899D02*
Y97436D01*
G01X981700Y108899D02*
X983700Y106899D01*
G01X981700Y118403D02*
Y108899D01*
G01X994596Y131299D02*
X981700Y118403D01*
G01X994596Y199498D02*
Y131299D01*
G01X996596Y130470D02*
Y199062D01*
G01X983800Y117674D02*
X996596Y130470D01*
G01X983800Y116369D02*
Y117674D01*
G01X984600Y115569D02*
X983800Y116369D01*
G01X988678Y115569D02*
X984600D01*
G01X989476Y114771D02*
X988678Y115569D01*
G01X989476Y112589D02*
Y114771D01*
G01X988674Y111787D02*
X989476Y112589D01*
G01X984600Y111787D02*
X988674D01*
G01X983800Y110987D02*
X984600Y111787D01*
G01X983800Y109480D02*
Y110987D01*
G01X986400Y106880D02*
X983800Y109480D01*
G01X986400Y104900D02*
Y106880D01*
G01X985700Y104200D02*
X986400Y104900D01*
G01X985700Y96014D02*
Y104200D01*
G01X999796Y128596D02*
Y199305D01*
G01X992100Y120900D02*
X999796Y128596D01*
G01X992100Y111101D02*
Y120900D01*
G01X991300Y110301D02*
X992100Y111101D01*
G01X990800Y110301D02*
X991300D01*
G01X990000Y109501D02*
X990800Y110301D01*
G01X990000Y107901D02*
Y109501D01*
G01X990800Y107101D02*
X990000Y107901D01*
G01X991300Y107101D02*
X990800D01*
G01X992100Y106301D02*
X991300Y107101D01*
G01X992100Y104900D02*
Y106301D01*
G01X989100Y101900D02*
X992100Y104900D01*
G01X1023726Y120118D02*
Y197381D01*
G01X1025927Y117917D02*
X1023726Y120118D01*
G01X1025927Y116785D02*
Y117917D01*
G01X1024787Y115645D02*
X1025927Y116785D01*
G01X1024787Y114513D02*
Y115645D01*
G01X1025918Y113382D02*
X1024787Y114513D01*
G01X1027050Y113382D02*
X1025918D01*
G01X1028190Y114522D02*
X1027050Y113382D01*
G01X1029322Y114522D02*
X1028190D01*
G01X1030200Y113644D02*
X1029322Y114522D01*
G01X1025726Y120948D02*
Y196930D01*
G01X1032300Y114374D02*
X1025726Y120948D01*
G01X974379Y100700D02*
X973884D01*
G01X976700Y103021D02*
X974379Y100700D01*
G01X1011426Y98486D02*
X1009526Y96586D01*
G01X1011426Y198627D02*
Y98486D01*
G01X1013476Y198651D02*
Y99893D01*
G01X1019726Y105302D02*
X1027000Y98028D01*
G01X1019726Y198554D02*
Y105302D01*
G01X1028926Y122274D02*
X1045270Y105930D01*
G01X1028926Y191223D02*
Y122274D01*
G01X980326Y191655D02*
Y195421D01*
G01X978000Y195407D02*
X977976Y195431D01*
G01X978000Y192865D02*
Y195407D01*
G01X985326Y189583D02*
Y194591D01*
G01X982826Y190620D02*
Y194591D01*
G01X1020362Y401412D02*
Y499104D01*
G01X1015275Y396325D02*
X1020362Y401412D01*
G01X993962Y398763D02*
Y475598D01*
G01X991500Y396301D02*
X993962Y398763D01*
G01X1011900Y398700D02*
X1016362Y403162D01*
G01X1018362Y402262D02*
X1013754Y397654D01*
G01X1018362Y499933D02*
Y402262D01*
G01X991962Y402187D02*
Y475304D01*
G01X991961Y402186D02*
X991962Y402187D01*
G01X991961Y401161D02*
Y402186D01*
G01X1022362Y400562D02*
Y498275D01*
G01X1016650Y394850D02*
X1022362Y400562D01*
G01X1029138Y394761D02*
X1034250Y399873D01*
G01X1033500Y383100D02*
X1034200Y383800D01*
G01X1032385Y380709D02*
X1033500Y381824D01*
G01X997962Y402138D02*
Y476840D01*
G01X999500Y400600D02*
X997962Y402138D01*
G01X999500Y399300D02*
Y400600D01*
G01X997962Y397762D02*
X999500Y399300D01*
G01X997962Y396007D02*
Y397762D01*
G01X1000700Y402900D02*
Y478450D01*
G01X1000800Y402800D02*
X1000700Y402900D01*
G01X1024362Y399661D02*
Y496862D01*
G01X1019301Y394600D02*
X1024362Y399661D01*
G01X995962Y395968D02*
Y476122D01*
G01X1009000Y401500D02*
X1012362Y404862D01*
G01X1014362Y404012D02*
X1010575Y400225D01*
G01X1032084Y394284D02*
X1035800Y398000D01*
G01X1031800Y391300D02*
X1037600Y397100D01*
G01X1031800Y390600D02*
Y391300D01*
G01X1030500Y389300D02*
X1031800Y390600D01*
G01X1030500Y387700D02*
Y389300D01*
G01X1031034Y387166D02*
X1030500Y387700D01*
G01X1031034Y386034D02*
Y387166D01*
G01X1030500Y385500D02*
X1031034Y386034D01*
G01X1030500Y383800D02*
Y385500D01*
G01X1030900Y383400D02*
X1030500Y383800D01*
G01X1030900Y381899D02*
Y383400D01*
G01X1029005Y380004D02*
X1030900Y381899D01*
G01X1029005Y378760D02*
Y380004D01*
G01X980856Y405851D02*
Y418744D01*
G01X1009162Y407781D02*
Y489438D01*
G01X1016362Y403162D02*
Y506598D01*
G01X975483Y406172D02*
Y416917D01*
G01X1029562Y410706D02*
Y494062D01*
G01X1032762Y411204D02*
Y483891D01*
G01X1012362Y404862D02*
Y490809D01*
G01X1005162Y407821D02*
Y487138D01*
G01X1003162Y407821D02*
Y485738D01*
G01X1014362Y501144D02*
Y404012D01*
G01X1007162Y488238D02*
Y407727D01*
G01X978356Y405699D02*
Y417644D01*
G01X972983Y406172D02*
Y415817D01*
G01X1027562Y410841D02*
Y495262D01*
G01X1023400Y526001D02*
Y548900D01*
G01X1022501Y525102D02*
X1023400Y526001D01*
G01X1022501Y501243D02*
Y525102D01*
G01X1020362Y499104D02*
X1022501Y501243D01*
G01X975656Y519456D02*
Y532678D01*
G01X975300Y519100D02*
X975656Y519456D01*
G01X975300Y517100D02*
Y519100D01*
G01X977362Y515038D02*
X975300Y517100D01*
G01X977362Y512792D02*
Y515038D01*
G01X976700Y512130D02*
X977362Y512792D01*
G01X976700Y507617D02*
Y512130D01*
G01X976695Y507605D02*
X976700Y507617D01*
G01X980500Y503800D02*
X976695Y507605D01*
G01X980500Y489060D02*
Y503800D01*
G01X993962Y475598D02*
X980500Y489060D01*
G01X973430Y497170D02*
X976530D01*
G01X999150Y526108D02*
Y533050D01*
G01X999760Y525498D02*
X999150Y526108D01*
G01X1001122Y525498D02*
X999760D01*
G01X1001775Y524845D02*
X1001122Y525498D01*
G01X1001775Y523455D02*
Y524845D01*
G01X1001208Y522888D02*
X1001775Y523455D01*
G01X999904Y522888D02*
X1001208D01*
G01X999300Y522284D02*
X999904Y522888D01*
G01X999300Y516800D02*
Y522284D01*
G01X998900Y516400D02*
X999300Y516800D01*
G01X998900Y514400D02*
Y516400D01*
G01X999400Y513900D02*
X998900Y514400D01*
G01X999400Y511900D02*
Y513900D01*
G01X998669Y511169D02*
X999400Y511900D01*
G01X998669Y509165D02*
Y511169D01*
G01X1003276Y504558D02*
X998669Y509165D01*
G01X1003276Y495324D02*
Y504558D01*
G01X1009162Y489438D02*
X1003276Y495324D01*
G01X1018469Y508705D02*
Y527168D01*
G01X1016362Y506598D02*
X1018469Y508705D01*
G01X1020501Y502072D02*
X1018362Y499933D01*
G01X1020501Y526001D02*
Y502072D01*
G01X1021400Y526900D02*
X1020501Y526001D01*
G01X972300Y519500D02*
Y530300D01*
G01X972500Y519300D02*
X972300Y519500D01*
G01X972500Y516900D02*
Y519300D01*
G01X972200Y516600D02*
X972500Y516900D01*
G01X972200Y514300D02*
Y516600D01*
G01X974015Y512485D02*
X972200Y514300D01*
G01X974015Y509999D02*
Y512485D01*
G01Y507921D02*
Y509999D01*
G01X974970Y506966D02*
X974015Y507921D01*
G01X974970Y506104D02*
Y506966D01*
G01X974021Y505155D02*
X974970Y506104D01*
G01X974021Y504276D02*
Y505155D01*
G01X974722Y503575D02*
X974021Y504276D01*
G01X975567Y503575D02*
X974722D01*
G01X976480Y504488D02*
X975567Y503575D01*
G01X977395Y504488D02*
X976480D01*
G01X978500Y503383D02*
X977395Y504488D01*
G01X978500Y488766D02*
Y503383D01*
G01X991962Y475304D02*
X978500Y488766D01*
G01X1026900Y502813D02*
Y535600D01*
G01X1022362Y498275D02*
X1026900Y502813D01*
G01X982400Y519400D02*
Y530402D01*
G01X982049Y519049D02*
X982400Y519400D01*
G01X982049Y516951D02*
Y519049D01*
G01X983100Y515900D02*
X982049Y516951D01*
G01X983100Y513747D02*
Y515900D01*
G01X984055Y512792D02*
X983100Y513747D01*
G01X983200Y511937D02*
X984055Y512792D01*
G01X983200Y509300D02*
Y511937D01*
G01X984500Y508000D02*
X983200Y509300D01*
G01X984500Y490302D02*
Y508000D01*
G01X997962Y476840D02*
X984500Y490302D01*
G01X985400Y516812D02*
X984055Y518157D01*
G01X985400Y514400D02*
Y516812D01*
G01X985900Y513900D02*
X985400Y514400D01*
G01X985900Y511600D02*
Y513900D01*
G01X985300Y511000D02*
X985900Y511600D01*
G01X985300Y509500D02*
Y511000D01*
G01X990049Y504751D02*
X985300Y509500D01*
G01X990049Y499555D02*
Y504751D01*
G01X986749Y496255D02*
X990049Y499555D01*
G01X986749Y494655D02*
Y496255D01*
G01X987917Y493487D02*
X986749Y494655D01*
G01X988709Y493487D02*
X987917D01*
G01X989840Y494618D02*
X988709Y493487D01*
G01X990940Y494618D02*
X989840D01*
G01X992071Y493487D02*
X990940Y494618D01*
G01X992071Y492213D02*
Y493487D01*
G01X989190Y489332D02*
X992071Y492213D01*
G01X989190Y488233D02*
Y489332D01*
G01X990321Y487102D02*
X989190Y488233D01*
G01X991486Y487102D02*
X990321D01*
G01X994321Y489937D02*
X991486Y487102D01*
G01X995600Y489937D02*
X994321D01*
G01X996731Y488806D02*
X995600Y489937D01*
G01X996731Y487821D02*
Y488806D01*
G01X993540Y484630D02*
X996731Y487821D01*
G01X993540Y483616D02*
Y484630D01*
G01X994671Y482485D02*
X993540Y483616D01*
G01X995921Y482485D02*
X994671D01*
G01X998419Y484983D02*
X995921Y482485D01*
G01X999668Y484983D02*
X998419D01*
G01X1000700Y483951D02*
X999668Y484983D01*
G01X1000700Y482395D02*
Y483951D01*
G01X999667Y481362D02*
X1000700Y482395D01*
G01X999667Y479483D02*
Y481362D01*
G01X1000700Y478450D02*
X999667Y479483D01*
G01X984055Y518157D02*
Y529013D01*
G01X1029562Y494062D02*
X1040154Y504654D01*
G01X1032762Y483891D02*
X1050983Y502112D01*
G01X1029200Y501700D02*
Y535400D01*
G01X1024362Y496862D02*
X1029200Y501700D01*
G01X980345Y515727D02*
Y528651D01*
G01X980708Y515364D02*
X980345Y515727D01*
G01X980708Y513108D02*
Y515364D01*
G01X978800Y511200D02*
X980708Y513108D01*
G01X978800Y509500D02*
Y511200D01*
G01X982500Y505800D02*
X978800Y509500D01*
G01X982500Y489584D02*
Y505800D01*
G01X995962Y476122D02*
X982500Y489584D01*
G01X1006300Y524226D02*
Y527100D01*
G01X1002282Y520208D02*
X1006300Y524226D01*
G01X1002282Y517284D02*
Y520208D01*
G01X1002885Y516681D02*
X1002282Y517284D01*
G01X1002885Y514513D02*
Y516681D01*
G01X1002051Y513679D02*
X1002885Y514513D01*
G01X1002051Y511088D02*
Y513679D01*
G01X1006300Y506839D02*
X1002051Y511088D01*
G01X1006300Y496871D02*
Y506839D01*
G01X1012362Y490809D02*
X1006300Y496871D01*
G01X992400Y519600D02*
Y531808D01*
G01X992600Y519400D02*
X992400Y519600D01*
G01X992600Y517000D02*
Y519400D01*
G01X992200Y516600D02*
X992600Y517000D01*
G01X992200Y514400D02*
Y516600D01*
G01X992700Y513900D02*
X992200Y514400D01*
G01X992700Y511700D02*
Y513900D01*
G01X992200Y511200D02*
X992700Y511700D01*
G01X992200Y508800D02*
Y511200D01*
G01X994000Y507000D02*
X992200Y508800D01*
G01X994000Y498300D02*
Y507000D01*
G01X1005162Y487138D02*
X994000Y498300D01*
G01X989129Y519229D02*
Y529871D01*
G01X988600Y518700D02*
X989129Y519229D01*
G01X988600Y517300D02*
Y518700D01*
G01X989500Y516400D02*
X988600Y517300D01*
G01X989500Y514500D02*
Y516400D01*
G01X988900Y513900D02*
X989500Y514500D01*
G01X988900Y511500D02*
Y513900D01*
G01X989300Y511100D02*
X988900Y511500D01*
G01X989300Y508000D02*
Y511100D01*
G01X992000Y505300D02*
X989300Y508000D01*
G01X992000Y496900D02*
Y505300D01*
G01X1003162Y485738D02*
X992000Y496900D01*
G01X1006086Y509420D02*
X1014362Y501144D01*
G01X1006086Y520754D02*
Y509420D01*
G01X1008300Y522968D02*
X1006086Y520754D01*
G01X1008300Y526800D02*
Y522968D01*
G01X999972Y495428D02*
X1007162Y488238D01*
G01X999972Y496560D02*
Y495428D01*
G01X1001242Y497830D02*
X999972Y496560D01*
G01X1001242Y499059D02*
Y497830D01*
G01X1000111Y500190D02*
X1001242Y499059D01*
G01X999076Y500190D02*
X1000111D01*
G01X997874Y498988D02*
X999076Y500190D01*
G01X996626Y498988D02*
X997874D01*
G01X995800Y499814D02*
X996626Y498988D01*
G01X995800Y502973D02*
Y499814D01*
G01X996410Y503583D02*
X995800Y502973D01*
G01X997907Y503583D02*
X996410D01*
G01X998478Y504154D02*
X997907Y503583D01*
G01X998478Y505544D02*
Y504154D01*
G01X997829Y506193D02*
X998478Y505544D01*
G01X996410Y506193D02*
X997829D01*
G01X995800Y506803D02*
X996410Y506193D01*
G01X995800Y508800D02*
Y506803D01*
G01X996400Y509400D02*
X995800Y508800D01*
G01X996400Y510800D02*
Y509400D01*
G01X995537Y511663D02*
X996400Y510800D01*
G01X995537Y513837D02*
Y511663D01*
G01X996098Y514398D02*
X995537Y513837D01*
G01X996098Y516502D02*
Y514398D01*
G01X995712Y516888D02*
X996098Y516502D01*
G01X995712Y530388D02*
Y516888D01*
G01X1031300Y499000D02*
Y535200D01*
G01X1027562Y495262D02*
X1031300Y499000D01*
G01X1004133Y588194D02*
X1002411Y589916D01*
G01X1004133Y585722D02*
Y588194D01*
G01X1007233Y582622D02*
X1004133Y585722D01*
G01X1016878Y582622D02*
X1007233D01*
G01X1025200Y574300D02*
X1016878Y582622D01*
G01X1025200Y550700D02*
Y574300D01*
G01X1023400Y548900D02*
X1025200Y550700D01*
G01X977362Y534384D02*
Y536957D01*
G01X975656Y532678D02*
X977362Y534384D01*
G01X985902Y554010D02*
X984055Y555857D01*
G01X988327Y554010D02*
X985902D01*
G01X988937Y553400D02*
X988327Y554010D01*
G01X988937Y552295D02*
Y553400D01*
G01X989526Y551706D02*
X988937Y552295D01*
G01X990916Y551706D02*
X989526D01*
G01X991547Y552337D02*
X990916Y551706D01*
G01X991547Y553400D02*
Y552337D01*
G01X992157Y554010D02*
X991547Y553400D01*
G01X994757Y554010D02*
X992157D01*
G01X995799Y552968D02*
X994757Y554010D01*
G01X995799Y544981D02*
Y552968D01*
G01X999062Y541718D02*
X995799Y544981D01*
G01X999062Y533138D02*
Y541718D01*
G01X999150Y533050D02*
X999062Y533138D01*
G01X984055Y566813D02*
X984054Y566814D01*
G01X984055Y555857D02*
Y566813D01*
G01X995757Y587043D02*
X994200Y588600D01*
G01X995757Y581929D02*
Y587043D01*
G01X1000910Y576776D02*
X995757Y581929D01*
G01X1017891Y576776D02*
X1000910D01*
G01X1019400Y575267D02*
X1017891Y576776D01*
G01X1019400Y558700D02*
Y575267D01*
G01X1021600Y556500D02*
X1019400Y558700D01*
G01X1021600Y551900D02*
Y556500D01*
G01X1019400Y549700D02*
X1021600Y551900D01*
G01X1019400Y528099D02*
Y549700D01*
G01X1018469Y527168D02*
X1019400Y528099D01*
G01X1021400Y549300D02*
Y526900D01*
G01X1023300Y551200D02*
X1021400Y549300D01*
G01X1023300Y557200D02*
Y551200D01*
G01X1021400Y559100D02*
X1023300Y557200D01*
G01X1021400Y575822D02*
Y559100D01*
G01X1016210Y581012D02*
X1021400Y575822D01*
G01X1001545Y581012D02*
X1016210D01*
G01X997441Y585116D02*
X1001545Y581012D01*
G01X997441Y585722D02*
Y585116D01*
G01Y590841D02*
Y585722D01*
G01X974015Y534264D02*
Y536957D01*
G01X973000Y533249D02*
X974015Y534264D01*
G01X973000Y531000D02*
Y533249D01*
G01X972300Y530300D02*
X973000Y531000D01*
G01X1029700Y574612D02*
X1035371Y580283D01*
G01X1029700Y538400D02*
Y574612D01*
G01X1026900Y535600D02*
X1029700Y538400D01*
G01X982148Y535050D02*
X984055Y536957D01*
G01X982148Y534272D02*
Y535050D01*
G01X981350Y533474D02*
X982148Y534272D01*
G01X979333Y533474D02*
X981350D01*
G01X978723Y532864D02*
X979333Y533474D01*
G01X978723Y531874D02*
Y532864D01*
G01X979333Y531264D02*
X978723Y531874D01*
G01X981538Y531264D02*
X979333D01*
G01X982400Y530402D02*
X981538Y531264D01*
G01X984055Y529013D02*
X984054Y529014D01*
G01X1031400Y573600D02*
X1035600Y577800D01*
G01X1031400Y537600D02*
Y573600D01*
G01X1029200Y535400D02*
X1031400Y537600D01*
G01X980345Y528651D02*
X980708Y529014D01*
G01X975642Y587434D02*
Y595346D01*
G01X977362Y585714D02*
X975642Y587434D01*
G01X981800Y581276D02*
X977362Y585714D01*
G01X981800Y578000D02*
Y581276D01*
G01X982800Y577000D02*
X981800Y578000D01*
G01X988127Y577000D02*
X982800D01*
G01X989041Y576086D02*
X988127Y577000D01*
G01X989041Y573759D02*
Y576086D01*
G01X993500Y569300D02*
X989041Y573759D01*
G01X994600Y569300D02*
X993500D01*
G01X995712Y568188D02*
X994600Y569300D01*
G01X995712Y560588D02*
Y568188D01*
G01X999149Y557151D02*
X995712Y560588D01*
G01X999149Y554419D02*
Y557151D01*
G01X1002499Y551069D02*
X999149Y554419D01*
G01X1002499Y544336D02*
Y551069D01*
G01X1005762Y541073D02*
X1002499Y544336D01*
G01X1005762Y536166D02*
Y541073D01*
G01X1005202Y535606D02*
X1005762Y536166D01*
G01X1005202Y530918D02*
Y535606D01*
G01X1005760Y530360D02*
X1005202Y530918D01*
G01X1005760Y527640D02*
Y530360D01*
G01X1006300Y527100D02*
X1005760Y527640D01*
G01X978991Y554140D02*
X980708Y555857D01*
G01X978991Y546841D02*
Y554140D01*
G01X982496Y543336D02*
X978991Y546841D01*
G01X984356Y543336D02*
X982496D01*
G01X989026Y538666D02*
X984356Y543336D01*
G01X989026Y535574D02*
Y538666D01*
G01X990000Y534600D02*
X989026Y535574D01*
G01X990000Y534208D02*
Y534600D01*
G01X992400Y531808D02*
X990000Y534208D01*
G01X980708Y555857D02*
Y566814D01*
G01X974015Y569685D02*
Y574757D01*
G01X975642Y568058D02*
X974015Y569685D01*
G01X975642Y564343D02*
Y568058D01*
G01X976453Y563532D02*
X975642Y564343D01*
G01X976453Y558433D02*
Y563532D01*
G01X975642Y557622D02*
X976453Y558433D01*
G01X975642Y554151D02*
Y557622D01*
G01X974015Y552524D02*
X975642Y554151D01*
G01X974015Y547914D02*
Y552524D01*
G01X982629Y539300D02*
X974015Y547914D01*
G01X984174Y539300D02*
X982629D01*
G01X985721Y537753D02*
X984174Y539300D01*
G01X985721Y535421D02*
Y537753D01*
G01X986749Y534393D02*
X985721Y535421D01*
G01X986749Y532251D02*
Y534393D01*
G01X989129Y529871D02*
X986749Y532251D01*
G01X1009500Y528000D02*
X1008300Y526800D01*
G01X1009500Y530313D02*
Y528000D01*
G01X1010300Y531113D02*
X1009500Y530313D01*
G01X1012100Y531113D02*
X1010300D01*
G01X1013116Y532129D02*
X1012100Y531113D01*
G01X1013116Y533709D02*
Y532129D01*
G01X1012304Y534521D02*
X1013116Y533709D01*
G01X1011004Y534521D02*
X1012304D01*
G01X1009223Y536302D02*
X1011004Y534521D01*
G01X1009223Y559162D02*
Y536302D01*
G01X1005810Y562575D02*
X1009223Y559162D01*
G01X1004948Y562575D02*
X1005810D01*
G01X1003861Y561488D02*
X1004948Y562575D01*
G01X1002999Y561488D02*
X1003861D01*
G01X1002015Y562472D02*
X1002999Y561488D01*
G01X1002015Y563334D02*
Y562472D01*
G01X1003102Y564421D02*
X1002015Y563334D01*
G01X1003102Y565283D02*
Y564421D01*
G01X1002426Y565959D02*
X1003102Y565283D01*
G01X1002426Y568283D02*
Y565959D01*
G01X998909Y571800D02*
X1002426Y568283D01*
G01X997528Y571800D02*
X998909D01*
G01X995741Y573587D02*
X997528Y571800D01*
G01X995741Y576232D02*
Y573587D01*
G01X992234Y579739D02*
X995741Y576232D01*
G01X987874Y579739D02*
X992234D01*
G01X986863Y580750D02*
X987874Y579739D01*
G01X986863Y582114D02*
Y580750D01*
G01X987688Y582939D02*
X986863Y582114D01*
G01X991262Y582939D02*
X987688D01*
G01X992479Y584156D02*
X991262Y582939D01*
G01X992479Y586487D02*
Y584156D01*
G01X991230Y587736D02*
X992479Y586487D01*
G01X982400Y587736D02*
X991230D01*
G01X980708Y589428D02*
X982400Y587736D01*
G01X981725Y550243D02*
X984054Y547914D01*
G01X981725Y554238D02*
Y550243D01*
G01X982400Y554913D02*
X981725Y554238D01*
G01X982400Y567700D02*
Y554913D01*
G01X982165Y567935D02*
X982400Y567700D01*
G01X982165Y572867D02*
Y567935D01*
G01X984055Y574757D02*
X982165Y572867D01*
G01X994900Y531200D02*
X995712Y530388D01*
G01X994900Y532200D02*
Y531200D01*
G01X992459Y534641D02*
X994900Y532200D01*
G01X992459Y539509D02*
Y534641D01*
G01X984054Y547914D02*
X992459Y539509D01*
G01X1031300Y535200D02*
X1037847Y541747D01*
G01X1004133Y610067D02*
Y612358D01*
G01X1005937Y608263D02*
X1004133Y610067D01*
G01X1005937Y606237D02*
Y608263D01*
G01X1002411Y602711D02*
X1005937Y606237D01*
G01X1002411Y589916D02*
Y602711D01*
G01X985891Y591821D02*
X984055Y593657D01*
G01X989979Y591821D02*
X985891D01*
G01X993200Y588600D02*
X989979Y591821D01*
G01X994200Y588600D02*
X993200D01*
G01X984055Y593657D02*
Y607292D01*
G01X995712Y592570D02*
X997441Y590841D01*
G01X995712Y595936D02*
Y592570D01*
G01X998200Y598424D02*
X995712Y595936D01*
G01X998200Y605000D02*
Y598424D01*
G01X999417Y606217D02*
X998200Y605000D01*
G01X999417Y608283D02*
Y606217D01*
G01X997441Y610259D02*
X999417Y608283D01*
G01X997441Y612357D02*
Y610259D01*
G01X977362Y610038D02*
Y612457D01*
G01X973623Y606299D02*
X977362Y610038D01*
G01X973269Y606299D02*
X973623D01*
G01X972100Y605130D02*
X973269Y606299D01*
G01X972100Y598888D02*
Y605130D01*
G01X975642Y595346D02*
X972100Y598888D01*
G01X980708Y593657D02*
Y589428D01*
G01Y597693D02*
Y593657D01*
G01X980160Y598241D02*
X980708Y597693D01*
G01X977930Y598241D02*
X980160D01*
G01X977270Y598901D02*
X977930Y598241D01*
G01X977270Y600961D02*
Y598901D01*
G01X978055Y601746D02*
X977270Y600961D01*
G01X979882Y601746D02*
X978055D01*
G01X980708Y602572D02*
X979882Y601746D01*
G01X980708Y604614D02*
Y602572D01*
G01X1077753Y-1741D02*
X1077755Y-1743D01*
G01X1074509Y-1741D02*
X1077753D01*
G01X1073337Y-569D02*
X1074509Y-1741D01*
G01X1073337Y6384D02*
Y-569D01*
G01X1073947Y6994D02*
X1073337Y6384D01*
G01X1074937Y6994D02*
X1073947D01*
G01X1075547Y6384D02*
X1074937Y6994D01*
G01X1075547Y2023D02*
Y6384D01*
G01X1076197Y1373D02*
X1075547Y2023D01*
G01X1077187Y1373D02*
X1076197D01*
G01X1077757Y1943D02*
X1077187Y1373D01*
G01X1077757Y9122D02*
Y1943D01*
G01X1077755Y9124D02*
X1077757Y9122D01*
G01X1077755Y10483D02*
Y9124D01*
G01X1072736Y15502D02*
X1077755Y10483D01*
G01X1072736Y20322D02*
Y15502D01*
G01X1066000Y27058D02*
X1072736Y20322D01*
G01X1066000Y31400D02*
Y27058D01*
G01X1062755Y34645D02*
X1066000Y31400D01*
G01X1050985Y-1741D02*
X1050983Y-1743D01*
G01X1050985Y773D02*
Y-1741D01*
G01X1050375Y1383D02*
X1050985Y773D01*
G01X1048207Y1383D02*
X1050375D01*
G01X1047570Y2020D02*
X1048207Y1383D01*
G01X1047570Y3920D02*
Y2020D01*
G01X1048153Y4503D02*
X1047570Y3920D01*
G01X1050375Y4503D02*
X1048153D01*
G01X1050985Y5113D02*
X1050375Y4503D01*
G01X1050985Y9122D02*
Y5113D01*
G01X1050983Y9124D02*
X1050985Y9122D01*
G01X1050983Y11792D02*
Y9124D01*
G01X1050275Y12500D02*
X1050983Y11792D01*
G01X1050275Y14125D02*
Y12500D01*
G01X1049245Y15155D02*
X1050275Y14125D01*
G01X1049245Y20025D02*
Y15155D01*
G01X1044103Y25167D02*
X1049245Y20025D01*
G01X1035932Y25167D02*
X1044103D01*
G01X1069013Y30073D02*
X1071064Y28022D01*
G01X1069013Y33545D02*
Y30073D01*
G01X1087797Y-2402D02*
Y9122D01*
G01X1092876Y31076D02*
X1096108Y34308D01*
G01X1092876Y27243D02*
Y31076D01*
G01X1091903Y26270D02*
X1092876Y27243D01*
G01X1091903Y23345D02*
Y26270D01*
G01X1093704Y21544D02*
X1091903Y23345D01*
G01X1093704Y19644D02*
Y21544D01*
G01X1093107Y19047D02*
X1093704Y19644D01*
G01X1090582Y19047D02*
X1093107D01*
G01X1089400Y17865D02*
X1090582Y19047D01*
G01X1089400Y12770D02*
Y17865D01*
G01X1087795Y11165D02*
X1089400Y12770D01*
G01X1087795Y9124D02*
Y11165D01*
G01X1087797Y9122D02*
X1087795Y9124D01*
G01X1084448Y9120D02*
X1084450Y9122D01*
G01X1084448Y6229D02*
Y9120D01*
G01X1083838Y5619D02*
X1084448Y6229D01*
G01X1081571Y5619D02*
X1083838D01*
G01X1080961Y5009D02*
X1081571Y5619D01*
G01X1080961Y3109D02*
Y5009D01*
G01X1081571Y2499D02*
X1080961Y3109D01*
G01X1083838Y2499D02*
X1081571D01*
G01X1084448Y1889D02*
X1083838Y2499D01*
G01X1084448Y-1743D02*
Y1889D01*
G01X1089183Y31453D02*
X1092860Y35130D01*
G01X1088501Y31453D02*
X1089183D01*
G01X1086164Y29116D02*
X1088501Y31453D01*
G01X1086164Y12658D02*
Y29116D01*
G01X1084448Y10942D02*
X1086164Y12658D01*
G01X1084448Y9124D02*
Y10942D01*
G01X1084450Y9122D02*
X1084448Y9124D01*
G01X1062676Y31156D02*
X1059416Y34416D01*
G01X1062676Y29624D02*
Y31156D01*
G01X1062670Y29618D02*
X1062676Y29624D01*
G01X1062670Y26991D02*
Y29618D01*
G01X1071064Y18597D02*
X1062670Y26991D01*
G01X1071064Y17057D02*
Y18597D01*
G01Y15925D02*
Y17057D01*
G01X1069200Y14061D02*
X1071064Y15925D01*
G01X1069200Y10800D02*
Y14061D01*
G01X1069444Y10556D02*
X1069200Y10800D01*
G01X1069444Y7844D02*
Y10556D01*
G01X1069200Y7600D02*
X1069444Y7844D01*
G01X1069200Y-2676D02*
Y7600D01*
G01X1071062Y-4538D02*
X1069200Y-2676D01*
G01X1071062Y-7108D02*
Y-4538D01*
G01X1054331Y-4535D02*
X1054330Y-4536D01*
G01X1054331Y9122D02*
Y-4535D01*
G01Y11369D02*
Y9122D01*
G01X1052300Y13400D02*
X1054331Y11369D01*
G01X1052300Y15600D02*
Y13400D01*
G01X1052696Y15996D02*
X1052300Y15600D01*
G01X1052696Y19588D02*
Y15996D01*
G01X1042150Y30134D02*
X1052696Y19588D01*
G01X1042150Y36550D02*
Y30134D01*
G01X1053999Y74089D02*
X1054331Y73757D01*
G01X1053999Y79455D02*
Y74089D01*
G01X1053755Y79699D02*
X1053999Y79455D01*
G01X1053755Y83155D02*
Y79699D01*
G01X1054331Y83731D02*
X1053755Y83155D01*
G01X1054331Y84598D02*
Y83731D01*
G01X1054330Y84599D02*
X1054331Y84598D01*
G01X1052800Y86129D02*
X1054330Y84599D01*
G01X1052800Y88800D02*
Y86129D01*
G01X1052500Y89100D02*
X1052800Y88800D01*
G01X1052500Y91300D02*
Y89100D01*
G01X1052800Y91600D02*
X1052500Y91300D01*
G01X1052800Y93500D02*
Y91600D01*
G01X1052000Y94300D02*
X1052800Y93500D01*
G01X1052000Y98456D02*
Y94300D01*
G01X1077757Y75001D02*
Y73757D01*
G01X1077162Y75596D02*
X1077757Y75001D01*
G01X1071746Y75596D02*
X1077162D01*
G01X1071189Y76153D02*
X1071746Y75596D01*
G01X1071189Y77143D02*
Y76153D01*
G01X1071852Y77806D02*
X1071189Y77143D01*
G01X1077347Y77806D02*
X1071852D01*
G01X1077992Y78451D02*
X1077347Y77806D01*
G01X1077992Y79441D02*
Y78451D01*
G01X1077417Y80016D02*
X1077992Y79441D01*
G01X1073992Y80016D02*
X1077417D01*
G01X1073382Y80626D02*
X1073992Y80016D01*
G01X1073382Y81616D02*
Y80626D01*
G01X1073992Y82226D02*
X1073382Y81616D01*
G01X1076842Y82226D02*
X1073992D01*
G01X1077452Y82836D02*
X1076842Y82226D01*
G01X1077452Y87089D02*
Y82836D01*
G01X1077755Y87392D02*
X1077452Y87089D01*
G01X1077755Y88045D02*
Y87392D01*
G01X1077400Y88400D02*
X1077755Y88045D01*
G01X1077400Y90100D02*
Y88400D01*
G01X1075677Y91823D02*
X1077400Y90100D01*
G01X1075677Y93277D02*
Y91823D01*
G01X1076100Y93700D02*
X1075677Y93277D01*
G01X1076100Y101700D02*
Y93700D01*
G01X1062755Y37763D02*
Y34645D01*
G01X1062100Y38418D02*
X1062755Y37763D01*
G01X1062100Y45400D02*
Y38418D01*
G01X1062733Y46033D02*
X1062100Y45400D01*
G01X1062733Y56440D02*
Y46033D01*
G01X1062771Y56478D02*
X1062733Y56440D01*
G01X1062771Y61129D02*
Y56478D01*
G01X1059413Y64487D02*
X1062771Y61129D01*
G01X1059413Y67667D02*
Y64487D01*
G01X1059859Y68113D02*
X1059413Y67667D01*
G01X1059859Y71215D02*
Y68113D01*
G01X1059390Y71684D02*
X1059859Y71215D01*
G01X1059390Y75010D02*
Y71684D01*
G01X1059100Y75300D02*
X1059390Y75010D01*
G01X1059100Y85338D02*
Y75300D01*
G01X1060162Y86400D02*
X1059100Y85338D01*
G01X1060200Y86400D02*
X1060162D01*
G01X1062900Y89100D02*
X1060200Y86400D01*
G01X1062900Y91200D02*
Y89100D01*
G01X1061800Y92300D02*
X1062900Y91200D01*
G01X1061800Y107113D02*
Y92300D01*
G01X1089700Y75660D02*
X1087797Y73757D01*
G01X1089700Y77434D02*
Y75660D01*
G01X1088101Y79033D02*
X1089700Y77434D01*
G01X1088101Y80892D02*
Y79033D01*
G01X1089093Y81884D02*
X1088101Y80892D01*
G01X1089093Y83416D02*
Y81884D01*
G01X1087795Y84714D02*
X1089093Y83416D01*
G01X1088400Y85319D02*
X1087795Y84714D01*
G01X1088400Y86699D02*
Y85319D01*
G01X1089300Y87599D02*
X1088400Y86699D01*
G01X1089300Y88700D02*
Y87599D01*
G01X1090058Y89458D02*
X1089300Y88700D01*
G01X1090058Y90342D02*
Y89458D01*
G01X1088529Y91871D02*
X1090058Y90342D01*
G01X1088529Y94683D02*
Y91871D01*
G01X1069434Y33966D02*
X1069013Y33545D01*
G01X1069434Y49193D02*
Y33966D01*
G01X1068976Y49651D02*
X1069434Y49193D01*
G01X1068976Y52769D02*
Y49651D01*
G01X1071064Y54857D02*
X1068976Y52769D01*
G01X1066400Y92200D02*
Y106739D01*
G01X1065900Y91700D02*
X1066400Y92200D01*
G01X1065900Y88800D02*
Y91700D01*
G01X1066300Y88400D02*
X1065900Y88800D01*
G01X1066300Y86200D02*
Y88400D01*
G01X1062664Y82564D02*
X1066300Y86200D01*
G01X1062664Y72436D02*
Y82564D01*
G01X1063100Y72000D02*
X1062664Y72436D01*
G01X1063100Y70031D02*
Y72000D01*
G01X1065982Y67149D02*
X1063100Y70031D01*
G01X1065982Y64243D02*
Y67149D01*
G01X1071064Y59161D02*
X1065982Y64243D01*
G01X1071064Y54857D02*
Y59161D01*
G01X1083019Y37388D02*
X1084450Y35957D01*
G01X1083019Y45491D02*
Y37388D01*
G01X1084450Y46922D02*
X1083019Y45491D01*
G01X1079300Y93850D02*
Y109188D01*
G01X1079650Y93500D02*
X1079300Y93850D01*
G01X1079650Y91650D02*
Y93500D01*
G01X1079283Y91283D02*
X1079650Y91650D01*
G01X1079283Y89217D02*
Y91283D01*
G01X1079800Y88700D02*
X1079283Y89217D01*
G01X1079800Y86300D02*
Y88700D01*
G01X1079300Y85800D02*
X1079800Y86300D01*
G01X1079300Y83700D02*
Y85800D01*
G01X1079700Y83300D02*
X1079300Y83700D01*
G01X1079700Y75798D02*
Y83300D01*
G01X1079377Y75475D02*
X1079700Y75798D01*
G01X1079377Y63864D02*
Y75475D01*
G01X1082714Y60527D02*
X1079377Y63864D01*
G01X1082714Y53475D02*
Y60527D01*
G01X1081254Y52015D02*
X1082714Y53475D01*
G01X1081254Y50118D02*
Y52015D01*
G01X1084450Y46922D02*
X1081254Y50118D01*
G01X1092800Y93600D02*
Y109536D01*
G01X1093000Y93400D02*
X1092800Y93600D01*
G01X1093000Y91400D02*
Y93400D01*
G01X1092600Y91000D02*
X1093000Y91400D01*
G01X1092600Y89000D02*
Y91000D01*
G01X1093000Y88600D02*
X1092600Y89000D01*
G01X1093000Y86600D02*
Y88600D01*
G01X1092600Y86200D02*
X1093000Y86600D01*
G01X1092600Y74900D02*
Y86200D01*
G01X1092880Y74620D02*
X1092600Y74900D01*
G01X1092880Y61736D02*
Y74620D01*
G01X1092300Y61156D02*
X1092880Y61736D01*
G01X1092300Y56500D02*
Y61156D01*
G01X1092851Y55949D02*
X1092300Y56500D01*
G01X1092851Y43789D02*
Y55949D01*
G01X1092200Y43138D02*
X1092851Y43789D01*
G01X1092200Y37800D02*
Y43138D01*
G01X1092860Y37140D02*
X1092200Y37800D01*
G01X1092860Y35130D02*
Y37140D01*
G01X1059800Y92334D02*
Y106284D01*
G01X1055800Y88334D02*
X1059800Y92334D01*
G01X1055800Y86500D02*
Y88334D01*
G01X1056900Y85400D02*
X1055800Y86500D01*
G01X1056900Y75700D02*
Y85400D01*
G01X1055965Y74765D02*
X1056900Y75700D01*
G01X1055965Y69765D02*
Y74765D01*
G01X1055957Y69757D02*
X1055965Y69765D01*
G01X1055957Y59495D02*
Y69757D01*
G01X1059297Y56155D02*
X1055957Y59495D01*
G01X1059297Y52830D02*
Y56155D01*
G01X1059679Y52448D02*
X1059297Y52830D01*
G01X1059679Y49634D02*
Y52448D01*
G01X1059416Y49371D02*
X1059679Y49634D01*
G01X1059416Y34416D02*
Y49371D01*
G01X1085766Y75073D02*
X1084450Y73757D01*
G01X1085766Y85336D02*
Y75073D01*
G01X1086300Y85870D02*
X1085766Y85336D01*
G01X1086300Y86592D02*
Y85870D01*
G01X1085500Y87392D02*
X1086300Y86592D01*
G01X1084448Y87392D02*
X1085500D01*
G01X1084448Y88048D02*
Y87392D01*
G01X1085900Y89500D02*
X1084448Y88048D01*
G01X1085900Y90900D02*
Y89500D01*
G01X1086300Y91300D02*
X1085900Y90900D01*
G01X1086300Y93700D02*
Y91300D01*
G01X1086100Y93900D02*
X1086300Y93700D01*
G01X1086100Y101900D02*
Y93900D01*
G01X1048284Y38658D02*
X1050985Y35957D01*
G01X1048284Y44221D02*
Y38658D01*
G01X1050985Y46922D02*
X1048284Y44221D01*
G01X1039300Y60800D02*
X1035986D01*
G01X1042300Y57800D02*
X1039300Y60800D01*
G01X1042300Y54000D02*
Y57800D01*
G01X1046000Y50300D02*
X1042300Y54000D01*
G01X1050275Y50300D02*
X1046000D01*
G01X1050983Y49592D02*
X1050275Y50300D01*
G01X1050983Y46924D02*
Y49592D01*
G01X1050985Y46922D02*
X1050983Y46924D01*
G01X1056600Y38226D02*
X1054331Y35957D01*
G01X1056600Y43116D02*
Y38226D01*
G01X1054331Y45385D02*
X1056600Y43116D01*
G01X1054331Y46922D02*
Y45385D01*
G01X1037908Y79100D02*
X1034072D01*
G01X1038952Y78056D02*
X1037908Y79100D01*
G01X1039814Y78056D02*
X1038952D01*
G01X1040370Y78612D02*
X1039814Y78056D01*
G01X1041232Y78612D02*
X1040370D01*
G01X1042216Y77628D02*
X1041232Y78612D01*
G01X1042216Y76766D02*
Y77628D01*
G01X1041660Y76210D02*
X1042216Y76766D01*
G01X1041660Y75348D02*
Y76210D01*
G01X1042400Y74608D02*
X1041660Y75348D01*
G01X1042400Y65471D02*
Y74608D01*
G01X1049269Y58602D02*
X1042400Y65471D01*
G01X1049269Y53931D02*
Y58602D01*
G01X1051000Y52200D02*
X1049269Y53931D01*
G01X1051500Y52200D02*
X1051000D01*
G01X1054330Y49370D02*
X1051500Y52200D01*
G01X1054330Y46923D02*
Y49370D01*
G01X1054331Y46922D02*
X1054330Y46923D01*
G01X1077757Y37190D02*
Y35957D01*
G01X1077257Y37690D02*
X1077757Y37190D01*
G01X1073234Y37690D02*
X1077257D01*
G01X1072573Y38351D02*
X1073234Y37690D01*
G01X1072573Y39727D02*
Y38351D01*
G01X1073183Y40337D02*
X1072573Y39727D01*
G01X1077147Y40337D02*
X1073183D01*
G01X1077757Y40947D02*
X1077147Y40337D01*
G01X1077757Y42146D02*
Y40947D01*
G01X1077147Y42756D02*
X1077757Y42146D01*
G01X1073183Y42756D02*
X1077147D01*
G01X1072573Y43366D02*
X1073183Y42756D01*
G01X1072573Y44397D02*
Y43366D01*
G01X1073183Y45007D02*
X1072573Y44397D01*
G01X1077147Y45007D02*
X1073183D01*
G01X1077757Y45617D02*
X1077147Y45007D01*
G01X1077757Y46922D02*
Y45617D01*
G01X1068900Y91500D02*
Y107068D01*
G01X1069600Y90800D02*
X1068900Y91500D01*
G01X1069600Y89200D02*
Y90800D01*
G01X1069200Y88800D02*
X1069600Y89200D01*
G01X1069200Y85800D02*
Y88800D01*
G01X1069600Y85400D02*
X1069200Y85800D01*
G01X1069600Y82455D02*
Y85400D01*
G01X1066750Y79605D02*
X1069600Y82455D01*
G01X1066750Y76716D02*
Y79605D01*
G01X1065982Y75948D02*
X1066750Y76716D01*
G01X1065982Y70018D02*
Y75948D01*
G01X1069428Y66572D02*
X1065982Y70018D01*
G01X1069428Y64196D02*
Y66572D01*
G01X1076041Y57583D02*
X1069428Y64196D01*
G01X1076041Y53159D02*
Y57583D01*
G01X1077755Y51445D02*
X1076041Y53159D01*
G01X1077755Y46924D02*
Y51445D01*
G01X1077757Y46922D02*
X1077755Y46924D01*
G01X1071062Y92757D02*
Y94815D01*
G01X1071573Y92246D02*
X1071062Y92757D01*
G01X1071573Y79902D02*
Y92246D01*
G01X1069449Y77778D02*
X1071573Y79902D01*
G01X1069449Y72222D02*
Y77778D01*
G01X1069051Y71824D02*
X1069449Y72222D01*
G01X1069051Y69349D02*
Y71824D01*
G01X1071064Y67336D02*
X1069051Y69349D01*
G01X1071064Y65822D02*
Y67336D01*
G01X1086100Y37654D02*
X1087797Y35957D01*
G01X1086100Y45225D02*
Y37654D01*
G01X1087797Y46922D02*
X1086100Y45225D01*
G01X1082900Y94100D02*
Y101200D01*
G01X1082400Y93600D02*
X1082900Y94100D01*
G01X1082400Y91700D02*
Y93600D01*
G01X1083000Y91100D02*
X1082400Y91700D01*
G01X1083000Y89300D02*
Y91100D01*
G01X1082200Y88500D02*
X1083000Y89300D01*
G01X1082200Y86200D02*
Y88500D01*
G01X1083000Y85400D02*
X1082200Y86200D01*
G01X1083000Y83700D02*
Y85400D01*
G01X1082400Y83100D02*
X1083000Y83700D01*
G01X1082400Y76650D02*
Y83100D01*
G01X1082824Y76226D02*
X1082400Y76650D01*
G01X1082824Y72425D02*
Y76226D01*
G01X1081369Y70970D02*
X1082824Y72425D01*
G01X1081369Y68229D02*
Y70970D01*
G01X1082824Y66774D02*
X1081369Y68229D01*
G01X1082824Y64495D02*
Y66774D01*
G01X1086165Y61154D02*
X1082824Y64495D01*
G01X1086165Y53865D02*
Y61154D01*
G01X1085736Y53436D02*
X1086165Y53865D01*
G01X1085736Y51564D02*
Y53436D01*
G01X1087795Y49505D02*
X1085736Y51564D01*
G01X1087795Y46924D02*
Y49505D01*
G01X1087797Y46922D02*
X1087795Y46924D01*
G01X1040496Y38204D02*
X1042150Y36550D01*
G01X1040496Y39066D02*
Y38204D01*
G01X1042364Y40934D02*
X1040496Y39066D01*
G01X1042364Y41642D02*
Y40934D01*
G01X1040892Y43114D02*
X1042364Y41642D01*
G01X1040130Y43114D02*
X1040892D01*
G01X1038289Y41273D02*
X1040130Y43114D01*
G01X1037427Y41273D02*
X1038289D01*
G01X1049900Y88475D02*
X1050983Y87392D01*
G01X1049900Y91100D02*
Y88475D01*
G01X1045300Y95700D02*
X1049900Y91100D01*
G01X1050983Y73759D02*
X1050985Y73757D01*
G01X1050983Y87392D02*
Y73759D01*
G01X1126900Y118738D02*
X1087379Y158259D01*
G01X1048900Y101556D02*
X1052000Y98456D01*
G01X1048900Y105600D02*
Y101556D01*
G01X1075362Y102438D02*
X1076100Y101700D01*
G01X1075362Y108662D02*
Y102438D01*
G01X1047256Y136768D02*
X1075362Y108662D01*
G01X1047256Y190969D02*
Y136768D01*
G01X1057149Y111764D02*
X1061800Y107113D01*
G01X1052113Y111764D02*
X1057149D01*
G01X1036126Y127751D02*
X1052113Y111764D01*
G01X1036126Y195037D02*
Y127751D01*
G01X1089468Y125781D02*
X1104000Y111249D01*
G01X1089468Y134109D02*
Y125781D01*
G01X1088311Y135266D02*
X1089468Y134109D01*
G01X1087449Y135266D02*
X1088311D01*
G01X1085237Y133054D02*
X1087449Y135266D01*
G01X1084445Y133054D02*
X1085237D01*
G01X1083037Y134462D02*
X1084445Y133054D01*
G01X1083037Y135254D02*
Y134462D01*
G01X1085249Y137466D02*
X1083037Y135254D01*
G01X1085249Y138328D02*
Y137466D01*
G01X1071892Y151685D02*
X1085249Y138328D01*
G01X1071892Y189404D02*
Y151685D01*
G01X1089600Y95754D02*
X1088529Y94683D01*
G01X1089600Y103312D02*
Y95754D01*
G01X1088931Y103981D02*
X1089600Y103312D01*
G01X1087332Y103981D02*
X1088931D01*
G01X1086639Y104674D02*
X1087332Y103981D01*
G01X1086639Y106626D02*
Y104674D01*
G01X1087255Y107242D02*
X1086639Y106626D01*
G01X1088963Y107242D02*
X1087255D01*
G01X1089623Y107902D02*
X1088963Y107242D01*
G01X1089623Y109111D02*
Y107902D01*
G01X1057806Y140928D02*
X1089623Y109111D01*
G01X1057806Y191151D02*
Y140928D01*
G01X1094928Y154246D02*
Y169265D01*
G01X1131000Y118174D02*
X1094928Y154246D01*
G01X1040056Y131325D02*
Y191575D01*
G01X1043394Y127987D02*
X1040056Y131325D01*
G01X1043394Y126855D02*
Y127987D01*
G01X1042733Y126194D02*
X1043394Y126855D01*
G01X1042733Y125143D02*
Y126194D01*
G01X1043864Y124012D02*
X1042733Y125143D01*
G01X1045077Y124012D02*
X1043864D01*
G01X1045657Y124592D02*
X1045077Y124012D01*
G01X1046789Y124592D02*
X1045657D01*
G01X1047920Y123461D02*
X1046789Y124592D01*
G01X1047920Y122329D02*
Y123461D01*
G01X1047180Y121589D02*
X1047920Y122329D01*
G01X1047180Y120477D02*
Y121589D01*
G01X1048311Y119346D02*
X1047180Y120477D01*
G01X1049463Y119346D02*
X1048311D01*
G01X1050183Y120066D02*
X1049463Y119346D01*
G01X1051315Y120066D02*
X1050183D01*
G01X1052446Y118935D02*
X1051315Y120066D01*
G01X1052446Y117803D02*
Y118935D01*
G01X1051775Y117132D02*
X1052446Y117803D01*
G01X1051775Y115954D02*
Y117132D01*
G01X1052765Y114964D02*
X1051775Y115954D01*
G01X1058175Y114964D02*
X1052765D01*
G01X1066400Y106739D02*
X1058175Y114964D01*
G01X1063062Y141638D02*
Y195238D01*
G01X1095483Y109217D02*
X1063062Y141638D01*
G01X1094800Y105900D02*
X1095483Y106583D01*
G01X1094800Y103700D02*
Y105900D01*
G01X1096288Y102212D02*
X1094800Y103700D01*
G01X1050506Y137982D02*
Y191694D01*
G01X1079300Y109188D02*
X1050506Y137982D01*
G01X1061012Y141324D02*
Y194243D01*
G01X1092800Y109536D02*
X1061012Y141324D01*
G01X1034126Y127598D02*
Y194697D01*
G01X1035900Y125824D02*
X1034126Y127598D01*
G01X1035900Y124962D02*
Y125824D01*
G01X1034904Y123966D02*
X1035900Y124962D01*
G01X1034904Y123104D02*
Y123966D01*
G01X1036249Y121759D02*
X1034904Y123104D01*
G01X1037111Y121759D02*
X1036249D01*
G01X1038107Y122755D02*
X1037111Y121759D01*
G01X1038969Y122755D02*
X1038107D01*
G01X1040314Y121410D02*
X1038969Y122755D01*
G01X1040314Y120548D02*
Y121410D01*
G01X1039318Y119552D02*
X1040314Y120548D01*
G01X1039318Y118690D02*
Y119552D01*
G01X1040663Y117345D02*
X1039318Y118690D01*
G01X1041525Y117345D02*
X1040663D01*
G01X1042521Y118341D02*
X1041525Y117345D01*
G01X1043383Y118341D02*
X1042521D01*
G01X1051960Y109764D02*
X1043383Y118341D01*
G01X1056320Y109764D02*
X1051960D01*
G01X1059800Y106284D02*
X1056320Y109764D01*
G01X1084500Y103500D02*
X1086100Y101900D01*
G01X1084500Y111405D02*
Y103500D01*
G01X1055806Y140099D02*
X1084500Y111405D01*
G01X1055806Y190981D02*
Y140099D01*
G01X1078446Y133555D02*
X1101400Y110601D01*
G01X1078446Y135168D02*
Y133555D01*
G01X1081023Y137745D02*
X1078446Y135168D01*
G01X1081023Y138877D02*
Y137745D01*
G01X1079717Y140183D02*
X1081023Y138877D01*
G01X1078585Y140183D02*
X1079717D01*
G01X1075962Y137560D02*
X1078585Y140183D01*
G01X1074830Y137560D02*
X1075962D01*
G01X1073363Y139027D02*
X1074830Y137560D01*
G01X1073363Y140159D02*
Y139027D01*
G01X1075986Y142782D02*
X1073363Y140159D01*
G01X1075986Y143914D02*
Y142782D01*
G01X1069392Y150508D02*
X1075986Y143914D01*
G01X1069392Y189404D02*
Y150508D01*
G01X1042056Y132154D02*
Y191624D01*
G01X1057246Y116964D02*
X1042056Y132154D01*
G01X1059004Y116964D02*
X1057246D01*
G01X1068900Y107068D02*
X1059004Y116964D01*
G01X1045256Y134198D02*
Y191381D01*
G01X1046056Y133398D02*
X1045256Y134198D01*
G01X1047797Y133398D02*
X1046056D01*
G01X1048452Y132743D02*
X1047797Y133398D01*
G01X1048452Y130285D02*
Y132743D01*
G01X1049521Y129216D02*
X1048452Y130285D01*
G01X1051979Y129216D02*
X1049521D01*
G01X1052978Y128217D02*
X1051979Y129216D01*
G01X1052978Y125759D02*
Y128217D01*
G01X1054047Y124690D02*
X1052978Y125759D01*
G01X1056505Y124690D02*
X1054047D01*
G01X1057570Y123625D02*
X1056505Y124690D01*
G01X1057570Y121167D02*
Y123625D01*
G01X1058573Y120164D02*
X1057570Y121167D01*
G01X1061031Y120164D02*
X1058573D01*
G01X1073362Y107833D02*
X1061031Y120164D01*
G01X1073362Y102061D02*
Y107833D01*
G01X1071262Y99961D02*
X1073362Y102061D01*
G01X1071262Y98245D02*
Y99961D01*
G01X1071872Y97635D02*
X1071262Y98245D01*
G01X1072614Y97635D02*
X1071872D01*
G01X1073242Y97007D02*
X1072614Y97635D01*
G01X1073242Y96017D02*
Y97007D01*
G01X1072650Y95425D02*
X1073242Y96017D01*
G01X1071672Y95425D02*
X1072650D01*
G01X1071062Y94815D02*
X1071672Y95425D01*
G01X1074127Y152992D02*
Y188139D01*
G01X1092928Y134185D02*
X1074127Y152992D01*
G01X1092928Y133054D02*
Y134185D01*
G01X1091953Y132079D02*
X1092928Y133054D01*
G01X1091953Y130949D02*
Y132079D01*
G01X1093086Y129816D02*
X1091953Y130949D01*
G01X1094215Y129816D02*
X1093086D01*
G01X1095191Y130792D02*
X1094215Y129816D01*
G01X1096321Y130792D02*
X1095191D01*
G01X1095252Y126326D02*
X1097454Y128528D01*
G01X1096385Y124063D02*
X1095252Y125196D01*
G01X1052506Y138873D02*
Y191500D01*
G01X1081300Y110079D02*
X1052506Y138873D01*
G01X1081300Y102800D02*
Y110079D01*
G01X1082900Y101200D02*
X1081300Y102800D01*
G01X1077065Y153584D02*
Y188577D01*
G01X1109000Y121649D02*
X1077065Y153584D01*
G01X1045300Y99795D02*
Y95700D01*
G01X1044500Y100595D02*
X1045300Y99795D01*
G01X1042634Y100595D02*
X1044500D01*
G01X1041864Y101365D02*
X1042634Y100595D01*
G01X1041864Y102965D02*
Y101365D01*
G01X1042694Y103795D02*
X1041864Y102965D01*
G01X1044409Y103795D02*
X1042694D01*
G01X1045270Y104656D02*
X1044409Y103795D01*
G01X1045270Y105930D02*
Y104656D01*
G01X1087379Y170630D02*
Y185879D01*
G01X1087989Y170020D02*
X1087379Y170630D01*
G01X1089440Y170020D02*
X1087989D01*
G01X1090000Y169460D02*
X1089440Y170020D01*
G01X1090000Y167470D02*
Y169460D01*
G01X1089440Y166910D02*
X1090000Y167470D01*
G01X1087989Y166910D02*
X1089440D01*
G01X1087379Y166300D02*
X1087989Y166910D01*
G01X1087379Y158259D02*
Y166300D01*
G01X1072065Y189577D02*
X1071892Y189404D01*
G01X1089879Y174314D02*
Y186121D01*
G01X1094928Y169265D02*
X1089879Y174314D01*
G01X1054756Y208945D02*
Y233851D01*
G01X1058900Y204801D02*
X1054756Y208945D01*
G01X1058900Y199400D02*
Y204801D01*
G01X1063062Y195238D02*
X1058900Y199400D01*
G01X1052279Y208418D02*
Y235365D01*
G01X1056776Y203921D02*
X1052279Y208418D01*
G01X1056776Y198479D02*
Y203921D01*
G01X1061012Y194243D02*
X1056776Y198479D01*
G01X1069565Y189577D02*
X1069392Y189404D01*
G01X1094879Y176788D02*
Y188577D01*
G01X1106953Y164714D02*
X1094879Y176788D01*
G01X1092379Y175844D02*
Y188577D01*
G01X1100388Y167835D02*
X1092379Y175844D01*
G01X1074127Y188139D02*
X1074565Y188577D01*
G01X1054756Y233851D02*
X1057314Y236409D01*
G01X1052279Y235365D02*
X1049284Y238360D01*
G01X1066201Y401566D02*
Y467701D01*
G01X1050700Y402600D02*
X1053700Y405600D01*
G01X1050700Y399700D02*
Y402600D01*
G01X1045700Y394700D02*
X1050700Y399700D01*
G01X1045700Y392507D02*
Y394700D01*
G01X1059000Y401553D02*
Y470757D01*
G01X1061000Y401633D02*
Y469928D01*
G01X1034250Y399873D02*
Y406150D01*
G01X1039400Y396200D02*
Y403500D01*
G01X1037800Y394600D02*
X1039400Y396200D01*
G01X1037800Y392600D02*
Y394600D01*
G01X1034400Y389200D02*
X1037800Y392600D01*
G01X1034400Y387900D02*
Y389200D01*
G01X1033900Y387400D02*
X1034400Y387900D01*
G01X1033900Y385700D02*
Y387400D01*
G01X1034200Y385400D02*
X1033900Y385700D01*
G01X1034200Y383800D02*
Y385400D01*
G01X1033500Y381824D02*
Y383100D01*
G01X1064201Y402640D02*
Y468602D01*
G01X1054300Y399600D02*
Y403400D01*
G01X1053200Y398500D02*
X1054300Y399600D01*
G01X1052300Y398500D02*
X1053200D01*
G01X1047700Y393900D02*
X1052300Y398500D01*
G01X1047700Y391600D02*
Y393900D01*
G01X1045800Y403101D02*
X1050450Y407751D01*
G01X1045800Y398800D02*
Y403101D01*
G01X1043200Y396200D02*
X1045800Y398800D01*
G01X1043200Y393500D02*
Y396200D01*
G01X1035800Y398000D02*
Y405000D01*
G01X1043900Y399342D02*
Y404100D01*
G01X1042200Y397642D02*
X1043900Y399342D01*
G01X1042200Y393800D02*
Y397642D01*
G01X1037600Y397100D02*
Y404300D01*
G01X1088100Y454224D02*
X1123654Y489778D01*
G01X1088100Y415400D02*
Y454224D01*
G01X1089200Y414300D02*
X1088100Y415400D01*
G01X1089200Y406970D02*
Y414300D01*
G01X1089529Y406641D02*
X1089200Y406970D01*
G01X1053700Y405600D02*
Y475199D01*
G01X1037962Y409862D02*
Y481636D01*
G01X1034250Y406150D02*
X1037962Y409862D01*
G01X1045162Y409262D02*
Y478651D01*
G01X1039400Y403500D02*
X1045162Y409262D01*
G01X1055700Y404800D02*
Y474369D01*
G01X1054300Y403400D02*
X1055700Y404800D01*
G01X1078322Y458519D02*
X1095214Y475411D01*
G01X1078322Y413391D02*
Y458519D01*
G01X1078480Y413233D02*
X1078322Y413391D01*
G01X1050450Y407751D02*
Y476584D01*
G01X1093100Y452426D02*
X1131028Y490354D01*
G01X1093100Y416900D02*
Y452426D01*
G01X1094400Y415600D02*
X1093100Y416900D01*
G01X1094400Y407081D02*
Y415600D01*
G01X1094489Y406992D02*
X1094400Y407081D01*
G01X1070747Y411271D02*
Y466138D01*
G01X1070980Y411038D02*
X1070747Y411271D01*
G01X1039962Y409162D02*
Y480807D01*
G01X1035800Y405000D02*
X1039962Y409162D01*
G01X1090600Y453188D02*
X1128022Y490610D01*
G01X1090600Y415900D02*
Y453188D01*
G01X1091700Y414800D02*
X1090600Y415900D01*
G01X1091700Y406930D02*
Y414800D01*
G01X1091989Y406641D02*
X1091700Y406930D01*
G01X1048450Y408650D02*
Y477413D01*
G01X1043900Y404100D02*
X1048450Y408650D01*
G01X1075747Y459519D02*
X1090548Y474320D01*
G01X1075747Y413466D02*
Y459519D01*
G01X1075980Y413233D02*
X1075747Y413466D01*
G01X1034762Y411284D02*
Y483062D01*
G01X1043162Y409862D02*
Y479481D01*
G01X1037600Y404300D02*
X1043162Y409862D01*
G01X1073247Y410880D02*
Y465354D01*
G01X1073480Y410647D02*
X1073247Y410880D01*
G01X1066201Y467701D02*
X1096500Y498000D01*
G01X1080303Y523332D02*
Y526822D01*
G01X1079600Y522629D02*
X1080303Y523332D01*
G01X1079600Y517000D02*
Y522629D01*
G01X1079300Y516700D02*
X1079600Y517000D01*
G01X1079300Y514600D02*
Y516700D01*
G01X1080006Y513894D02*
X1079300Y514600D01*
G01X1080006Y511506D02*
Y513894D01*
G01X1079385Y510885D02*
X1080006Y511506D01*
G01X1079385Y509015D02*
Y510885D01*
G01X1080100Y508300D02*
X1079385Y509015D01*
G01X1080100Y501599D02*
Y508300D01*
G01X1053700Y475199D02*
X1080100Y501599D01*
G01X1085090Y525002D02*
Y526835D01*
G01X1085700Y524392D02*
X1085090Y525002D01*
G01X1086711Y524392D02*
X1085700D01*
G01X1087348Y523755D02*
X1086711Y524392D01*
G01X1087348Y522765D02*
Y523755D01*
G01X1086765Y522182D02*
X1087348Y522765D01*
G01X1085770Y522182D02*
X1086765D01*
G01X1085132Y521544D02*
X1085770Y522182D01*
G01X1085132Y520265D02*
Y521544D01*
G01X1085748Y519649D02*
X1085132Y520265D01*
G01X1086859Y519649D02*
X1085748D01*
G01X1087467Y519041D02*
X1086859Y519649D01*
G01X1087467Y517977D02*
Y519041D01*
G01X1085287Y515797D02*
X1087467Y517977D01*
G01X1085287Y514387D02*
Y515797D01*
G01X1084448Y513548D02*
X1085287Y514387D01*
G01X1084448Y512792D02*
Y513548D01*
G01X1085900Y511340D02*
X1084448Y512792D01*
G01X1085900Y505952D02*
Y511340D01*
G01X1086696Y505156D02*
X1085900Y505952D01*
G01X1086696Y498453D02*
Y505156D01*
G01X1083843Y495600D02*
X1086696Y498453D01*
G01X1081814Y495600D02*
X1083843D01*
G01X1079639Y493425D02*
X1081814Y495600D01*
G01X1079639Y491396D02*
Y493425D01*
G01X1078296Y490053D02*
X1079639Y491396D01*
G01X1077166Y490053D02*
X1078296D01*
G01X1076456Y490054D02*
X1077166Y490053D01*
G01X1075113Y488711D02*
X1076456Y490054D01*
G01X1075113Y486870D02*
Y488711D01*
G01X1073770Y485527D02*
X1075113Y486870D01*
G01X1072351Y485527D02*
X1073770D01*
G01X1070587Y483763D02*
X1072351Y485527D01*
G01X1070587Y482344D02*
Y483763D01*
G01X1069244Y481001D02*
X1070587Y482344D01*
G01X1068114Y481001D02*
X1069244D01*
G01X1067404Y481002D02*
X1068114Y481001D01*
G01X1066061Y479659D02*
X1067404Y481002D01*
G01X1066061Y477818D02*
Y479659D01*
G01X1064718Y476475D02*
X1066061Y477818D01*
G01X1063588Y476475D02*
X1064718D01*
G01X1062878Y476476D02*
X1063588Y476475D01*
G01X1061535Y475133D02*
X1062878Y476476D01*
G01X1061535Y473292D02*
Y475133D01*
G01X1059000Y470757D02*
X1061535Y473292D01*
G01X1089433Y519233D02*
Y530067D01*
G01X1089300Y519100D02*
X1089433Y519233D01*
G01X1089300Y516700D02*
Y519100D01*
G01X1089600Y516400D02*
X1089300Y516700D01*
G01X1089600Y514300D02*
Y516400D01*
G01X1087795Y512495D02*
X1089600Y514300D01*
G01X1087795Y510114D02*
Y512495D01*
G01X1089600Y508309D02*
X1087795Y510114D01*
G01X1089600Y498528D02*
Y508309D01*
G01X1061000Y469928D02*
X1089600Y498528D01*
G01X1055949Y519149D02*
Y538749D01*
G01X1055700Y518900D02*
X1055949Y519149D01*
G01X1055700Y516900D02*
Y518900D01*
G01X1056300Y516300D02*
X1055700Y516900D01*
G01X1056300Y514500D02*
Y516300D01*
G01X1055700Y513900D02*
X1056300Y514500D01*
G01X1055700Y511800D02*
Y513900D01*
G01X1056500Y511000D02*
X1055700Y511800D01*
G01X1056500Y500174D02*
Y511000D01*
G01X1037962Y481636D02*
X1056500Y500174D01*
G01X1065984Y521616D02*
Y529884D01*
G01X1067057Y520543D02*
X1065984Y521616D01*
G01X1067057Y517857D02*
Y520543D01*
G01X1065800Y516600D02*
X1067057Y517857D01*
G01X1065800Y514400D02*
Y516600D01*
G01X1066300Y513900D02*
X1065800Y514400D01*
G01X1066300Y511800D02*
Y513900D01*
G01X1065700Y511200D02*
X1066300Y511800D01*
G01X1065700Y509100D02*
Y511200D01*
G01X1066300Y508500D02*
X1065700Y509100D01*
G01X1066300Y499789D02*
Y508500D01*
G01X1045162Y478651D02*
X1066300Y499789D01*
G01X1092871Y519329D02*
Y530371D01*
G01X1093300Y518900D02*
X1092871Y519329D01*
G01X1093300Y517100D02*
Y518900D01*
G01X1092600Y516400D02*
X1093300Y517100D01*
G01X1092600Y514300D02*
Y516400D01*
G01X1093300Y513600D02*
X1092600Y514300D01*
G01X1093300Y512200D02*
Y513600D01*
G01X1092500Y511400D02*
X1093300Y512200D01*
G01X1092500Y509198D02*
Y511400D01*
G01X1092819Y508879D02*
X1092500Y509198D01*
G01X1092819Y497220D02*
Y508879D01*
G01X1064201Y468602D02*
X1092819Y497220D01*
G01X1082822Y519222D02*
Y530278D01*
G01X1082640Y519040D02*
X1082822Y519222D01*
G01X1082640Y516460D02*
Y519040D01*
G01X1082999Y516101D02*
X1082640Y516460D01*
G01X1082999Y514299D02*
Y516101D01*
G01X1082572Y513872D02*
X1082999Y514299D01*
G01X1082572Y511328D02*
Y513872D01*
G01X1083000Y510900D02*
X1082572Y511328D01*
G01X1083000Y501670D02*
Y510900D01*
G01X1079014Y497684D02*
X1083000Y501670D01*
G01X1079014Y497683D02*
Y497684D01*
G01X1055700Y474369D02*
X1079014Y497683D01*
G01X1045915Y514085D02*
Y532454D01*
G01X1046400Y513600D02*
X1045915Y514085D01*
G01X1046400Y512000D02*
Y513600D01*
G01X1040154Y505754D02*
X1046400Y512000D01*
G01X1040154Y504654D02*
Y505754D01*
G01X1048255Y525022D02*
Y526905D01*
G01X1048865Y524412D02*
X1048255Y525022D01*
G01X1050196Y524412D02*
X1048865D01*
G01X1050820Y523788D02*
X1050196Y524412D01*
G01X1050820Y522798D02*
Y523788D01*
G01X1050224Y522202D02*
X1050820Y522798D01*
G01X1048405Y522202D02*
X1050224D01*
G01X1047792Y521589D02*
X1048405Y522202D01*
G01X1047792Y518008D02*
Y521589D01*
G01X1050983Y514817D02*
X1047792Y518008D01*
G01X1050983Y512792D02*
Y514817D01*
G01Y502112D02*
Y512792D01*
G01X1094492Y479826D02*
X1095354D01*
G01X1093508Y478842D02*
X1094492Y479826D01*
G01X1093508Y477980D02*
Y478842D01*
G01X1095214Y476273D02*
X1093508Y477980D01*
G01X1076151Y519351D02*
Y535351D01*
G01X1075800Y519000D02*
X1076151Y519351D01*
G01X1075800Y517110D02*
Y519000D01*
G01X1076300Y516610D02*
X1075800Y517110D01*
G01X1076300Y514247D02*
Y516610D01*
G01X1077755Y512792D02*
X1076300Y514247D01*
G01X1077755Y510145D02*
Y512792D01*
G01X1074862Y507252D02*
X1077755Y510145D01*
G01X1073144Y507252D02*
X1074862D01*
G01X1072460Y506568D02*
X1073144Y507252D01*
G01X1072460Y504736D02*
Y506568D01*
G01X1073144Y504052D02*
X1072460Y504736D01*
G01X1074858Y504052D02*
X1073144D01*
G01X1075547Y503363D02*
X1074858Y504052D01*
G01X1075547Y501681D02*
Y503363D01*
G01X1050450Y476584D02*
X1075547Y501681D01*
G01X1070747Y466138D02*
X1101582Y496973D01*
G01X1059388Y516588D02*
Y530488D01*
G01X1059100Y516300D02*
X1059388Y516588D01*
G01X1059100Y514500D02*
Y516300D01*
G01X1059700Y513900D02*
X1059100Y514500D01*
G01X1059700Y512100D02*
Y513900D01*
G01X1059100Y511500D02*
X1059700Y512100D01*
G01X1059100Y499945D02*
Y511500D01*
G01X1039962Y480807D02*
X1059100Y499945D01*
G01X1068640Y525715D02*
Y526598D01*
G01X1069730Y524625D02*
X1068640Y525715D01*
G01X1070880Y524625D02*
X1069730D01*
G01X1072129Y525874D02*
X1070880Y524625D01*
G01X1073336Y525874D02*
X1072129D01*
G01X1074319Y524891D02*
X1073336Y525874D01*
G01X1074319Y522795D02*
Y524891D01*
G01X1072949Y521425D02*
X1074319Y522795D01*
G01X1070362Y521425D02*
X1072949D01*
G01X1069370Y520433D02*
X1070362Y521425D01*
G01X1069370Y518988D02*
Y520433D01*
G01X1070201Y518157D02*
X1069370Y518988D01*
G01X1071062Y518157D02*
X1070201D01*
G01X1071062Y515738D02*
Y518157D01*
G01X1072812Y513988D02*
X1071062Y515738D01*
G01X1072812Y511912D02*
Y513988D01*
G01X1070274Y509374D02*
X1072812Y511912D01*
G01X1070274Y499237D02*
Y509374D01*
G01X1048450Y477413D02*
X1070274Y499237D01*
G01X1090548Y478849D02*
X1107162Y495463D01*
G01X1090548Y474320D02*
Y478849D01*
G01X1052628Y519472D02*
Y530428D01*
G01X1052865Y519235D02*
X1052628Y519472D01*
G01X1052865Y516965D02*
Y519235D01*
G01X1052606Y516706D02*
X1052865Y516965D01*
G01X1052606Y514094D02*
Y516706D01*
G01X1053100Y513600D02*
X1052606Y514094D01*
G01X1053100Y511229D02*
Y513600D01*
G01X1054330Y509999D02*
X1053100Y511229D01*
G01X1054330Y502630D02*
Y509999D01*
G01X1034762Y483062D02*
X1054330Y502630D01*
G01X1062500Y517000D02*
Y527100D01*
G01X1062900Y516600D02*
X1062500Y517000D01*
G01X1062900Y514300D02*
Y516600D01*
G01X1062500Y513900D02*
X1062900Y514300D01*
G01X1062500Y511700D02*
Y513900D01*
G01X1063000Y511200D02*
X1062500Y511700D01*
G01X1063000Y509400D02*
Y511200D01*
G01X1062300Y508700D02*
X1063000Y509400D01*
G01X1062300Y498619D02*
Y508700D01*
G01X1043162Y479481D02*
X1062300Y498619D01*
G01X1085317Y477424D02*
X1104280Y496387D01*
G01X1085317Y476562D02*
Y477424D01*
G01X1086556Y475323D02*
X1085317Y476562D01*
G01X1086556Y474461D02*
Y475323D01*
G01X1085572Y473477D02*
X1086556Y474461D01*
G01X1084710Y473477D02*
X1085572D01*
G01X1083471Y474716D02*
X1084710Y473477D01*
G01X1082609Y474716D02*
X1083471D01*
G01X1081625Y473732D02*
X1082609Y474716D01*
G01X1081625Y472870D02*
Y473732D01*
G01X1082864Y471631D02*
X1081625Y472870D01*
G01X1082864Y470769D02*
Y471631D01*
G01X1081880Y469785D02*
X1082864Y470769D01*
G01X1081018Y469785D02*
X1081880D01*
G01X1079779Y471024D02*
X1081018Y469785D01*
G01X1078917Y471024D02*
X1079779D01*
G01X1073247Y465354D02*
X1078917Y471024D01*
G01X1087795Y587895D02*
X1089418Y589518D01*
G01X1087795Y585724D02*
Y587895D01*
G01X1087797Y585722D02*
X1087795Y585724D01*
G01X1096117Y577402D02*
X1087797Y585722D01*
G01X1084450Y572750D02*
Y574757D01*
G01X1084879Y572321D02*
X1084450Y572750D01*
G01X1084879Y569591D02*
Y572321D01*
G01X1082844Y567556D02*
X1084879Y569591D01*
G01X1082844Y560438D02*
Y567556D01*
G01X1082727Y560321D02*
X1082844Y560438D01*
G01X1082727Y555081D02*
Y560321D01*
G01X1084840Y552968D02*
X1082727Y555081D01*
G01X1084840Y548312D02*
Y552968D01*
G01X1084450Y547922D02*
X1084840Y548312D01*
G01X1079369Y542841D02*
X1084450Y547922D01*
G01X1079369Y527756D02*
Y542841D01*
G01X1080303Y526822D02*
X1079369Y527756D01*
G01X1086083Y535324D02*
X1084450Y536957D01*
G01X1086083Y527828D02*
Y535324D01*
G01X1085090Y526835D02*
X1086083Y527828D01*
G01X1050985Y585722D02*
Y590982D01*
G01X1045546Y580283D02*
X1050985Y585722D01*
G01X1035371Y580283D02*
X1045546D01*
G01X1089200Y535554D02*
X1087797Y536957D01*
G01X1089200Y530300D02*
Y535554D01*
G01X1089433Y530067D02*
X1089200Y530300D01*
G01X1065999Y573699D02*
Y588592D01*
G01X1062400Y570100D02*
X1065999Y573699D01*
G01X1062400Y568400D02*
Y570100D01*
G01X1062766Y568034D02*
X1062400Y568400D01*
G01X1062766Y554766D02*
Y568034D01*
G01X1059600Y551600D02*
X1062766Y554766D01*
G01X1059600Y549200D02*
Y551600D01*
G01X1059417Y549017D02*
X1059600Y549200D01*
G01X1059417Y546157D02*
Y549017D01*
G01X1056700Y543440D02*
X1059417Y546157D01*
G01X1056700Y539500D02*
Y543440D01*
G01X1055949Y538749D02*
X1056700Y539500D01*
G01X1077755Y574755D02*
X1077757Y574757D01*
G01X1077755Y569683D02*
Y574755D01*
G01X1079369Y568069D02*
X1077755Y569683D01*
G01X1079369Y557231D02*
Y568069D01*
G01X1079486Y557114D02*
X1079369Y557231D01*
G01X1079486Y549651D02*
Y557114D01*
G01X1077757Y547922D02*
X1079486Y549651D01*
G01X1075613Y545778D02*
X1077757Y547922D01*
G01X1071200Y545778D02*
X1075613D01*
G01X1069451Y544029D02*
X1071200Y545778D01*
G01X1069451Y542838D02*
Y544029D01*
G01X1070061Y542228D02*
X1069451Y542838D01*
G01X1072454Y542228D02*
X1070061D01*
G01X1073105Y541577D02*
X1072454Y542228D01*
G01X1073105Y540187D02*
Y541577D01*
G01X1072536Y539618D02*
X1073105Y540187D01*
G01X1070443Y539618D02*
X1072536D01*
G01X1069451Y538626D02*
X1070443Y539618D01*
G01X1069451Y535537D02*
Y538626D01*
G01X1068481Y534567D02*
X1069451Y535537D01*
G01X1068481Y532381D02*
Y534567D01*
G01X1065984Y529884D02*
X1068481Y532381D01*
G01X1084450Y587910D02*
X1084878Y588338D01*
G01X1084450Y585722D02*
Y587910D01*
G01X1089418Y580754D02*
X1084450Y585722D01*
G01X1089418Y573782D02*
Y580754D01*
G01X1092855Y570345D02*
X1089418Y573782D01*
G01X1092855Y535855D02*
Y570345D01*
G01X1092600Y535600D02*
X1092855Y535855D01*
G01X1092600Y533200D02*
Y535600D01*
G01X1093300Y532500D02*
X1092600Y533200D01*
G01X1093300Y530800D02*
Y532500D01*
G01X1092871Y530371D02*
X1093300Y530800D01*
G01X1087795Y574755D02*
X1087797Y574757D01*
G01X1087795Y569519D02*
Y574755D01*
G01X1086186Y567910D02*
X1087795Y569519D01*
G01X1086186Y565673D02*
Y567910D01*
G01X1087029Y564830D02*
X1086186Y565673D01*
G01X1087029Y561318D02*
Y564830D01*
G01X1086186Y560475D02*
X1087029Y561318D01*
G01X1086186Y554796D02*
Y560475D01*
G01X1087795Y553187D02*
X1086186Y554796D01*
G01X1087795Y547924D02*
Y553187D01*
G01X1087797Y547922D02*
X1087795Y547924D01*
G01X1087797Y546172D02*
Y547922D01*
G01X1082836Y541211D02*
X1087797Y546172D01*
G01X1082836Y535664D02*
Y541211D01*
G01X1081396Y534224D02*
X1082836Y535664D01*
G01X1081396Y531704D02*
Y534224D01*
G01X1082822Y530278D02*
X1081396Y531704D01*
G01X1054331Y569554D02*
Y574757D01*
G01X1052717Y567940D02*
X1054331Y569554D01*
G01X1052717Y552448D02*
Y567940D01*
G01X1054331Y550834D02*
X1052717Y552448D01*
G01X1054331Y547922D02*
Y550834D01*
G01X1049345Y542936D02*
X1054331Y547922D01*
G01X1049345Y535884D02*
Y542936D01*
G01X1045915Y532454D02*
X1049345Y535884D01*
G01X1050984Y536956D02*
X1050985Y536957D01*
G01X1050984Y534584D02*
Y536956D01*
G01X1049100Y532700D02*
X1050984Y534584D01*
G01X1049100Y530700D02*
Y532700D01*
G01X1049367Y530433D02*
X1049100Y530700D01*
G01X1049367Y528017D02*
Y530433D01*
G01X1048255Y526905D02*
X1049367Y528017D01*
G01X1056000Y587391D02*
Y600240D01*
G01X1054331Y585722D02*
X1056000Y587391D01*
G01X1054331Y584762D02*
Y585722D01*
G01X1047369Y577800D02*
X1054331Y584762D01*
G01X1035600Y577800D02*
X1047369D01*
G01X1076151Y535351D02*
X1077757Y536957D01*
G01Y585722D02*
Y590657D01*
G01X1076566Y584531D02*
X1077757Y585722D01*
G01X1076566Y583275D02*
Y584531D01*
G01X1078360Y581481D02*
X1076566Y583275D01*
G01X1078360Y580307D02*
Y581481D01*
G01X1076889Y578836D02*
X1078360Y580307D01*
G01X1075718Y578836D02*
X1076889D01*
G01X1073784Y580770D02*
X1075718Y578836D01*
G01X1072427Y580770D02*
X1073784D01*
G01X1070821Y579164D02*
X1072427Y580770D01*
G01X1070821Y577924D02*
Y579164D01*
G01X1072698Y576047D02*
X1070821Y577924D01*
G01X1072698Y573970D02*
Y576047D01*
G01X1071478Y572750D02*
X1072698Y573970D01*
G01X1069113Y572750D02*
X1071478D01*
G01X1065983Y569620D02*
X1069113Y572750D01*
G01X1065983Y554883D02*
Y569620D01*
G01X1062708Y551608D02*
X1065983Y554883D01*
G01X1062708Y546708D02*
Y551608D01*
G01X1059387Y543387D02*
X1062708Y546708D01*
G01X1059387Y535687D02*
Y543387D01*
G01X1059600Y535474D02*
X1059387Y535687D01*
G01X1059600Y530700D02*
Y535474D01*
G01X1059388Y530488D02*
X1059600Y530700D01*
G01X1068640Y526598D02*
X1071064Y529022D01*
G01X1054330Y536956D02*
X1054331Y536957D01*
G01X1054330Y534264D02*
Y536956D01*
G01X1053100Y533034D02*
X1054330Y534264D01*
G01X1053100Y530900D02*
Y533034D01*
G01X1052628Y530428D02*
X1053100Y530900D01*
G01X1050985Y570260D02*
Y574757D01*
G01X1049353Y568628D02*
X1050985Y570260D01*
G01X1049353Y561335D02*
Y568628D01*
G01X1049264Y561246D02*
X1049353Y561335D01*
G01X1049264Y552354D02*
Y561246D01*
G01X1050984Y550634D02*
X1049264Y552354D01*
G01X1050984Y547922D02*
Y550634D01*
G01X1048779Y545717D02*
X1050984Y547922D01*
G01X1042147Y545717D02*
X1048779D01*
G01X1041027Y544597D02*
X1042147Y545717D01*
G01X1041027Y542932D02*
Y544597D01*
G01X1039842Y541747D02*
X1041027Y542932D01*
G01X1037847Y541747D02*
X1039842D01*
G01X1071064Y564972D02*
Y566822D01*
G01X1071674Y564362D02*
X1071064Y564972D01*
G01X1075516Y564362D02*
X1071674D01*
G01X1076126Y563752D02*
X1075516Y564362D01*
G01X1076126Y562762D02*
Y563752D01*
G01X1075516Y562152D02*
X1076126Y562762D01*
G01X1071674Y562152D02*
X1075516D01*
G01X1071064Y561542D02*
X1071674Y562152D01*
G01X1071064Y560552D02*
Y561542D01*
G01X1071674Y559942D02*
X1071064Y560552D01*
G01X1075412Y559942D02*
X1071674D01*
G01X1076001Y559353D02*
X1075412Y559942D01*
G01X1076001Y558363D02*
Y559353D01*
G01X1075370Y557732D02*
X1076001Y558363D01*
G01X1071674Y557732D02*
X1075370D01*
G01X1071064Y557122D02*
X1071674Y557732D01*
G01X1071064Y555857D02*
Y557122D01*
G01X1069000Y553793D02*
X1071064Y555857D01*
G01X1069000Y549700D02*
Y553793D01*
G01X1069437Y549263D02*
X1069000Y549700D01*
G01X1069437Y546997D02*
Y549263D01*
G01X1065998Y543558D02*
X1069437Y546997D01*
G01X1065998Y535498D02*
Y543558D01*
G01X1062708Y532208D02*
X1065998Y535498D01*
G01X1062708Y527308D02*
Y532208D01*
G01X1062500Y527100D02*
X1062708Y527308D01*
G01X1087795Y607405D02*
Y609864D01*
G01X1090300Y604900D02*
X1087795Y607405D01*
G01X1090300Y595500D02*
Y604900D01*
G01X1089418Y594618D02*
X1090300Y595500D01*
G01X1089418Y589518D02*
Y594618D01*
G01X1050984Y610216D02*
Y612658D01*
G01X1049105Y608337D02*
X1050984Y610216D01*
G01X1049105Y606023D02*
Y608337D01*
G01X1049581Y605547D02*
X1049105Y606023D01*
G01X1049581Y595381D02*
Y605547D01*
G01X1049251Y595051D02*
X1049581Y595381D01*
G01X1049251Y592716D02*
Y595051D01*
G01X1050985Y590982D02*
X1049251Y592716D01*
G01X1072394Y605960D02*
X1071062Y607292D01*
G01X1072394Y601823D02*
Y605960D01*
G01X1071336Y600765D02*
X1072394Y601823D01*
G01X1065315Y600765D02*
X1071336D01*
G01X1064442Y599892D02*
X1065315Y600765D01*
G01X1064442Y598408D02*
Y599892D01*
G01X1065285Y597565D02*
X1064442Y598408D01*
G01X1070028Y597565D02*
X1065285D01*
G01X1071062Y596531D02*
X1070028Y597565D01*
G01X1071062Y593659D02*
Y596531D01*
G01X1071064Y593657D02*
X1071062Y593659D01*
G01X1065999Y588592D02*
X1071064Y593657D01*
G01X1084448Y610248D02*
Y612657D01*
G01X1082646Y608446D02*
X1084448Y610248D01*
G01X1082646Y606054D02*
Y608446D01*
G01X1083022Y605678D02*
X1082646Y606054D01*
G01X1083022Y595222D02*
Y605678D01*
G01X1082734Y594934D02*
X1083022Y595222D01*
G01X1082734Y592768D02*
Y594934D01*
G01X1084878Y590624D02*
X1082734Y592768D01*
G01X1084878Y588338D02*
Y590624D01*
G01X1054330Y607602D02*
Y609864D01*
G01X1056385Y605547D02*
X1054330Y607602D01*
G01X1056385Y600625D02*
Y605547D01*
G01X1056000Y600240D02*
X1056385Y600625D01*
G01X1077755Y610245D02*
Y612657D01*
G01X1079619Y608381D02*
X1077755Y610245D01*
G01X1079619Y606119D02*
Y608381D01*
G01X1078300Y604800D02*
X1079619Y606119D01*
G01X1078300Y596200D02*
Y604800D01*
G01X1079472Y595028D02*
X1078300Y596200D01*
G01X1079472Y592372D02*
Y595028D01*
G01X1077757Y590657D02*
X1079472Y592372D01*
G01X1125700Y29440D02*
Y34400D01*
G01X1127100Y28040D02*
X1125700Y29440D01*
G01X1127100Y19651D02*
Y28040D01*
G01X1124606Y17157D02*
X1127100Y19651D01*
G01X1123678Y16229D02*
X1124606Y17157D01*
G01X1123678Y13101D02*
Y16229D01*
G01X1126720Y10059D02*
X1123678Y13101D01*
G01X1126720Y8674D02*
Y10059D01*
G01X1125045Y6999D02*
X1126720Y8674D01*
G01X1125045Y5876D02*
Y6999D01*
G01X1126545Y4376D02*
X1125045Y5876D01*
G01X1126545Y3024D02*
Y4376D01*
G01X1125260Y1740D02*
X1126545Y3024D01*
G01X1125045Y1524D02*
X1125260Y1740D01*
G01X1125045Y301D02*
Y1524D01*
G01X1126478Y-1132D02*
X1125045Y301D01*
G01X1126478Y-2226D02*
Y-1132D01*
G01X1127952Y-3700D02*
X1126478Y-2226D01*
G01X1137992Y-8347D02*
Y-9901D01*
G01X1140239Y-6100D02*
X1137992Y-8347D01*
G01X1141463Y-6100D02*
X1140239D01*
G01X1143039Y-4524D02*
X1141463Y-6100D01*
G01X1143039Y-2900D02*
Y-4524D01*
G01X1142264Y-2125D02*
X1143039Y-2900D01*
G01X1142264Y10888D02*
Y-2125D01*
G01X1141038Y12114D02*
X1142264Y10888D01*
G01X1102241Y14100D02*
X1104227Y12114D01*
G01X1102241Y15514D02*
Y14100D01*
G01X1103800Y17073D02*
X1102241Y15514D01*
G01X1103800Y23800D02*
Y17073D01*
G01X1105841Y25841D02*
X1103800Y23800D01*
G01X1105841Y28599D02*
Y25841D01*
G01X1106091Y28849D02*
X1105841Y28599D01*
G01X1106091Y35049D02*
Y28849D01*
G01X1101181Y-8347D02*
Y-9901D01*
G01X1103428Y-6100D02*
X1101181Y-8347D01*
G01X1104652Y-6100D02*
X1103428D01*
G01X1106228Y-4524D02*
X1104652Y-6100D01*
G01X1106228Y-2900D02*
Y-4524D01*
G01X1105453Y-2125D02*
X1106228Y-2900D01*
G01X1105453Y10888D02*
Y-2125D01*
G01X1104227Y12114D02*
X1105453Y10888D01*
G01X1144685Y-7779D02*
Y-9901D01*
G01X1146564Y-5900D02*
X1144685Y-7779D01*
G01X1147964Y-5900D02*
X1146564D01*
G01X1149420Y-4444D02*
X1147964Y-5900D01*
G01X1149420Y-3100D02*
Y-4444D01*
G01X1148804Y-2484D02*
X1149420Y-3100D01*
G01X1148804Y10641D02*
Y-2484D01*
G01X1147331Y12114D02*
X1148804Y10641D01*
G01X1146464Y-3233D02*
X1147331Y-4100D01*
G01X1146464Y-932D02*
Y-3233D01*
G01X1144831Y701D02*
X1146464Y-932D01*
G01X1144831Y2000D02*
Y701D01*
G01X1146181Y3350D02*
X1144831Y2000D01*
G01X1146181Y4250D02*
Y3350D01*
G01X1144931Y5500D02*
X1146181Y4250D01*
G01X1144931Y6699D02*
Y5500D01*
G01X1146464Y8232D02*
X1144931Y6699D01*
G01X1146464Y10200D02*
Y8232D01*
G01X1143564Y13100D02*
X1146464Y10200D01*
G01X1143564Y16036D02*
Y13100D01*
G01X1144685Y17157D02*
X1143564Y16036D01*
G01X1144685Y30021D02*
Y27899D01*
G01X1146564Y31900D02*
X1144685Y30021D01*
G01X1147964Y31900D02*
X1146564D01*
G01X1149420Y33356D02*
X1147964Y31900D01*
G01X1130241Y29499D02*
Y34359D01*
G01X1129400Y28658D02*
X1130241Y29499D01*
G01X1129400Y18809D02*
Y28658D01*
G01X1126141Y15550D02*
X1129400Y18809D01*
G01X1126141Y13925D02*
Y15550D01*
G01X1127952Y12114D02*
X1126141Y13925D01*
G01X1129341Y10725D02*
X1127952Y12114D01*
G01X1129341Y-2288D02*
Y10725D01*
G01X1129953Y-2900D02*
X1129341Y-2288D01*
G01X1129953Y-4300D02*
Y-2900D01*
G01X1128153Y-6100D02*
X1129953Y-4300D01*
G01X1127153Y-6100D02*
X1128153D01*
G01X1125853Y-7400D02*
X1127153Y-6100D01*
G01X1125853Y-8654D02*
Y-7400D01*
G01X1124606Y-9901D02*
X1125853Y-8654D01*
G01X1141463Y31700D02*
X1143039Y33276D01*
G01X1140239Y31700D02*
X1141463D01*
G01X1139100Y30561D02*
X1140239Y31700D01*
G01X1139100Y29007D02*
Y30561D01*
G01X1137992Y27899D02*
X1139100Y29007D01*
G01X1101181Y24781D02*
Y17157D01*
G01X1103200Y26800D02*
X1101181Y24781D01*
G01X1103200Y28400D02*
Y26800D01*
G01X1102241Y29359D02*
X1103200Y28400D01*
G01X1102241Y34441D02*
Y29359D01*
G01X1103053Y-3012D02*
X1104141Y-4100D01*
G01X1103053Y-1132D02*
Y-3012D01*
G01X1101620Y301D02*
X1103053Y-1132D01*
G01X1101620Y1500D02*
Y301D01*
G01X1103120Y3000D02*
X1101620Y1500D01*
G01X1103120Y4200D02*
Y3000D01*
G01X1101670Y5650D02*
X1103120Y4200D01*
G01X1101670Y7049D02*
Y5650D01*
G01X1103053Y8432D02*
X1101670Y7049D01*
G01X1103053Y10301D02*
Y8432D01*
G01X1100253Y13101D02*
X1103053Y10301D01*
G01X1100253Y16229D02*
Y13101D01*
G01X1101181Y17157D02*
X1100253Y16229D01*
G01X1136641Y29249D02*
Y34759D01*
G01X1136091Y28699D02*
X1136641Y29249D01*
G01X1136091Y18964D02*
Y28699D01*
G01X1132741Y15614D02*
X1136091Y18964D01*
G01X1132741Y14018D02*
Y15614D01*
G01X1134645Y12114D02*
X1132741Y14018D01*
G01X1136034Y10725D02*
X1134645Y12114D01*
G01X1136034Y-2288D02*
Y10725D01*
G01X1136646Y-2900D02*
X1136034Y-2288D01*
G01X1136646Y-4300D02*
Y-2900D01*
G01X1134846Y-6100D02*
X1136646Y-4300D01*
G01X1133846Y-6100D02*
X1134846D01*
G01X1132546Y-7400D02*
X1133846Y-6100D01*
G01X1132546Y-8654D02*
Y-7400D01*
G01X1131299Y-9901D02*
X1132546Y-8654D01*
G01X1132741Y28999D02*
Y34641D01*
G01X1133800Y27940D02*
X1132741Y28999D01*
G01X1133800Y26400D02*
Y27940D01*
G01X1133000Y25600D02*
X1133800Y26400D01*
G01X1133000Y22901D02*
Y25600D01*
G01X1133700Y22201D02*
X1133000Y22901D01*
G01X1133700Y19558D02*
Y22201D01*
G01X1131299Y17157D02*
X1133700Y19558D01*
G01X1130178Y16036D02*
X1131299Y17157D01*
G01X1130178Y13100D02*
Y16036D01*
G01X1133520Y9758D02*
X1130178Y13100D01*
G01X1133520Y8700D02*
Y9758D01*
G01X1131720Y6900D02*
X1133520Y8700D01*
G01X1131720Y5325D02*
Y6900D01*
G01X1132920Y4125D02*
X1131720Y5325D01*
G01X1132920Y2999D02*
Y4125D01*
G01X1131720Y1799D02*
X1132920Y2999D01*
G01X1131720Y426D02*
Y1799D01*
G01X1133078Y-932D02*
X1131720Y426D01*
G01X1133078Y-2133D02*
Y-932D01*
G01X1134645Y-3700D02*
X1133078Y-2133D01*
G01X1108591Y29609D02*
Y34191D01*
G01X1109741Y28459D02*
X1108591Y29609D01*
G01X1109741Y26041D02*
Y28459D01*
G01X1107874Y24174D02*
X1109741Y26041D01*
G01X1107874Y17157D02*
Y24174D01*
G01X1106753Y16036D02*
X1107874Y17157D01*
G01X1106753Y13100D02*
Y16036D01*
G01X1109653Y10200D02*
X1106753Y13100D01*
G01X1109653Y8232D02*
Y10200D01*
G01X1108120Y6699D02*
X1109653Y8232D01*
G01X1108120Y5500D02*
Y6699D01*
G01X1109370Y4250D02*
X1108120Y5500D01*
G01X1109370Y3350D02*
Y4250D01*
G01X1108020Y2000D02*
X1109370Y3350D01*
G01X1108020Y701D02*
Y2000D01*
G01X1109653Y-932D02*
X1108020Y701D01*
G01X1109653Y-3233D02*
Y-932D01*
G01X1110520Y-4100D02*
X1109653Y-3233D01*
G01X1112441Y24941D02*
Y37141D01*
G01X1109941Y22441D02*
X1112441Y24941D01*
G01X1109941Y16742D02*
Y22441D01*
G01X1108447Y15248D02*
X1109941Y16742D01*
G01X1108447Y14187D02*
Y15248D01*
G01X1110520Y12114D02*
X1108447Y14187D01*
G01X1111993Y10641D02*
X1110520Y12114D01*
G01X1111993Y-2484D02*
Y10641D01*
G01X1112609Y-3100D02*
X1111993Y-2484D01*
G01X1112609Y-4444D02*
Y-3100D01*
G01X1111153Y-5900D02*
X1112609Y-4444D01*
G01X1109753Y-5900D02*
X1111153D01*
G01X1107874Y-7779D02*
X1109753Y-5900D01*
G01X1107874Y-9901D02*
Y-7779D01*
G01X1139864Y-3012D02*
X1140952Y-4100D01*
G01X1139864Y-1132D02*
Y-3012D01*
G01X1138431Y301D02*
X1139864Y-1132D01*
G01X1138431Y1500D02*
Y301D01*
G01X1139931Y3000D02*
X1138431Y1500D01*
G01X1139931Y4200D02*
Y3000D01*
G01X1138481Y5650D02*
X1139931Y4200D01*
G01X1138481Y7049D02*
Y5650D01*
G01X1139864Y8432D02*
X1138481Y7049D01*
G01X1139864Y10301D02*
Y8432D01*
G01X1137064Y13101D02*
X1139864Y10301D01*
G01X1137064Y16229D02*
Y13101D01*
G01X1137992Y17157D02*
X1137064Y16229D01*
G01X1126500Y91673D02*
Y101400D01*
G01X1125700Y90873D02*
X1126500Y91673D01*
G01X1125700Y86855D02*
Y90873D01*
G01X1126841Y85714D02*
X1125700Y86855D01*
G01X1126841Y84341D02*
Y85714D01*
G01X1125800Y83300D02*
X1126841Y84341D01*
G01X1125800Y75500D02*
Y83300D01*
G01X1126841Y74459D02*
X1125800Y75500D01*
G01X1126841Y73341D02*
Y74459D01*
G01X1125800Y72300D02*
X1126841Y73341D01*
G01X1125800Y67140D02*
Y72300D01*
G01X1126441Y66499D02*
X1125800Y67140D01*
G01X1126441Y53814D02*
Y66499D01*
G01X1126041Y53414D02*
X1126441Y53814D01*
G01X1126041Y48714D02*
Y53414D01*
G01X1126841Y47914D02*
X1126041Y48714D01*
G01X1126841Y46541D02*
Y47914D01*
G01X1126000Y45700D02*
X1126841Y46541D01*
G01X1126000Y37901D02*
Y45700D01*
G01X1126841Y37060D02*
X1126000Y37901D01*
G01X1126841Y35541D02*
Y37060D01*
G01X1125700Y34400D02*
X1126841Y35541D01*
G01X1105741Y35399D02*
X1106091Y35049D01*
G01X1105741Y36941D02*
Y35399D01*
G01X1106400Y37600D02*
X1105741Y36941D01*
G01X1106400Y45541D02*
Y37600D01*
G01X1105741Y46200D02*
X1106400Y45541D01*
G01X1105741Y47342D02*
Y46200D01*
G01X1106091Y47692D02*
X1105741Y47342D01*
G01X1106091Y53614D02*
Y47692D01*
G01X1106000Y53705D02*
X1106091Y53614D01*
G01X1106000Y66558D02*
Y53705D01*
G01X1106091Y66649D02*
X1106000Y66558D01*
G01X1106091Y71942D02*
Y66649D01*
G01X1105525Y72508D02*
X1106091Y71942D01*
G01X1105525Y74025D02*
Y72508D01*
G01X1106300Y74800D02*
X1105525Y74025D01*
G01X1106300Y83600D02*
Y74800D01*
G01X1105525Y84375D02*
X1106300Y83600D01*
G01X1105525Y85925D02*
Y84375D01*
G01X1106174Y86574D02*
X1105525Y85925D01*
G01X1106174Y91474D02*
Y86574D01*
G01X1105792Y91856D02*
X1106174Y91474D01*
G01X1105792Y102408D02*
Y91856D01*
G01X1146494Y92094D02*
Y105106D01*
G01X1145094Y90694D02*
X1146494Y92094D01*
G01X1145094Y86874D02*
Y90694D01*
G01X1146494Y85474D02*
X1145094Y86874D01*
G01X1146494Y84000D02*
Y85474D01*
G01X1146200Y83706D02*
X1146494Y84000D01*
G01X1146200Y75200D02*
Y83706D01*
G01X1146494Y74906D02*
X1146200Y75200D01*
G01X1146494Y73195D02*
Y74906D01*
G01X1145494Y72195D02*
X1146494Y73195D01*
G01X1145494Y67307D02*
Y72195D01*
G01X1146594Y66207D02*
X1145494Y67307D01*
G01X1146594Y64579D02*
Y66207D01*
G01X1144685Y62670D02*
X1146594Y64579D01*
G01X1144685Y54957D02*
Y62670D01*
G01X1143564Y53836D02*
X1144685Y54957D01*
G01X1143564Y50900D02*
Y53836D01*
G01X1146464Y48000D02*
X1143564Y50900D01*
G01X1146464Y46032D02*
Y48000D01*
G01X1144931Y44499D02*
X1146464Y46032D01*
G01X1144931Y43300D02*
Y44499D01*
G01X1146181Y42050D02*
X1144931Y43300D01*
G01X1146181Y41150D02*
Y42050D01*
G01X1144831Y39800D02*
X1146181Y41150D01*
G01X1144831Y38501D02*
Y39800D01*
G01X1146464Y36868D02*
X1144831Y38501D01*
G01X1146464Y34567D02*
Y36868D01*
G01X1147331Y33700D02*
X1146464Y34567D01*
G01X1149420Y34700D02*
Y33356D01*
G01X1148804Y35316D02*
X1149420Y34700D01*
G01X1148804Y48441D02*
Y35316D01*
G01X1147331Y49914D02*
X1148804Y48441D01*
G01X1145600Y51645D02*
X1147331Y49914D01*
G01X1145600Y53300D02*
Y51645D01*
G01X1146674Y54374D02*
X1145600Y53300D01*
G01X1146674Y61339D02*
Y54374D01*
G01X1149194Y63859D02*
X1146674Y61339D01*
G01X1149194Y74594D02*
Y63859D01*
G01X1149800Y75200D02*
X1149194Y74594D01*
G01X1149800Y83294D02*
Y75200D01*
G01X1149194Y83900D02*
X1149800Y83294D01*
G01X1149194Y105101D02*
Y83900D01*
G01X1129400Y91755D02*
Y94864D01*
G01X1130141Y91014D02*
X1129400Y91755D01*
G01X1130141Y86514D02*
Y91014D01*
G01X1129341Y85714D02*
X1130141Y86514D01*
G01X1129341Y83800D02*
Y85714D01*
G01X1129700Y83441D02*
X1129341Y83800D01*
G01X1129700Y75100D02*
Y83441D01*
G01X1129341Y74741D02*
X1129700Y75100D01*
G01X1129341Y73159D02*
Y74741D01*
G01X1130241Y72259D02*
X1129341Y73159D01*
G01X1130241Y67299D02*
Y72259D01*
G01X1129441Y66499D02*
X1130241Y67299D01*
G01X1129441Y53914D02*
Y66499D01*
G01X1129874Y53481D02*
X1129441Y53914D01*
G01X1129874Y48447D02*
Y53481D01*
G01X1129341Y47914D02*
X1129874Y48447D01*
G01X1129341Y46259D02*
Y47914D01*
G01X1130000Y45600D02*
X1129341Y46259D01*
G01X1130000Y37399D02*
Y45600D01*
G01X1129341Y36740D02*
X1130000Y37399D01*
G01X1129341Y35259D02*
Y36740D01*
G01X1130241Y34359D02*
X1129341Y35259D01*
G01X1096288Y85612D02*
Y102212D01*
G01X1096300Y85600D02*
X1096288Y85612D01*
G01X1096300Y37300D02*
Y85600D01*
G01X1096108Y37108D02*
X1096300Y37300D01*
G01X1096108Y34308D02*
Y37108D01*
G01X1142264Y48688D02*
X1141038Y49914D01*
G01X1142264Y35675D02*
Y48688D01*
G01X1143039Y34900D02*
X1142264Y35675D01*
G01X1143039Y33276D02*
Y34900D01*
G01X1142694Y91474D02*
Y105308D01*
G01X1142994Y91174D02*
X1142694Y91474D01*
G01X1142994Y86474D02*
Y91174D01*
G01X1142594Y86074D02*
X1142994Y86474D01*
G01X1142594Y84006D02*
Y86074D01*
G01X1143100Y83500D02*
X1142594Y84006D01*
G01X1143100Y75200D02*
Y83500D01*
G01X1142594Y74694D02*
X1143100Y75200D01*
G01X1142594Y72959D02*
Y74694D01*
G01X1142894Y72659D02*
X1142594Y72959D01*
G01X1142894Y67359D02*
Y72659D01*
G01X1142594Y67059D02*
X1142894Y67359D01*
G01X1142594Y63022D02*
Y67059D01*
G01X1140874Y61302D02*
X1142594Y63022D01*
G01X1140874Y57126D02*
Y61302D01*
G01X1141038Y56962D02*
X1140874Y57126D01*
G01X1141038Y49914D02*
Y56962D01*
G01X1103300Y35500D02*
X1102241Y34441D01*
G01X1103300Y36900D02*
Y35500D01*
G01X1102600Y37600D02*
X1103300Y36900D01*
G01X1102600Y45500D02*
Y37600D01*
G01X1103300Y46200D02*
X1102600Y45500D01*
G01X1103300Y47399D02*
Y46200D01*
G01X1102377Y48322D02*
X1103300Y47399D01*
G01X1102377Y53178D02*
Y48322D01*
G01X1103900Y54701D02*
X1102377Y53178D01*
G01X1103900Y65500D02*
Y54701D01*
G01X1102241Y67159D02*
X1103900Y65500D01*
G01X1102241Y72275D02*
Y67159D01*
G01X1103025Y73059D02*
X1102241Y72275D01*
G01X1103025Y74775D02*
Y73059D01*
G01X1102400Y75400D02*
X1103025Y74775D01*
G01X1102400Y83375D02*
Y75400D01*
G01X1103025Y84000D02*
X1102400Y83375D01*
G01X1103025Y85823D02*
Y84000D01*
G01X1102374Y86474D02*
X1103025Y85823D01*
G01X1102374Y91074D02*
Y86474D01*
G01X1103069Y91769D02*
X1102374Y91074D01*
G01X1103069Y101066D02*
Y91769D01*
G01X1136000Y92015D02*
Y120246D01*
G01X1136741Y91274D02*
X1136000Y92015D01*
G01X1136741Y86614D02*
Y91274D01*
G01X1136041Y85914D02*
X1136741Y86614D01*
G01X1136041Y84000D02*
Y85914D01*
G01X1136600Y83441D02*
X1136041Y84000D01*
G01X1136600Y75200D02*
Y83441D01*
G01X1136041Y74641D02*
X1136600Y75200D01*
G01X1136041Y73159D02*
Y74641D01*
G01X1136641Y72559D02*
X1136041Y73159D01*
G01X1136641Y67049D02*
Y72559D01*
G01X1135900Y66308D02*
X1136641Y67049D01*
G01X1135900Y54055D02*
Y66308D01*
G01X1136474Y53481D02*
X1135900Y54055D01*
G01X1136474Y48547D02*
Y53481D01*
G01X1135500Y47573D02*
X1136474Y48547D01*
G01X1135500Y35900D02*
Y47573D01*
G01X1136641Y34759D02*
X1135500Y35900D01*
G01X1133500Y92001D02*
Y119210D01*
G01X1132700Y91201D02*
X1133500Y92001D01*
G01X1132700Y86355D02*
Y91201D01*
G01X1133562Y85493D02*
X1132700Y86355D01*
G01X1133562Y84361D02*
Y85493D01*
G01X1132800Y83599D02*
X1133562Y84361D01*
G01X1132800Y75200D02*
Y83599D01*
G01X1133705Y74295D02*
X1132800Y75200D01*
G01X1133705Y73505D02*
Y74295D01*
G01X1132741Y72541D02*
X1133705Y73505D01*
G01X1132741Y66799D02*
Y72541D01*
G01X1134000Y65540D02*
X1132741Y66799D01*
G01X1134000Y64600D02*
Y65540D01*
G01X1133174Y63774D02*
X1134000Y64600D01*
G01X1133174Y62826D02*
Y63774D01*
G01X1134000Y62000D02*
X1133174Y62826D01*
G01X1134000Y60926D02*
Y62000D01*
G01X1133174Y60100D02*
X1134000Y60926D01*
G01X1133174Y58726D02*
Y60100D01*
G01X1133900Y58000D02*
X1133174Y58726D01*
G01X1133900Y56926D02*
Y58000D01*
G01X1133174Y56200D02*
X1133900Y56926D01*
G01X1133174Y53847D02*
Y56200D01*
G01X1132400Y53073D02*
X1133174Y53847D01*
G01X1132400Y48855D02*
Y53073D01*
G01X1133241Y48014D02*
X1132400Y48855D01*
G01X1133241Y46242D02*
Y48014D01*
G01X1132300Y45301D02*
X1133241Y46242D01*
G01X1132300Y41974D02*
Y45301D01*
G01X1132900Y41374D02*
X1132300Y41974D01*
G01X1132900Y40099D02*
Y41374D01*
G01X1132200Y39399D02*
X1132900Y40099D01*
G01X1132200Y37900D02*
Y39399D01*
G01X1133241Y36859D02*
X1132200Y37900D01*
G01X1133241Y35141D02*
Y36859D01*
G01X1132741Y34641D02*
X1133241Y35141D01*
G01X1109774Y92024D02*
Y102226D01*
G01X1108674Y90924D02*
X1109774Y92024D01*
G01X1108674Y86574D02*
Y90924D01*
G01X1109600Y85648D02*
X1108674Y86574D01*
G01X1109600Y83700D02*
Y85648D01*
G01X1109375Y83475D02*
X1109600Y83700D01*
G01X1109375Y75566D02*
Y83475D01*
G01X1109674Y75267D02*
X1109375Y75566D01*
G01X1109674Y73174D02*
Y75267D01*
G01X1108591Y72091D02*
X1109674Y73174D01*
G01X1108591Y67409D02*
Y72091D01*
G01X1109941Y66059D02*
X1108591Y67409D01*
G01X1109941Y54542D02*
Y66059D01*
G01X1108591Y53192D02*
X1109941Y54542D01*
G01X1108591Y48914D02*
Y53192D01*
G01X1109600Y47905D02*
X1108591Y48914D01*
G01X1109600Y46059D02*
Y47905D01*
G01X1109200Y45659D02*
X1109600Y46059D01*
G01X1109200Y37800D02*
Y45659D01*
G01X1109700Y37300D02*
X1109200Y37800D01*
G01X1109700Y35300D02*
Y37300D01*
G01X1108591Y34191D02*
X1109700Y35300D01*
G01X1112441Y83959D02*
Y105050D01*
G01X1113100Y83300D02*
X1112441Y83959D01*
G01X1113100Y75659D02*
Y83300D01*
G01X1112441Y75000D02*
X1113100Y75659D01*
G01X1112441Y46254D02*
Y75000D01*
G01X1113008Y45687D02*
X1112441Y46254D01*
G01X1113008Y37708D02*
Y45687D01*
G01X1112441Y37141D02*
X1113008Y37708D01*
G01X1137992Y61457D02*
Y54957D01*
G01X1139894Y63359D02*
X1137992Y61457D01*
G01X1139894Y66307D02*
Y63359D01*
G01X1139094Y67107D02*
X1139894Y66307D01*
G01X1139094Y72159D02*
Y67107D01*
G01X1139894Y72959D02*
X1139094Y72159D01*
G01X1139894Y74706D02*
Y72959D01*
G01X1139300Y75300D02*
X1139894Y74706D01*
G01X1139300Y83406D02*
Y75300D01*
G01X1139894Y84000D02*
X1139300Y83406D01*
G01X1139894Y85574D02*
Y84000D01*
G01X1139094Y86374D02*
X1139894Y85574D01*
G01X1139094Y90974D02*
Y86374D01*
G01X1140100Y91980D02*
X1139094Y90974D01*
G01X1140100Y105300D02*
Y91980D01*
G01X1139864Y34788D02*
X1140952Y33700D01*
G01X1139864Y36636D02*
Y34788D01*
G01X1138000Y38500D02*
X1139864Y36636D01*
G01X1138000Y39301D02*
Y38500D01*
G01X1139931Y41232D02*
X1138000Y39301D01*
G01X1139931Y41968D02*
Y41232D01*
G01X1138000Y43899D02*
X1139931Y41968D01*
G01X1138000Y44500D02*
Y43899D01*
G01X1139864Y46364D02*
X1138000Y44500D01*
G01X1139864Y48101D02*
Y46364D01*
G01X1138700Y49265D02*
X1139864Y48101D01*
G01X1138700Y54249D02*
Y49265D01*
G01X1137992Y54957D02*
X1138700Y54249D01*
G01X1126900Y117200D02*
Y118738D01*
G01X1125200Y115500D02*
X1126900Y117200D01*
G01X1125200Y114652D02*
Y115500D01*
G01X1126000Y113852D02*
X1125200Y114652D01*
G01X1128123Y113852D02*
X1126000D01*
G01X1128923Y113052D02*
X1128123Y113852D01*
G01X1128923Y111452D02*
Y113052D01*
G01X1128123Y110652D02*
X1128923Y111452D01*
G01X1126000Y110652D02*
X1128123D01*
G01X1125200Y109852D02*
X1126000Y110652D01*
G01X1125200Y108252D02*
Y109852D01*
G01X1126000Y107452D02*
X1125200Y108252D01*
G01X1127100Y107452D02*
X1126000D01*
G01X1127900Y106652D02*
X1127100Y107452D01*
G01X1127900Y105052D02*
Y106652D01*
G01X1127100Y104252D02*
X1127900Y105052D01*
G01X1126000Y104252D02*
X1127100D01*
G01X1125200Y103452D02*
X1126000Y104252D01*
G01X1125200Y102700D02*
Y103452D01*
G01X1126500Y101400D02*
X1125200Y102700D01*
G01X1104000Y104200D02*
X1105792Y102408D01*
G01X1104000Y111249D02*
Y104200D01*
G01X1115859Y153116D02*
Y166859D01*
G01X1139875Y129100D02*
X1115859Y153116D01*
G01X1158900Y129100D02*
X1139875D01*
G01X1144685Y112207D02*
X1144535Y112357D01*
G01X1144685Y106915D02*
Y112207D01*
G01X1146494Y105106D02*
X1144685Y106915D01*
G01X1145100Y147000D02*
X1133000Y159100D01*
G01X1173083Y147000D02*
X1145100D01*
G01X1147331Y106964D02*
X1149194Y105101D01*
G01X1131000Y96464D02*
Y118174D01*
G01X1129400Y94864D02*
X1131000Y96464D01*
G01X1145000Y154000D02*
X1137988Y161012D01*
G01X1173155Y154000D02*
X1145000D01*
G01X1142694Y105308D02*
X1141038Y106964D01*
G01X1130288Y155912D02*
Y171439D01*
G01X1132391Y153809D02*
X1130288Y155912D01*
G01X1133183Y153809D02*
X1132391D01*
G01X1134041Y154667D02*
X1133183Y153809D01*
G01X1134833Y154667D02*
X1134041D01*
G01X1135852Y153648D02*
X1134833Y154667D01*
G01X1135852Y152856D02*
Y153648D01*
G01X1134994Y151998D02*
X1135852Y152856D01*
G01X1134994Y151206D02*
Y151998D01*
G01X1136013Y150187D02*
X1134994Y151206D01*
G01X1136805Y150187D02*
X1136013D01*
G01X1137663Y151045D02*
X1136805Y150187D01*
G01X1138455Y151045D02*
X1137663D01*
G01X1139474Y150026D02*
X1138455Y151045D01*
G01X1139474Y149234D02*
Y150026D01*
G01X1138616Y148376D02*
X1139474Y149234D01*
G01X1138616Y147584D02*
Y148376D01*
G01X1141100Y145100D02*
X1138616Y147584D01*
G01X1171275Y145100D02*
X1141100D01*
G01X1101400Y102735D02*
X1103069Y101066D01*
G01X1101400Y110601D02*
Y102735D01*
G01X1113389Y152050D02*
Y166274D01*
G01X1139239Y126200D02*
X1113389Y152050D01*
G01X1155754Y126200D02*
X1139239D01*
G01X1161754Y120200D02*
X1155754Y126200D01*
G01X1106393Y156137D02*
X1106953Y156697D01*
G01X1104460Y156137D02*
X1106393D01*
G01X1103900Y155577D02*
X1104460Y156137D01*
G01X1103900Y154137D02*
Y155577D01*
G01X1104460Y153577D02*
X1103900Y154137D01*
G01X1106393Y153577D02*
X1104460D01*
G01X1106953Y153017D02*
X1106393Y153577D01*
G01X1106953Y149293D02*
Y153017D01*
G01X1136000Y120246D02*
X1106953Y149293D01*
G01X1097463Y155515D02*
Y157405D01*
G01X1098073Y154905D02*
X1097463Y155515D01*
G01X1099778Y154905D02*
X1098073D01*
G01X1100388Y154295D02*
X1099778Y154905D01*
G01X1100388Y152322D02*
Y154295D01*
G01X1133500Y119210D02*
X1100388Y152322D01*
G01X1097454Y129659D02*
X1096321Y130792D01*
G01X1097454Y128528D02*
Y129659D01*
G01X1095252Y125196D02*
Y126326D01*
G01X1097514Y124063D02*
X1096385D01*
G01X1099717Y126266D02*
X1097514Y124063D01*
G01X1100847Y126266D02*
X1099717D01*
G01X1101980Y125133D02*
X1100847Y126266D01*
G01X1101980Y124002D02*
Y125133D01*
G01X1100735Y122757D02*
X1101980Y124002D01*
G01X1100735Y121965D02*
Y122757D01*
G01X1102206Y120494D02*
X1100735Y121965D01*
G01X1102998Y120494D02*
X1102206D01*
G01X1104244Y121740D02*
X1102998Y120494D01*
G01X1105373Y121740D02*
X1104244D01*
G01X1106500Y120613D02*
X1105373Y121740D01*
G01X1106500Y105500D02*
Y120613D01*
G01X1109774Y102226D02*
X1106500Y105500D01*
G01X1144076Y151800D02*
X1136000Y159876D01*
G01X1146768Y151800D02*
X1144076D01*
G01X1147328Y151240D02*
X1146768Y151800D01*
G01X1147328Y149960D02*
Y151240D01*
G01X1147888Y149400D02*
X1147328Y149960D01*
G01X1149328Y149400D02*
X1147888D01*
G01X1149888Y149960D02*
X1149328Y149400D01*
G01X1149888Y151240D02*
Y149960D01*
G01X1150448Y151800D02*
X1149888Y151240D01*
G01X1151888Y151800D02*
X1150448D01*
G01X1152448Y151240D02*
X1151888Y151800D01*
G01X1152448Y149960D02*
Y151240D01*
G01X1153008Y149400D02*
X1152448Y149960D01*
G01X1154448Y149400D02*
X1153008D01*
G01X1155348Y150300D02*
X1154448Y149400D01*
G01X1173319Y150300D02*
X1155348D01*
G01X1109000Y120718D02*
Y121649D01*
G01X1109800Y119918D02*
X1109000Y120718D01*
G01X1110600Y119918D02*
X1109800D01*
G01X1111400Y119118D02*
X1110600Y119918D01*
G01X1111400Y117518D02*
Y119118D01*
G01X1110600Y116718D02*
X1111400Y117518D01*
G01X1109800Y116718D02*
X1110600D01*
G01X1109000Y115918D02*
X1109800Y116718D01*
G01X1109000Y106900D02*
Y115918D01*
G01X1110050Y105850D02*
X1109000Y106900D01*
G01X1111641Y105850D02*
X1110050D01*
G01X1112441Y105050D02*
X1111641Y105850D01*
G01X1111374Y150529D02*
Y164649D01*
G01X1143903Y118000D02*
X1111374Y150529D01*
G01X1149181Y118000D02*
X1143903D01*
G01X1149981Y118800D02*
X1149181Y118000D01*
G01X1149981Y122800D02*
Y118800D01*
G01X1150781Y123600D02*
X1149981Y122800D01*
G01X1152381Y123600D02*
X1150781D01*
G01X1153181Y122800D02*
X1152381Y123600D01*
G01X1153181Y116260D02*
Y122800D01*
G01X1153741Y115700D02*
X1153181Y116260D01*
G01X1175354Y115700D02*
X1153741D01*
G01X1138242Y107158D02*
X1140100Y105300D01*
G01X1138242Y112357D02*
Y107158D01*
G01X1118264Y154248D02*
Y168028D01*
G01X1139426Y133086D02*
X1118264Y154248D01*
G01X1143192Y133086D02*
X1139426D01*
G01X1145178Y131100D02*
X1143192Y133086D01*
G01X1170563Y131100D02*
X1145178D01*
G01X1144400Y182900D02*
X1157099D01*
G01X1133100Y194200D02*
X1144400Y182900D01*
G01X1103892Y178826D02*
Y185697D01*
G01X1115859Y166859D02*
X1103892Y178826D01*
G01X1150200Y200300D02*
X1162400D01*
G01X1145000Y205500D02*
X1150200Y200300D01*
G01X1119556Y185280D02*
Y187055D01*
G01X1133000Y171836D02*
X1119556Y185280D01*
G01X1133000Y159100D02*
Y171836D01*
G01X1149400Y195600D02*
X1160899D01*
G01X1142200Y202800D02*
X1149400Y195600D01*
G01X1149900Y197900D02*
X1161600D01*
G01X1143300Y204500D02*
X1149900Y197900D01*
G01X1145400Y176100D02*
X1130750Y190750D01*
G01X1158101Y176100D02*
X1145400D01*
G01X1124556Y185980D02*
Y187055D01*
G01X1137988Y172548D02*
X1124556Y185980D01*
G01X1137988Y161012D02*
Y172548D01*
G01X1117056Y184671D02*
Y187055D01*
G01X1130288Y171439D02*
X1117056Y184671D01*
G01X1148700Y193200D02*
X1159900D01*
G01X1141450Y200450D02*
X1148700Y193200D01*
G01X1101200Y178463D02*
Y185669D01*
G01X1113389Y166274D02*
X1101200Y178463D01*
G01X1106953Y156697D02*
Y164714D01*
G01X1100388Y164845D02*
Y167835D01*
G01X1099778Y164235D02*
X1100388Y164845D01*
G01X1098073Y164235D02*
X1099778D01*
G01X1097463Y163625D02*
X1098073Y164235D01*
G01X1097463Y161735D02*
Y163625D01*
G01X1098073Y161125D02*
X1097463Y161735D01*
G01X1099778Y161125D02*
X1098073D01*
G01X1100388Y160515D02*
X1099778Y161125D01*
G01X1100388Y158625D02*
Y160515D01*
G01X1099778Y158015D02*
X1100388Y158625D01*
G01X1098073Y158015D02*
X1099778D01*
G01X1097463Y157405D02*
X1098073Y158015D01*
G01X1129400Y189000D02*
Y189500D01*
G01X1144300Y174100D02*
X1129400Y189000D01*
G01X1153801Y174100D02*
X1144300D01*
G01X1160700Y167201D02*
X1153801Y174100D01*
G01X1122056Y185478D02*
Y187055D01*
G01X1136000Y171534D02*
X1122056Y185478D01*
G01X1136000Y159876D02*
Y171534D01*
G01X1099000Y177023D02*
Y185848D01*
G01X1111374Y164649D02*
X1099000Y177023D01*
G01X1106100Y180192D02*
Y185400D01*
G01X1118264Y168028D02*
X1106100Y180192D01*
G01X1145600Y178900D02*
X1158500D01*
G01X1131200Y193300D02*
X1145600Y178900D01*
G01X1118687Y442487D02*
X1144933Y468733D01*
G01X1118687Y421025D02*
Y442487D01*
G01X1155206Y427900D02*
X1162123Y434817D01*
G01X1148276Y427900D02*
X1155206D01*
G01X1135756Y415380D02*
X1148276Y427900D01*
G01X1135756Y412641D02*
Y415380D01*
G01X1108581Y447764D02*
X1141115Y480298D01*
G01X1108581Y420405D02*
Y447764D01*
G01X1106081Y448800D02*
X1140485Y483204D01*
G01X1106081Y420405D02*
Y448800D01*
G01X1156915Y426015D02*
X1164469Y433569D01*
G01X1149938Y426015D02*
X1156915D01*
G01X1138256Y414333D02*
X1149938Y426015D01*
G01X1146094Y459094D02*
X1179752D01*
G01X1126187Y439187D02*
X1146094Y459094D01*
G01X1126187Y419941D02*
Y439187D01*
G01X1144673Y461273D02*
X1175784D01*
G01X1123687Y440287D02*
X1144673Y461273D01*
G01X1123687Y419941D02*
Y440287D01*
G01X1147300Y452200D02*
X1182020D01*
G01X1133600Y438500D02*
X1147300Y452200D01*
G01X1133600Y432973D02*
Y438500D01*
G01X1134210Y432363D02*
X1133600Y432973D01*
G01X1135699Y432363D02*
X1134210D01*
G01X1136309Y431753D02*
X1135699Y432363D01*
G01X1136309Y430363D02*
Y431753D01*
G01X1135699Y429753D02*
X1136309Y430363D01*
G01X1134210Y429753D02*
X1135699D01*
G01X1133600Y429143D02*
X1134210Y429753D01*
G01X1133600Y414931D02*
Y429143D01*
G01X1099936Y449727D02*
X1138509Y488300D01*
G01X1099936Y421086D02*
Y449727D01*
G01X1101081Y419941D02*
X1099936Y421086D01*
G01X1156410Y464370D02*
Y465748D01*
G01X1155800Y463760D02*
X1156410Y464370D01*
G01X1154410Y463760D02*
X1155800D01*
G01X1153800Y464370D02*
X1154410Y463760D01*
G01X1153800Y466139D02*
Y464370D01*
G01X1151190D02*
Y466139D01*
G01X1150580Y463760D02*
X1151190Y464370D01*
G01X1149190Y463760D02*
X1150580D01*
G01X1148580Y464370D02*
X1149190Y463760D01*
G01X1148580Y466139D02*
Y464370D01*
G01X1145970D02*
Y466139D01*
G01X1145360Y463760D02*
X1145970Y464370D01*
G01X1143360Y463760D02*
X1145360D01*
G01X1121187Y441587D02*
X1143360Y463760D01*
G01X1121187Y421025D02*
Y441587D01*
G01X1154988Y411200D02*
X1178884Y435096D01*
G01X1149816Y411200D02*
X1154988D01*
G01X1148959Y410343D02*
X1149816Y411200D01*
G01X1155682Y408768D02*
X1179720Y432806D01*
G01X1150934Y408768D02*
X1155682D01*
G01X1150734Y408568D02*
X1150934Y408768D01*
G01X1095936Y451714D02*
X1135498Y491276D01*
G01X1095936Y417064D02*
Y451714D01*
G01X1099000Y414000D02*
X1095936Y417064D01*
G01X1099000Y406860D02*
Y414000D01*
G01X1098631Y406491D02*
X1099000Y406860D01*
G01X1102436Y448691D02*
X1139965Y486220D01*
G01X1102436Y423264D02*
Y448691D01*
G01X1103800Y421900D02*
X1102436Y423264D01*
G01X1103800Y420160D02*
Y421900D01*
G01X1146400Y454600D02*
X1180955D01*
G01X1130800Y439000D02*
X1146400Y454600D01*
G01X1130800Y414631D02*
Y439000D01*
G01X1130756Y414587D02*
X1130800Y414631D01*
G01X1156940Y406900D02*
X1180722Y430682D01*
G01X1152716Y406900D02*
X1156940D01*
G01X1152559Y406743D02*
X1152716Y406900D01*
G01X1154399Y404903D02*
X1158085D01*
G01X1096093Y518007D02*
Y531205D01*
G01X1096500Y517600D02*
X1096093Y518007D01*
G01X1096500Y514800D02*
Y517600D01*
G01X1095500Y513800D02*
X1096500Y514800D01*
G01X1095500Y511800D02*
Y513800D01*
G01X1096500Y510800D02*
X1095500Y511800D01*
G01X1096500Y498000D02*
Y510800D01*
G01X1144933Y468733D02*
X1159327D01*
G01X1126441Y517357D02*
Y529842D01*
G01X1126041Y516957D02*
X1126441Y517357D01*
G01X1126041Y512057D02*
Y516957D01*
G01X1126391Y511707D02*
X1126041Y512057D01*
G01X1126391Y509435D02*
Y511707D01*
G01X1123654Y506698D02*
X1126391Y509435D01*
G01X1123654Y489778D02*
Y506698D01*
G01X1156344Y480298D02*
X1157734D01*
G01X1155734Y479688D02*
X1156344Y480298D01*
G01X1155734Y478478D02*
Y479688D01*
G01X1155124Y477868D02*
X1155734Y478478D01*
G01X1153734Y477868D02*
X1155124D01*
G01X1153124Y478478D02*
X1153734Y477868D01*
G01X1153124Y479688D02*
Y478478D01*
G01X1152514Y480298D02*
X1153124Y479688D01*
G01X1141115Y480298D02*
X1152514D01*
G01X1140485Y483204D02*
X1176657D01*
G01X1112900Y519059D02*
Y528100D01*
G01X1112441Y518600D02*
X1112900Y519059D01*
G01X1112441Y509359D02*
Y518600D01*
G01X1113600Y508200D02*
X1112441Y509359D01*
G01X1113600Y506551D02*
Y508200D01*
G01X1112990Y505941D02*
X1113600Y506551D01*
G01X1110508Y505941D02*
X1112990D01*
G01X1109898Y505331D02*
X1110508Y505941D01*
G01X1109898Y503351D02*
Y505331D01*
G01X1110508Y502741D02*
X1109898Y503351D01*
G01X1112990Y502741D02*
X1110508D01*
G01X1113600Y502131D02*
X1112990Y502741D01*
G01X1113600Y500151D02*
Y502131D01*
G01X1112990Y499541D02*
X1113600Y500151D01*
G01X1110508Y499541D02*
X1112990D01*
G01X1109898Y498931D02*
X1110508Y499541D01*
G01X1109898Y496951D02*
Y498931D01*
G01X1110253Y496596D02*
X1109898Y496951D01*
G01X1110253Y495888D02*
Y496596D01*
G01X1100102Y485737D02*
X1110253Y495888D01*
G01X1100102Y480299D02*
Y485737D01*
G01X1097922Y478119D02*
X1100102Y480299D01*
G01X1097060Y478119D02*
X1097922D01*
G01X1095354Y479826D02*
X1097060Y478119D01*
G01X1095214Y475411D02*
Y476273D01*
G01X1133104Y517004D02*
Y529903D01*
G01X1132768Y516668D02*
X1133104Y517004D01*
G01X1132768Y511630D02*
Y516668D01*
G01X1133145Y511253D02*
X1132768Y511630D01*
G01X1133145Y509244D02*
Y511253D01*
G01X1131028Y507127D02*
X1133145Y509244D01*
G01X1131028Y490354D02*
Y507127D01*
G01X1146400Y519552D02*
Y527900D01*
G01X1146552Y519400D02*
X1146400Y519552D01*
G01X1146552Y517457D02*
Y519400D01*
G01X1145402Y516307D02*
X1146552Y517457D01*
G01X1145402Y512057D02*
Y516307D01*
G01X1146752Y510707D02*
X1145402Y512057D01*
G01X1146752Y507366D02*
Y510707D01*
G01X1144385Y504999D02*
X1146752Y507366D01*
G01X1144385Y498487D02*
Y504999D01*
G01X1145374Y492851D02*
X1147331Y490894D01*
G01X1145374Y493974D02*
Y492851D01*
G01X1146674Y495274D02*
X1145374Y493974D01*
G01X1146674Y503752D02*
Y495274D01*
G01X1149252Y506330D02*
X1146674Y503752D01*
G01X1149252Y518600D02*
Y506330D01*
G01X1149700Y519048D02*
X1149252Y518600D01*
G01X1149700Y527900D02*
Y519048D01*
G01X1102900Y519741D02*
Y527800D01*
G01X1103141Y519500D02*
X1102900Y519741D01*
G01X1103141Y517357D02*
Y519500D01*
G01X1102241Y516457D02*
X1103141Y517357D01*
G01X1102241Y511797D02*
Y516457D01*
G01X1103141Y510897D02*
X1102241Y511797D01*
G01X1103141Y509200D02*
Y510897D01*
G01X1101582Y507641D02*
X1103141Y509200D01*
G01X1101582Y496973D02*
Y507641D01*
G01X1138509Y488300D02*
X1170201D01*
G01X1156410Y465748D02*
X1157048Y466386D01*
G01X1153190Y466749D02*
X1153800Y466139D01*
G01X1151800Y466749D02*
X1153190D01*
G01X1151190Y466139D02*
X1151800Y466749D01*
G01X1147970D02*
X1148580Y466139D01*
G01X1146580Y466749D02*
X1147970D01*
G01X1145970Y466139D02*
X1146580Y466749D01*
G01X1129600Y519459D02*
Y527600D01*
G01X1129441Y519300D02*
X1129600Y519459D01*
G01X1129441Y517357D02*
Y519300D01*
G01X1130241Y516557D02*
X1129441Y517357D01*
G01X1130241Y512157D02*
Y516557D01*
G01X1129341Y511257D02*
X1130241Y512157D01*
G01X1129341Y509201D02*
Y511257D01*
G01X1126084Y505944D02*
X1129341Y509201D01*
G01X1126084Y503877D02*
Y505944D01*
G01X1126694Y503267D02*
X1126084Y503877D01*
G01X1128212Y503267D02*
X1126694D01*
G01X1128822Y502657D02*
X1128212Y503267D01*
G01X1128822Y501267D02*
Y502657D01*
G01X1128212Y500657D02*
X1128822Y501267D01*
G01X1126694Y500657D02*
X1128212D01*
G01X1126084Y500047D02*
X1126694Y500657D01*
G01X1126084Y498657D02*
Y500047D01*
G01X1126694Y498047D02*
X1126084Y498657D01*
G01X1128212Y498047D02*
X1126694D01*
G01X1128822Y497437D02*
X1128212Y498047D01*
G01X1128822Y496047D02*
Y497437D01*
G01X1128212Y495437D02*
X1128822Y496047D01*
G01X1126694Y495437D02*
X1128212D01*
G01X1126084Y494827D02*
X1126694Y495437D01*
G01X1126084Y493437D02*
Y494827D01*
G01X1126694Y492827D02*
X1126084Y493437D01*
G01X1127512Y492827D02*
X1126694D01*
G01X1128022Y492317D02*
X1127512Y492827D01*
G01X1128022Y490610D02*
Y492317D01*
G01X1109600Y519441D02*
Y527900D01*
G01X1109941Y519100D02*
X1109600Y519441D01*
G01X1109941Y517657D02*
Y519100D01*
G01X1108591Y516307D02*
X1109941Y517657D01*
G01X1108591Y512057D02*
Y516307D01*
G01X1109941Y510707D02*
X1108591Y512057D01*
G01X1109941Y509441D02*
Y510707D01*
G01X1107162Y506662D02*
X1109941Y509441D01*
G01X1107162Y495463D02*
Y506662D01*
G01X1136300Y519709D02*
Y527700D01*
G01X1136091Y519500D02*
X1136300Y519709D01*
G01X1136091Y517357D02*
Y519500D01*
G01X1137100Y516348D02*
X1136091Y517357D01*
G01X1137100Y512100D02*
Y516348D01*
G01X1135498Y510498D02*
X1137100Y512100D01*
G01X1135498Y505916D02*
Y510498D01*
G01X1134888Y505306D02*
X1135498Y505916D01*
G01X1133594Y505306D02*
X1134888D01*
G01X1132984Y504696D02*
X1133594Y505306D01*
G01X1132984Y503306D02*
Y504696D01*
G01X1133594Y502696D02*
X1132984Y503306D01*
G01X1134888Y502696D02*
X1133594D01*
G01X1135498Y502086D02*
X1134888Y502696D01*
G01X1135498Y491276D02*
Y502086D01*
G01X1139965Y486220D02*
X1170821D01*
G01X1139700Y500195D02*
X1137992Y498487D01*
G01X1139700Y508699D02*
Y500195D01*
G01X1140052Y509051D02*
X1139700Y508699D01*
G01X1140052Y510757D02*
Y509051D01*
G01X1139052Y511757D02*
X1140052Y510757D01*
G01X1139052Y516457D02*
Y511757D01*
G01X1139952Y517357D02*
X1139052Y516457D01*
G01X1139952Y519600D02*
Y517357D01*
G01X1139700Y519852D02*
X1139952Y519600D01*
G01X1139700Y528000D02*
Y519852D01*
G01X1142874Y492980D02*
X1141038Y491144D01*
G01X1142874Y494326D02*
Y492980D01*
G01X1141985Y495215D02*
X1142874Y494326D01*
G01X1141985Y499063D02*
Y495215D01*
G01X1142552Y499630D02*
X1141985Y499063D01*
G01X1142552Y510657D02*
Y499630D01*
G01X1142902Y511007D02*
X1142552Y510657D01*
G01X1142902Y517207D02*
Y511007D01*
G01X1142652Y517457D02*
X1142902Y517207D01*
G01X1142652Y519100D02*
Y517457D01*
G01X1143000Y519448D02*
X1142652Y519100D01*
G01X1143000Y527800D02*
Y519448D01*
G01X1106200Y519799D02*
Y527500D01*
G01X1105400Y518999D02*
X1106200Y519799D01*
G01X1105400Y517500D02*
Y518999D01*
G01X1106700Y516200D02*
X1105400Y517500D01*
G01X1106700Y512356D02*
Y516200D01*
G01X1105841Y511497D02*
X1106700Y512356D01*
G01X1105841Y509159D02*
Y511497D01*
G01X1104280Y507598D02*
X1105841Y509159D01*
G01X1104280Y496387D02*
Y507598D01*
G01X1096117Y567783D02*
Y577402D01*
G01X1096600Y567300D02*
X1096117Y567783D01*
G01X1096600Y557300D02*
Y567300D01*
G01X1096279Y556979D02*
X1096600Y557300D01*
G01X1096279Y552079D02*
Y556979D01*
G01X1095974Y551774D02*
X1096279Y552079D01*
G01X1095974Y549026D02*
Y551774D01*
G01X1096500Y548500D02*
X1095974Y549026D01*
G01X1096500Y538600D02*
Y548500D01*
G01X1096200Y538300D02*
X1096500Y538600D01*
G01X1096200Y531312D02*
Y538300D01*
G01X1096093Y531205D02*
X1096200Y531312D01*
G01X1126448Y586750D02*
X1124173Y589025D01*
G01X1126448Y573849D02*
Y586750D01*
G01X1125568Y572969D02*
X1126448Y573849D01*
G01X1125568Y568470D02*
Y572969D01*
G01X1126641Y567397D02*
X1125568Y568470D01*
G01X1126641Y555357D02*
Y567397D01*
G01X1126041Y554757D02*
X1126641Y555357D01*
G01X1126041Y549857D02*
Y554757D01*
G01X1126503Y549395D02*
X1126041Y549857D01*
G01X1126503Y536404D02*
Y549395D01*
G01X1126041Y535942D02*
X1126503Y536404D01*
G01X1126041Y530242D02*
Y535942D01*
G01X1126441Y529842D02*
X1126041Y530242D01*
G01X1112441Y586443D02*
X1110520Y588364D01*
G01X1112441Y584759D02*
Y586443D01*
G01X1112900Y584300D02*
X1112441Y584759D01*
G01X1112900Y575959D02*
Y584300D01*
G01X1112441Y575500D02*
X1112900Y575959D01*
G01X1112441Y565759D02*
Y575500D01*
G01X1112900Y565300D02*
X1112441Y565759D01*
G01X1112900Y556999D02*
Y565300D01*
G01X1112441Y556540D02*
X1112900Y556999D01*
G01X1112441Y546459D02*
Y556540D01*
G01X1112900Y546000D02*
X1112441Y546459D01*
G01X1112900Y538159D02*
Y546000D01*
G01X1112441Y537700D02*
X1112900Y538159D01*
G01X1112441Y528559D02*
Y537700D01*
G01X1112900Y528100D02*
X1112441Y528559D01*
G01X1133404Y586444D02*
X1130861Y588987D01*
G01X1133404Y574389D02*
Y586444D01*
G01X1132300Y573285D02*
X1133404Y574389D01*
G01X1132300Y568538D02*
Y573285D01*
G01X1133222Y567616D02*
X1132300Y568538D01*
G01X1133222Y565622D02*
Y567616D01*
G01X1132975Y565375D02*
X1133222Y565622D01*
G01X1132975Y557566D02*
Y565375D01*
G01X1133348Y557193D02*
X1132975Y557566D01*
G01X1133348Y554948D02*
Y557193D01*
G01X1132500Y554100D02*
X1133348Y554948D01*
G01X1132500Y549800D02*
Y554100D01*
G01X1133180Y549120D02*
X1132500Y549800D01*
G01X1133180Y536081D02*
Y549120D01*
G01X1132200Y535101D02*
X1133180Y536081D01*
G01X1132200Y530807D02*
Y535101D01*
G01X1133104Y529903D02*
X1132200Y530807D01*
G01X1143252Y554524D02*
X1144685Y555957D01*
G01X1143252Y552007D02*
Y554524D01*
G01X1146602Y548657D02*
X1143252Y552007D01*
G01X1146602Y546502D02*
Y548657D01*
G01X1146400Y546300D02*
X1146602Y546502D01*
G01X1146400Y537802D02*
Y546300D01*
G01X1146602Y537600D02*
X1146400Y537802D01*
G01X1146602Y536503D02*
Y537600D01*
G01X1145452Y535353D02*
X1146602Y536503D01*
G01X1145452Y530547D02*
Y535353D01*
G01X1146552Y529447D02*
X1145452Y530547D01*
G01X1146552Y528052D02*
Y529447D01*
G01X1146400Y527900D02*
X1146552Y528052D01*
G01X1149252Y528348D02*
X1149700Y527900D01*
G01X1149252Y537700D02*
Y528348D01*
G01X1149700Y538148D02*
X1149252Y537700D01*
G01X1149700Y546100D02*
Y538148D01*
G01X1149252Y546548D02*
X1149700Y546100D01*
G01X1149252Y548643D02*
Y546548D01*
G01X1147331Y550564D02*
X1149252Y548643D01*
G01X1147331Y550914D02*
Y550564D01*
G01X1103091Y586457D02*
X1100100Y589448D01*
G01X1103091Y584991D02*
Y586457D01*
G01X1102900Y584800D02*
X1103091Y584991D01*
G01X1102900Y575691D02*
Y584800D01*
G01X1103091Y575500D02*
X1102900Y575691D01*
G01X1103091Y573942D02*
Y575500D01*
G01X1102093Y572944D02*
X1103091Y573942D01*
G01X1102093Y568207D02*
Y572944D01*
G01X1103141Y567159D02*
X1102093Y568207D01*
G01X1103141Y565941D02*
Y567159D01*
G01X1102800Y565600D02*
X1103141Y565941D01*
G01X1102800Y557641D02*
Y565600D01*
G01X1103141Y557300D02*
X1102800Y557641D01*
G01X1103141Y555157D02*
Y557300D01*
G01X1102241Y554257D02*
X1103141Y555157D01*
G01X1102241Y549557D02*
Y554257D01*
G01X1103241Y548557D02*
X1102241Y549557D01*
G01X1103241Y546841D02*
Y548557D01*
G01X1102900Y546500D02*
X1103241Y546841D01*
G01X1102900Y538241D02*
Y546500D01*
G01X1103241Y537900D02*
X1102900Y538241D01*
G01X1103241Y536242D02*
Y537900D01*
G01X1102241Y535242D02*
X1103241Y536242D01*
G01X1102241Y530258D02*
Y535242D01*
G01X1103141Y529358D02*
X1102241Y530258D01*
G01X1103141Y528041D02*
Y529358D01*
G01X1102900Y527800D02*
X1103141Y528041D01*
G01X1129298Y587368D02*
X1127952Y588714D01*
G01X1129341Y587368D02*
X1129298D01*
G01X1129341Y584559D02*
Y587368D01*
G01X1129600Y584300D02*
X1129341Y584559D01*
G01X1129600Y575759D02*
Y584300D01*
G01X1129341Y575500D02*
X1129600Y575759D01*
G01X1129341Y574059D02*
Y575500D01*
G01X1130007Y573393D02*
X1129341Y574059D01*
G01X1130007Y568163D02*
Y573393D01*
G01X1129441Y567597D02*
X1130007Y568163D01*
G01X1129441Y565859D02*
Y567597D01*
G01X1129600Y565700D02*
X1129441Y565859D01*
G01X1129600Y557659D02*
Y565700D01*
G01X1129141Y557200D02*
X1129600Y557659D01*
G01X1129141Y555457D02*
Y557200D01*
G01X1130241Y554357D02*
X1129141Y555457D01*
G01X1130241Y549957D02*
Y554357D01*
G01X1129341Y549057D02*
X1130241Y549957D01*
G01X1129341Y546759D02*
Y549057D01*
G01X1129600Y546500D02*
X1129341Y546759D01*
G01X1129600Y537959D02*
Y546500D01*
G01X1129341Y537700D02*
X1129600Y537959D01*
G01X1129341Y536458D02*
Y537700D01*
G01X1130141Y535658D02*
X1129341Y536458D01*
G01X1130141Y530542D02*
Y535658D01*
G01X1129441Y529842D02*
X1130141Y530542D01*
G01X1129441Y527759D02*
Y529842D01*
G01X1129600Y527600D02*
X1129441Y527759D01*
G01X1109791Y586457D02*
X1106441Y589807D01*
G01X1109791Y584891D02*
Y586457D01*
G01X1109500Y584600D02*
X1109791Y584891D01*
G01X1109500Y575891D02*
Y584600D01*
G01X1109791Y575600D02*
X1109500Y575891D01*
G01X1109791Y574291D02*
Y575600D01*
G01X1108641Y573141D02*
X1109791Y574291D01*
G01X1108641Y568359D02*
Y573141D01*
G01X1109741Y567259D02*
X1108641Y568359D01*
G01X1109741Y566041D02*
Y567259D01*
G01X1109500Y565800D02*
X1109741Y566041D01*
G01X1109500Y557541D02*
Y565800D01*
G01X1109741Y557300D02*
X1109500Y557541D01*
G01X1109741Y555257D02*
Y557300D01*
G01X1108591Y554107D02*
X1109741Y555257D01*
G01X1108591Y549857D02*
Y554107D01*
G01X1109941Y548507D02*
X1108591Y549857D01*
G01X1109941Y547141D02*
Y548507D01*
G01X1109600Y546800D02*
X1109941Y547141D01*
G01X1109600Y538601D02*
Y546800D01*
G01X1109941Y538260D02*
X1109600Y538601D01*
G01X1109941Y536640D02*
Y538260D01*
G01X1108591Y535290D02*
X1109941Y536640D01*
G01X1108591Y530608D02*
Y535290D01*
G01X1109941Y529258D02*
X1108591Y530608D01*
G01X1109941Y528241D02*
Y529258D01*
G01X1109600Y527900D02*
X1109941Y528241D01*
G01X1135941Y587470D02*
X1134645Y588766D01*
G01X1135941Y584659D02*
Y587470D01*
G01X1136300Y584300D02*
X1135941Y584659D01*
G01X1136300Y575659D02*
Y584300D01*
G01X1135941Y575300D02*
X1136300Y575659D01*
G01X1135941Y574058D02*
Y575300D01*
G01X1136941Y573058D02*
X1135941Y574058D01*
G01X1136941Y568497D02*
Y573058D01*
G01X1136091Y567647D02*
X1136941Y568497D01*
G01X1136091Y554809D02*
Y567647D01*
G01X1136041Y546659D02*
Y549641D01*
G01X1136300Y546400D02*
X1136041Y546659D01*
G01X1136300Y538499D02*
Y546400D01*
G01X1135700Y537899D02*
X1136300Y538499D01*
G01X1135700Y536499D02*
Y537899D01*
G01X1136741Y535458D02*
X1135700Y536499D01*
G01X1136741Y530466D02*
Y535458D01*
G01X1136091Y529816D02*
X1136741Y530466D01*
G01X1136091Y527909D02*
Y529816D01*
G01X1136300Y527700D02*
X1136091Y527909D01*
G01X1139952Y528252D02*
X1139700Y528000D01*
G01X1139952Y529449D02*
Y528252D01*
G01X1138904Y530497D02*
X1139952Y529449D01*
G01X1138904Y535144D02*
Y530497D01*
G01X1139902Y536142D02*
X1138904Y535144D01*
G01X1139902Y537800D02*
Y536142D01*
G01X1139700Y538002D02*
X1139902Y537800D01*
G01X1139700Y546400D02*
Y538002D01*
G01X1139902Y546602D02*
X1139700Y546400D01*
G01X1139902Y549186D02*
Y546602D01*
G01X1137988Y551100D02*
X1139902Y549186D01*
G01X1142652Y528148D02*
X1143000Y527800D01*
G01X1142652Y530197D02*
Y528148D01*
G01X1143152Y530697D02*
X1142652Y530197D01*
G01X1143152Y534856D02*
Y530697D01*
G01X1142552Y535456D02*
X1143152Y534856D01*
G01X1142552Y537600D02*
Y535456D01*
G01X1143000Y538048D02*
X1142552Y537600D01*
G01X1143000Y546100D02*
Y538048D01*
G01X1142552Y546548D02*
X1143000Y546100D01*
G01X1142552Y549400D02*
Y546548D01*
G01X1141038Y550914D02*
X1142552Y549400D01*
G01X1105741Y587200D02*
X1104227Y588714D01*
G01X1105741Y584959D02*
Y587200D01*
G01X1106200Y584500D02*
X1105741Y584959D01*
G01X1106200Y575859D02*
Y584500D01*
G01X1105741Y575400D02*
X1106200Y575859D01*
G01X1105741Y573256D02*
Y575400D01*
G01X1106341Y572656D02*
X1105741Y573256D01*
G01X1106341Y568497D02*
Y572656D01*
G01X1105841Y567997D02*
X1106341Y568497D01*
G01X1105841Y565859D02*
Y567997D01*
G01X1106200Y565500D02*
X1105841Y565859D01*
G01X1106200Y557699D02*
Y565500D01*
G01X1105486Y556985D02*
X1106200Y557699D01*
G01X1105486Y554814D02*
Y556985D01*
G01X1106400Y553900D02*
X1105486Y554814D01*
G01X1106400Y549800D02*
Y553900D01*
G01X1105500Y548900D02*
X1106400Y549800D01*
G01X1105500Y546900D02*
Y548900D01*
G01X1106200Y546200D02*
X1105500Y546900D01*
G01X1106200Y538199D02*
Y546200D01*
G01X1105636Y537635D02*
X1106200Y538199D01*
G01X1105636Y536263D02*
Y537635D01*
G01X1106400Y535499D02*
X1105636Y536263D01*
G01X1106400Y530499D02*
Y535499D01*
G01X1105541Y529640D02*
X1106400Y530499D01*
G01X1105541Y528159D02*
Y529640D01*
G01X1106200Y527500D02*
X1105541Y528159D01*
G01X1122901Y605649D02*
X1127952Y610700D01*
G01X1122901Y595462D02*
Y605649D01*
G01X1124606Y593757D02*
X1122901Y595462D01*
G01X1124173Y593324D02*
X1124606Y593757D01*
G01X1124173Y589025D02*
Y593324D01*
G01X1142980Y595462D02*
X1144685Y593757D01*
G01X1142980Y606480D02*
Y595462D01*
G01X1147700Y611200D02*
X1142980Y606480D01*
G01X1136287Y595462D02*
X1137992Y593757D01*
G01X1136287Y605435D02*
Y595462D01*
G01X1136909Y606057D02*
X1136287Y605435D01*
G01X1136909Y607245D02*
Y606057D01*
G01X1141332Y611668D02*
X1136909Y607245D01*
G01X1108854Y604499D02*
X1107874D01*
G01X1109453Y603900D02*
X1108854Y604499D01*
G01X1109453Y602700D02*
Y603900D01*
G01X1108509Y601756D02*
X1109453Y602700D01*
G01X1108509Y600544D02*
Y601756D01*
G01X1109353Y599700D02*
X1108509Y600544D01*
G01X1109353Y598000D02*
Y599700D01*
G01X1108509Y597156D02*
X1109353Y598000D01*
G01X1108509Y595736D02*
Y597156D01*
G01X1109653Y594592D02*
X1108509Y595736D01*
G01X1109653Y592999D02*
Y594592D01*
G01X1108746Y592092D02*
X1109653Y592999D01*
G01X1108746Y590400D02*
Y592092D01*
G01X1110432Y588714D02*
X1108746Y590400D01*
G01X1110520Y588714D02*
X1110432D01*
G01X1110520Y588364D02*
Y588714D01*
G01X1129594Y605649D02*
X1134645Y610700D01*
G01X1129594Y595462D02*
Y605649D01*
G01X1131299Y593757D02*
X1129594Y595462D01*
G01X1130861Y593319D02*
X1131299Y593757D01*
G01X1130861Y588987D02*
Y593319D01*
G01X1103153Y610300D02*
X1104141D01*
G01X1100098Y607245D02*
X1103153Y610300D01*
G01X1100098Y606057D02*
Y607245D01*
G01X1099476Y605435D02*
X1100098Y606057D01*
G01X1099476Y595462D02*
Y605435D01*
G01X1101181Y593757D02*
X1099476Y595462D01*
G01X1100100Y592676D02*
X1101181Y593757D01*
G01X1100100Y589448D02*
Y592676D01*
G01X1147243Y588714D02*
X1147331D01*
G01X1145557Y590400D02*
X1147243Y588714D01*
G01X1145557Y592092D02*
Y590400D01*
G01X1146464Y592999D02*
X1145557Y592092D01*
G01X1146464Y594592D02*
Y592999D01*
G01X1145320Y595736D02*
X1146464Y594592D01*
G01X1145320Y597156D02*
Y595736D01*
G01X1146164Y598000D02*
X1145320Y597156D01*
G01X1146164Y599700D02*
Y598000D01*
G01X1145320Y600544D02*
X1146164Y599700D01*
G01X1145320Y601756D02*
Y600544D01*
G01X1146264Y602700D02*
X1145320Y601756D01*
G01X1146264Y603900D02*
Y602700D01*
G01X1145665Y604499D02*
X1146264Y603900D01*
G01X1144685Y604499D02*
X1145665D01*
G01X1140950Y588714D02*
X1141038D01*
G01X1139264Y590400D02*
X1140950Y588714D01*
G01X1139264Y592600D02*
Y590400D01*
G01X1139764Y593100D02*
X1139264Y592600D01*
G01X1139764Y594999D02*
Y593100D01*
G01X1138627Y596136D02*
X1139764Y594999D01*
G01X1138627Y597464D02*
Y596136D01*
G01X1139564Y598401D02*
X1138627Y597464D01*
G01X1139564Y599799D02*
Y598401D01*
G01X1138627Y600736D02*
X1139564Y599799D01*
G01X1138627Y601964D02*
Y600736D01*
G01X1139664Y603001D02*
X1138627Y601964D01*
G01X1139664Y603899D02*
Y603001D01*
G01X1139064Y604499D02*
X1139664Y603899D01*
G01X1137992Y604499D02*
X1139064D01*
G01X1125678D02*
X1124606D01*
G01X1126378Y603799D02*
X1125678Y604499D01*
G01X1126378Y602525D02*
Y603799D01*
G01X1125241Y601388D02*
X1126378Y602525D01*
G01X1125241Y600312D02*
Y601388D01*
G01X1125426Y600126D02*
X1125241Y600312D01*
G01X1126253Y599300D02*
X1125426Y600126D01*
G01X1126253Y598100D02*
Y599300D01*
G01X1125241Y597088D02*
X1126253Y598100D01*
G01X1125241Y596012D02*
Y597088D01*
G01X1126353Y594900D02*
X1125241Y596012D01*
G01X1126353Y592267D02*
Y594900D01*
G01X1126178Y592092D02*
X1126353Y592267D01*
G01X1126178Y590400D02*
Y592092D01*
G01X1127864Y588714D02*
X1126178Y590400D01*
G01X1127952Y588714D02*
X1127864D01*
G01X1109354Y610300D02*
X1110520D01*
G01X1106169Y607115D02*
X1109354Y610300D01*
G01X1106169Y595462D02*
Y607115D01*
G01X1107874Y593757D02*
X1106169Y595462D01*
G01X1106441Y592324D02*
X1107874Y593757D01*
G01X1106441Y589807D02*
Y592324D01*
G01X1132371Y604499D02*
X1131299D01*
G01X1133071Y603799D02*
X1132371Y604499D01*
G01X1133071Y602525D02*
Y603799D01*
G01X1131934Y601388D02*
X1133071Y602525D01*
G01X1131934Y600312D02*
Y601388D01*
G01X1132946Y599300D02*
X1131934Y600312D01*
G01X1132946Y598100D02*
Y599300D01*
G01X1131934Y597088D02*
X1132946Y598100D01*
G01X1131934Y596012D02*
Y597088D01*
G01X1133046Y594900D02*
X1131934Y596012D01*
G01X1133046Y592267D02*
Y594900D01*
G01X1132871Y592092D02*
X1133046Y592267D01*
G01X1132871Y590400D02*
Y592092D01*
G01X1134557Y588714D02*
X1132871Y590400D01*
G01X1134645Y588714D02*
X1134557D01*
G01X1134645Y588766D02*
Y588714D01*
G01X1102253Y604499D02*
X1101181D01*
G01X1102853Y603899D02*
X1102253Y604499D01*
G01X1102853Y603001D02*
Y603899D01*
G01X1101816Y601964D02*
X1102853Y603001D01*
G01X1101816Y600736D02*
Y601964D01*
G01X1102753Y599799D02*
X1101816Y600736D01*
G01X1102753Y598401D02*
Y599799D01*
G01X1101816Y597464D02*
X1102753Y598401D01*
G01X1101816Y596136D02*
Y597464D01*
G01X1102953Y594999D02*
X1101816Y596136D01*
G01X1102953Y593100D02*
Y594999D01*
G01X1102453Y592600D02*
X1102953Y593100D01*
G01X1102453Y590400D02*
Y592600D01*
G01X1104139Y588714D02*
X1102453Y590400D01*
G01X1104227Y588714D02*
X1104139D01*
G01X1218307Y-7779D02*
Y-9901D01*
G01X1220186Y-5900D02*
X1218307Y-7779D01*
G01X1182213Y29594D02*
Y34213D01*
G01X1183363Y28444D02*
X1182213Y29594D01*
G01X1183363Y26663D02*
Y28444D01*
G01X1181496Y24796D02*
X1183363Y26663D01*
G01X1181496Y17157D02*
Y24796D01*
G01X1183275Y-3233D02*
X1184142Y-4100D01*
G01X1183275Y-932D02*
Y-3233D01*
G01X1181642Y701D02*
X1183275Y-932D01*
G01X1181642Y2000D02*
Y701D01*
G01X1182992Y3350D02*
X1181642Y2000D01*
G01X1182992Y4250D02*
Y3350D01*
G01X1181742Y5500D02*
X1182992Y4250D01*
G01X1181742Y6699D02*
Y5500D01*
G01X1183275Y8232D02*
X1181742Y6699D01*
G01X1183275Y10200D02*
Y8232D01*
G01X1180375Y13100D02*
X1183275Y10200D01*
G01X1180375Y16036D02*
Y13100D01*
G01X1181496Y17157D02*
X1180375Y16036D01*
G01X1169357Y-8654D02*
X1168110Y-9901D01*
G01X1169357Y-7400D02*
Y-8654D01*
G01X1170657Y-6100D02*
X1169357Y-7400D01*
G01X1171657Y-6100D02*
X1170657D01*
G01X1173457Y-4300D02*
X1171657Y-6100D01*
G01X1173457Y-2900D02*
Y-4300D01*
G01X1172845Y-2288D02*
X1173457Y-2900D01*
G01X1172845Y10725D02*
Y-2288D01*
G01X1171456Y12114D02*
X1172845Y10725D01*
G01X1202963D02*
X1201574Y12114D01*
G01X1202963Y-2288D02*
Y10725D01*
G01X1203575Y-2900D02*
X1202963Y-2288D01*
G01X1203575Y-4300D02*
Y-2900D01*
G01X1201775Y-6100D02*
X1203575Y-4300D01*
G01X1200775Y-6100D02*
X1201775D01*
G01X1199475Y-7400D02*
X1200775Y-6100D01*
G01X1199475Y-8654D02*
Y-7400D01*
G01X1198228Y-9901D02*
X1199475Y-8654D01*
G01X1203500Y29136D02*
Y34900D01*
G01X1203121Y28757D02*
X1203500Y29136D01*
G01X1203121Y18920D02*
Y28757D01*
G01X1199763Y15562D02*
X1203121Y18920D01*
G01X1199763Y13925D02*
Y15562D01*
G01X1201574Y12114D02*
X1199763Y13925D01*
G01X1162664Y29146D02*
X1161417Y27899D01*
G01X1162664Y30400D02*
Y29146D01*
G01X1163964Y31700D02*
X1162664Y30400D01*
G01X1164964Y31700D02*
X1163964D01*
G01X1166764Y33500D02*
X1164964Y31700D01*
G01X1216524Y28849D02*
Y35049D01*
G01X1216200Y28525D02*
X1216524Y28849D01*
G01X1216200Y19040D02*
Y28525D01*
G01X1212792Y15632D02*
X1216200Y19040D01*
G01X1212792Y13982D02*
Y15632D01*
G01X1214660Y12114D02*
X1212792Y13982D01*
G01X1215886Y10888D02*
X1214660Y12114D01*
G01X1215886Y-2125D02*
Y10888D01*
G01X1216661Y-2900D02*
X1215886Y-2125D01*
G01X1216661Y-4524D02*
Y-2900D01*
G01X1215085Y-6100D02*
X1216661Y-4524D01*
G01X1213861Y-6100D02*
X1215085D01*
G01X1211614Y-8347D02*
X1213861Y-6100D01*
G01X1211614Y-9901D02*
Y-8347D01*
G01X1210263Y29249D02*
Y34637D01*
G01X1209713Y28699D02*
X1210263Y29249D01*
G01X1209713Y18964D02*
Y28699D01*
G01X1206363Y15614D02*
X1209713Y18964D01*
G01X1206363Y14018D02*
Y15614D01*
G01X1208267Y12114D02*
X1206363Y14018D01*
G01X1209656Y10725D02*
X1208267Y12114D01*
G01X1209656Y-2288D02*
Y10725D01*
G01X1210268Y-2900D02*
X1209656Y-2288D01*
G01X1210268Y-4300D02*
Y-2900D01*
G01X1208468Y-6100D02*
X1210268Y-4300D01*
G01X1207468Y-6100D02*
X1208468D01*
G01X1206168Y-7400D02*
X1207468Y-6100D01*
G01X1206168Y-8654D02*
Y-7400D01*
G01X1204921Y-9901D02*
X1206168Y-8654D01*
G01X1197300Y16229D02*
X1198228Y17157D01*
G01X1197300Y13101D02*
Y16229D01*
G01X1200342Y10059D02*
X1197300Y13101D01*
G01X1200342Y8674D02*
Y10059D01*
G01X1198667Y6999D02*
X1200342Y8674D01*
G01X1198667Y5876D02*
Y6999D01*
G01X1200167Y4376D02*
X1198667Y5876D01*
G01X1200167Y3024D02*
Y4376D01*
G01X1198667Y1524D02*
X1200167Y3024D01*
G01X1198667Y301D02*
Y1524D01*
G01X1200100Y-1132D02*
X1198667Y301D01*
G01X1200100Y-2226D02*
Y-1132D01*
G01X1201574Y-3700D02*
X1200100Y-2226D01*
G01X1199663Y29099D02*
Y34763D01*
G01X1200263Y28499D02*
X1199663Y29099D01*
G01X1200263Y19192D02*
Y28499D01*
G01X1198228Y17157D02*
X1200263Y19192D01*
G01X1169889Y-2133D02*
X1171456Y-3700D01*
G01X1169889Y-932D02*
Y-2133D01*
G01X1168531Y426D02*
X1169889Y-932D01*
G01X1168531Y1799D02*
Y426D01*
G01X1169731Y2999D02*
X1168531Y1799D01*
G01X1169731Y4125D02*
Y2999D01*
G01X1168531Y5325D02*
X1169731Y4125D01*
G01X1168531Y6900D02*
Y5325D01*
G01X1170331Y8700D02*
X1168531Y6900D01*
G01X1170331Y9758D02*
Y8700D01*
G01X1166989Y13100D02*
X1170331Y9758D01*
G01X1166989Y16036D02*
Y13100D01*
G01X1168110Y17157D02*
X1166989Y16036D01*
G01X1179713Y28849D02*
Y35049D01*
G01X1179463Y28599D02*
X1179713Y28849D01*
G01X1179463Y26263D02*
Y28599D01*
G01X1178000Y24800D02*
X1179463Y26263D01*
G01X1178000Y17651D02*
Y24800D01*
G01X1175863Y15514D02*
X1178000Y17651D01*
G01X1175863Y14104D02*
Y15514D01*
G01X1176999Y12968D02*
X1175863Y14104D01*
G01X1176999Y12964D02*
Y12968D01*
G01X1177849Y12114D02*
X1176999Y12964D01*
G01X1179075Y10888D02*
X1177849Y12114D01*
G01X1179075Y-2125D02*
Y10888D01*
G01X1179850Y-2900D02*
X1179075Y-2125D01*
G01X1179850Y-4524D02*
Y-2900D01*
G01X1178274Y-6100D02*
X1179850Y-4524D01*
G01X1177050Y-6100D02*
X1178274D01*
G01X1174803Y-8347D02*
X1177050Y-6100D01*
G01X1174803Y-9901D02*
Y-8347D01*
G01X1162664Y-8654D02*
X1161417Y-9901D01*
G01X1162664Y-7400D02*
Y-8654D01*
G01X1163964Y-6100D02*
X1162664Y-7400D01*
G01X1164964Y-6100D02*
X1163964D01*
G01X1166764Y-4300D02*
X1164964Y-6100D01*
G01X1166764Y-2900D02*
Y-4300D01*
G01X1166152Y-2288D02*
X1166764Y-2900D01*
G01X1166152Y10725D02*
Y-2288D01*
G01X1164763Y12114D02*
X1166152Y10725D01*
G01X1212674Y29327D02*
Y34299D01*
G01X1213600Y28401D02*
X1212674Y29327D01*
G01X1213600Y27000D02*
Y28401D01*
G01X1212866Y26266D02*
X1213600Y27000D01*
G01X1212866Y25134D02*
Y26266D01*
G01X1213584Y24416D02*
X1212866Y25134D01*
G01X1213584Y23284D02*
Y24416D01*
G01X1212800Y22500D02*
X1213584Y23284D01*
G01X1212800Y21414D02*
Y22500D01*
G01X1213700Y20514D02*
X1212800Y21414D01*
G01X1213700Y19243D02*
Y20514D01*
G01X1211614Y17157D02*
X1213700Y19243D01*
G01X1210686Y16229D02*
X1211614Y17157D01*
G01X1210686Y13101D02*
Y16229D01*
G01X1213486Y10301D02*
X1210686Y13101D01*
G01X1213486Y8432D02*
Y10301D01*
G01X1212103Y7049D02*
X1213486Y8432D01*
G01X1212103Y5650D02*
Y7049D01*
G01X1213553Y4200D02*
X1212103Y5650D01*
G01X1213553Y3000D02*
Y4200D01*
G01X1212053Y1500D02*
X1213553Y3000D01*
G01X1212053Y301D02*
Y1500D01*
G01X1213486Y-1132D02*
X1212053Y301D01*
G01X1213486Y-3012D02*
Y-1132D01*
G01X1214574Y-4100D02*
X1213486Y-3012D01*
G01X1203800Y16036D02*
X1204921Y17157D01*
G01X1203800Y13100D02*
Y16036D01*
G01X1207142Y9758D02*
X1203800Y13100D01*
G01X1207142Y8700D02*
Y9758D01*
G01X1205342Y6900D02*
X1207142Y8700D01*
G01X1205342Y5325D02*
Y6900D01*
G01X1206542Y4125D02*
X1205342Y5325D01*
G01X1206542Y2999D02*
Y4125D01*
G01X1205342Y1799D02*
X1206542Y2999D01*
G01X1205342Y426D02*
Y1799D01*
G01X1206700Y-932D02*
X1205342Y426D01*
G01X1206700Y-2133D02*
Y-932D01*
G01X1208267Y-3700D02*
X1206700Y-2133D01*
G01X1206400Y29000D02*
Y34900D01*
G01X1207163Y28237D02*
X1206400Y29000D01*
G01X1207163Y19399D02*
Y28237D01*
G01X1204921Y17157D02*
X1207163Y19399D01*
G01X1175863Y29437D02*
Y34299D01*
G01X1176763Y28537D02*
X1175863Y29437D01*
G01X1176763Y27063D02*
Y28537D01*
G01X1174803Y25103D02*
X1176763Y27063D01*
G01X1174803Y17157D02*
Y25103D01*
G01X1173875Y16229D02*
X1174803Y17157D01*
G01X1173875Y13101D02*
Y16229D01*
G01X1176675Y10301D02*
X1173875Y13101D01*
G01X1176675Y8432D02*
Y10301D01*
G01X1175292Y7049D02*
X1176675Y8432D01*
G01X1175292Y5650D02*
Y7049D01*
G01X1176742Y4200D02*
X1175292Y5650D01*
G01X1176742Y3000D02*
Y4200D01*
G01X1175242Y1500D02*
X1176742Y3000D01*
G01X1175242Y301D02*
Y1500D01*
G01X1176675Y-1132D02*
X1175242Y301D01*
G01X1176675Y-3012D02*
Y-1132D01*
G01X1177763Y-4100D02*
X1176675Y-3012D01*
G01X1171657Y31700D02*
X1173457Y33500D01*
G01X1170657Y31700D02*
X1171657D01*
G01X1169357Y30400D02*
X1170657Y31700D01*
G01X1169357Y29146D02*
Y30400D01*
G01X1168110Y27899D02*
X1169357Y29146D01*
G01X1163289Y-2226D02*
X1164763Y-3700D01*
G01X1163289Y-1132D02*
Y-2226D01*
G01X1161856Y301D02*
X1163289Y-1132D01*
G01X1161856Y1524D02*
Y301D01*
G01X1163356Y3024D02*
X1161856Y1524D01*
G01X1163356Y4376D02*
Y3024D01*
G01X1161856Y5876D02*
X1163356Y4376D01*
G01X1161856Y6999D02*
Y5876D01*
G01X1163531Y8674D02*
X1161856Y6999D01*
G01X1163531Y10059D02*
Y8674D01*
G01X1160489Y13101D02*
X1163531Y10059D01*
G01X1160489Y16229D02*
Y13101D01*
G01X1161417Y17157D02*
X1160489Y16229D01*
G01X1185615Y10641D02*
X1184142Y12114D01*
G01X1185615Y-2484D02*
Y10641D01*
G01X1186231Y-3100D02*
X1185615Y-2484D01*
G01X1186231Y-4444D02*
Y-3100D01*
G01X1184775Y-5900D02*
X1186231Y-4444D01*
G01X1183375Y-5900D02*
X1184775D01*
G01X1181496Y-7779D02*
X1183375Y-5900D01*
G01X1181496Y-9901D02*
Y-7779D01*
G01X1186063Y25863D02*
Y74863D01*
G01X1183563Y23363D02*
X1186063Y25863D01*
G01X1183563Y16662D02*
Y23363D01*
G01X1182069Y15168D02*
X1183563Y16662D01*
G01X1182069Y14187D02*
Y15168D01*
G01X1184142Y12114D02*
X1182069Y14187D01*
G01X1218453Y701D02*
X1220086Y-932D01*
G01X1218453Y2000D02*
Y701D01*
G01X1219803Y3350D02*
X1218453Y2000D01*
G01X1218553Y5500D02*
X1219803Y4250D01*
G01X1218553Y6699D02*
Y5500D01*
G01X1220086Y8232D02*
X1218553Y6699D01*
G01X1217186Y13100D02*
X1220086Y10200D01*
G01X1217186Y16036D02*
Y13100D01*
G01X1218307Y17157D02*
X1217186Y16036D01*
G01X1218307Y24906D02*
Y17157D01*
G01X1220200Y26799D02*
X1218307Y24906D01*
G01X1163394Y56934D02*
X1161417Y54957D01*
G01X1163394Y66339D02*
Y56934D01*
G01X1162594Y67139D02*
X1163394Y66339D01*
G01X1162594Y72295D02*
Y67139D01*
G01X1163294Y72995D02*
X1162594Y72295D01*
G01X1163294Y74906D02*
Y72995D01*
G01X1162600Y75600D02*
X1163294Y74906D01*
G01X1162600Y83206D02*
Y75600D01*
G01X1163294Y83900D02*
X1162600Y83206D01*
G01X1163294Y86074D02*
Y83900D01*
G01X1162594Y86774D02*
X1163294Y86074D01*
G01X1162594Y91074D02*
Y86774D01*
G01X1163694Y92174D02*
X1162594Y91074D01*
G01X1163694Y104907D02*
Y92174D01*
G01X1163289Y35574D02*
X1164763Y34100D01*
G01X1163289Y36668D02*
Y35574D01*
G01X1161856Y38101D02*
X1163289Y36668D01*
G01X1161856Y39324D02*
Y38101D01*
G01X1163356Y40824D02*
X1161856Y39324D01*
G01X1163356Y42176D02*
Y40824D01*
G01X1161856Y43676D02*
X1163356Y42176D01*
G01X1161856Y44799D02*
Y43676D01*
G01X1163531Y46474D02*
X1161856Y44799D01*
G01X1163531Y47859D02*
Y46474D01*
G01X1160489Y50901D02*
X1163531Y47859D01*
G01X1160489Y54029D02*
Y50901D01*
G01X1161417Y54957D02*
X1160489Y54029D01*
G01X1183374Y92074D02*
Y104974D01*
G01X1182274Y90974D02*
X1183374Y92074D01*
G01X1182274Y86474D02*
Y90974D01*
G01X1183574Y85174D02*
X1182274Y86474D01*
G01X1183574Y84200D02*
Y85174D01*
G01X1182900Y83526D02*
X1183574Y84200D01*
G01X1182900Y75500D02*
Y83526D01*
G01X1183574Y74826D02*
X1182900Y75500D01*
G01X1183574Y73475D02*
Y74826D01*
G01X1182274Y72175D02*
X1183574Y73475D01*
G01X1182274Y67333D02*
Y72175D01*
G01X1183201Y66406D02*
X1182274Y67333D01*
G01X1183201Y66400D02*
Y66406D01*
G01X1183374Y66227D02*
X1183201Y66400D01*
G01X1183374Y54258D02*
Y66227D01*
G01X1182274Y53158D02*
X1183374Y54258D01*
G01X1182274Y48644D02*
Y53158D01*
G01X1183563Y47355D02*
X1182274Y48644D01*
G01X1183563Y35563D02*
Y47355D01*
G01X1182213Y34213D02*
X1183563Y35563D01*
G01X1169889Y35667D02*
X1171456Y34100D01*
G01X1169889Y36868D02*
Y35667D01*
G01X1168531Y38226D02*
X1169889Y36868D01*
G01X1168531Y39599D02*
Y38226D01*
G01X1169731Y40799D02*
X1168531Y39599D01*
G01X1169731Y41925D02*
Y40799D01*
G01X1168531Y43125D02*
X1169731Y41925D01*
G01X1168531Y44700D02*
Y43125D01*
G01X1170331Y46500D02*
X1168531Y44700D01*
G01X1170331Y47558D02*
Y46500D01*
G01X1166989Y50900D02*
X1170331Y47558D01*
G01X1166989Y53836D02*
Y50900D01*
G01X1168110Y54957D02*
X1166989Y53836D01*
G01X1170074Y56921D02*
X1168110Y54957D01*
G01X1170074Y66579D02*
Y56921D01*
G01X1169394Y67259D02*
X1170074Y66579D01*
G01X1169394Y72595D02*
Y67259D01*
G01X1170194Y73395D02*
X1169394Y72595D01*
G01X1170194Y74706D02*
Y73395D01*
G01X1169400Y75500D02*
X1170194Y74706D01*
G01X1169400Y83306D02*
Y75500D01*
G01X1170194Y84100D02*
X1169400Y83306D01*
G01X1170194Y85774D02*
Y84100D01*
G01X1169594Y86374D02*
X1170194Y85774D01*
G01X1169594Y91374D02*
Y86374D01*
G01X1170094Y91874D02*
X1169594Y91374D01*
G01X1170094Y104906D02*
Y91874D01*
G01X1202974Y91674D02*
Y105438D01*
G01X1203674Y90974D02*
X1202974Y91674D01*
G01X1203674Y86138D02*
Y90974D01*
G01X1202900Y85364D02*
X1203674Y86138D01*
G01X1202900Y73101D02*
Y85364D01*
G01X1203630Y72371D02*
X1202900Y73101D01*
G01X1203630Y67215D02*
Y72371D01*
G01X1203063Y66648D02*
X1203630Y67215D01*
G01X1203063Y53986D02*
Y66648D01*
G01X1203763Y53286D02*
X1203063Y53986D01*
G01X1203763Y48714D02*
Y53286D01*
G01X1202963Y47914D02*
X1203763Y48714D01*
G01X1202963Y46200D02*
Y47914D01*
G01X1203500Y45663D02*
X1202963Y46200D01*
G01X1203500Y37500D02*
Y45663D01*
G01X1202963Y36963D02*
X1203500Y37500D01*
G01X1202963Y35437D02*
Y36963D01*
G01X1203500Y34900D02*
X1202963Y35437D01*
G01X1162924Y51753D02*
X1164763Y49914D01*
G01X1162924Y53594D02*
Y51753D01*
G01X1165594Y56264D02*
X1162924Y53594D01*
G01X1165594Y65859D02*
Y56264D01*
G01X1166794Y67059D02*
X1165594Y65859D01*
G01X1166794Y72159D02*
Y67059D01*
G01X1166294Y72659D02*
X1166794Y72159D01*
G01X1166294Y74894D02*
Y72659D01*
G01X1166700Y75300D02*
X1166294Y74894D01*
G01X1166700Y83494D02*
Y75300D01*
G01X1166294Y83900D02*
X1166700Y83494D01*
G01X1166294Y86074D02*
Y83900D01*
G01X1166894Y86674D02*
X1166294Y86074D01*
G01X1166894Y91012D02*
Y86674D01*
G01X1165900Y92006D02*
X1166894Y91012D01*
G01X1165900Y105492D02*
Y92006D01*
G01X1166764Y34900D02*
Y33500D01*
G01X1166152Y35512D02*
X1166764Y34900D01*
G01X1166152Y48525D02*
Y35512D01*
G01X1164763Y49914D02*
X1166152Y48525D01*
G01X1216392Y90956D02*
Y102092D01*
G01X1216700Y90648D02*
X1216392Y90956D01*
G01X1216700Y86400D02*
Y90648D01*
G01X1216300Y86000D02*
X1216700Y86400D01*
G01X1216300Y83900D02*
Y86000D01*
G01X1216900Y83300D02*
X1216300Y83900D01*
G01X1216900Y75600D02*
Y83300D01*
G01X1216300Y75000D02*
X1216900Y75600D01*
G01X1216300Y72749D02*
Y75000D01*
G01X1216692Y72357D02*
X1216300Y72749D01*
G01X1216692Y67557D02*
Y72357D01*
G01X1216500Y67365D02*
X1216692Y67557D01*
G01X1216500Y53638D02*
Y67365D01*
G01X1216692Y53446D02*
X1216500Y53638D01*
G01X1216692Y48832D02*
Y53446D01*
G01X1216357Y48497D02*
X1216692Y48832D01*
G01X1216357Y46044D02*
Y48497D01*
G01X1216924Y45477D02*
X1216357Y46044D01*
G01X1216924Y37924D02*
Y45477D01*
G01X1216357Y37357D02*
X1216924Y37924D01*
G01X1216357Y35216D02*
Y37357D01*
G01X1216524Y35049D02*
X1216357Y35216D01*
G01X1209800Y91548D02*
Y102600D01*
G01X1210067Y91281D02*
X1209800Y91548D01*
G01X1210067Y85967D02*
Y91281D01*
G01X1209592Y85492D02*
X1210067Y85967D01*
G01X1209592Y84100D02*
Y85492D01*
G01X1210200Y83492D02*
X1209592Y84100D01*
G01X1210200Y75200D02*
Y83492D01*
G01X1209592Y74592D02*
X1210200Y75200D01*
G01X1209592Y73209D02*
Y74592D01*
G01X1210174Y72627D02*
X1209592Y73209D01*
G01X1210174Y67059D02*
Y72627D01*
G01X1209713Y66598D02*
X1210174Y67059D01*
G01X1209713Y53914D02*
Y66598D01*
G01X1210174Y53453D02*
X1209713Y53914D01*
G01X1210174Y48575D02*
Y53453D01*
G01X1209663Y48064D02*
X1210174Y48575D01*
G01X1209663Y46037D02*
Y48064D01*
G01X1210400Y45300D02*
X1209663Y46037D01*
G01X1210400Y37737D02*
Y45300D01*
G01X1209663Y37000D02*
X1210400Y37737D01*
G01X1209663Y35237D02*
Y37000D01*
G01X1210263Y34637D02*
X1209663Y35237D01*
G01X1200274Y91738D02*
Y105574D01*
G01X1199474Y90938D02*
X1200274Y91738D01*
G01X1199474Y86174D02*
Y90938D01*
G01X1200274Y85374D02*
X1199474Y86174D01*
G01X1200274Y84214D02*
Y85374D01*
G01X1199000Y82940D02*
X1200274Y84214D01*
G01X1199000Y75624D02*
Y82940D01*
G01X1200274Y74350D02*
X1199000Y75624D01*
G01X1200274Y73175D02*
Y74350D01*
G01X1199674Y72575D02*
X1200274Y73175D01*
G01X1199674Y66959D02*
Y72575D01*
G01X1200374Y66259D02*
X1199674Y66959D01*
G01X1200374Y64759D02*
Y66259D01*
G01X1200063Y64448D02*
X1200374Y64759D01*
G01X1200063Y53926D02*
Y64448D01*
G01X1199663Y53526D02*
X1200063Y53926D01*
G01X1199663Y48714D02*
Y53526D01*
G01X1200463Y47914D02*
X1199663Y48714D01*
G01X1200463Y46400D02*
Y47914D01*
G01X1199700Y45637D02*
X1200463Y46400D01*
G01X1199700Y37800D02*
Y45637D01*
G01X1200463Y37037D02*
X1199700Y37800D01*
G01X1200463Y35563D02*
Y37037D01*
G01X1199663Y34763D02*
X1200463Y35563D01*
G01X1179474Y91974D02*
Y105438D01*
G01X1180174Y91274D02*
X1179474Y91974D01*
G01X1180174Y86538D02*
Y91274D01*
G01X1179408Y85772D02*
X1180174Y86538D01*
G01X1179408Y84100D02*
Y85772D01*
G01X1180100Y83408D02*
X1179408Y84100D01*
G01X1180100Y75400D02*
Y83408D01*
G01X1179408Y74708D02*
X1180100Y75400D01*
G01X1179408Y72741D02*
Y74708D01*
G01X1179974Y72175D02*
X1179408Y72741D01*
G01X1179974Y67559D02*
Y72175D01*
G01X1179374Y66959D02*
X1179974Y67559D01*
G01X1179374Y53974D02*
Y66959D01*
G01X1180074Y53274D02*
X1179374Y53974D01*
G01X1180074Y48738D02*
Y53274D01*
G01X1179363Y48027D02*
X1180074Y48738D01*
G01X1179363Y35399D02*
Y48027D01*
G01X1179713Y35049D02*
X1179363Y35399D01*
G01X1213800Y91864D02*
Y103300D01*
G01X1213074Y91138D02*
X1213800Y91864D01*
G01X1213074Y86374D02*
Y91138D01*
G01X1213800Y85648D02*
X1213074Y86374D01*
G01X1213800Y84300D02*
Y85648D01*
G01X1213000Y83500D02*
X1213800Y84300D01*
G01X1213000Y75200D02*
Y83500D01*
G01X1213800Y74400D02*
X1213000Y75200D01*
G01X1213800Y73365D02*
Y74400D01*
G01X1212674Y72239D02*
X1213800Y73365D01*
G01X1212674Y67227D02*
Y72239D01*
G01X1213900Y66001D02*
X1212674Y67227D01*
G01X1213900Y54640D02*
Y66001D01*
G01X1212810Y53550D02*
X1213900Y54640D01*
G01X1212810Y48990D02*
Y53550D01*
G01X1213800Y48000D02*
X1212810Y48990D01*
G01X1213800Y46200D02*
Y48000D01*
G01X1213100Y45500D02*
X1213800Y46200D01*
G01X1213100Y38000D02*
Y45500D01*
G01X1213800Y37300D02*
X1213100Y38000D01*
G01X1213800Y35425D02*
Y37300D01*
G01X1212674Y34299D02*
X1213800Y35425D01*
G01X1206900Y91664D02*
Y103000D01*
G01X1206174Y90938D02*
X1206900Y91664D01*
G01X1206174Y86374D02*
Y90938D01*
G01X1206874Y85674D02*
X1206174Y86374D01*
G01X1206874Y83974D02*
Y85674D01*
G01X1206200Y83300D02*
X1206874Y83974D01*
G01X1206200Y75474D02*
Y83300D01*
G01X1206874Y74800D02*
X1206200Y75474D01*
G01X1206874Y73075D02*
Y74800D01*
G01X1206174Y72375D02*
X1206874Y73075D01*
G01X1206174Y67059D02*
Y72375D01*
G01X1207000Y66233D02*
X1206174Y67059D01*
G01X1207000Y54263D02*
Y66233D01*
G01X1206263Y53526D02*
X1207000Y54263D01*
G01X1206263Y48614D02*
Y53526D01*
G01X1206863Y48014D02*
X1206263Y48614D01*
G01X1206863Y46063D02*
Y48014D01*
G01X1206200Y45400D02*
X1206863Y46063D01*
G01X1206200Y37463D02*
Y45400D01*
G01X1206863Y36800D02*
X1206200Y37463D01*
G01X1206863Y35363D02*
Y36800D01*
G01X1206400Y34900D02*
X1206863Y35363D01*
G01X1176774Y91874D02*
Y105374D01*
G01X1175874Y90974D02*
X1176774Y91874D01*
G01X1175874Y86674D02*
Y90974D01*
G01X1176674Y85874D02*
X1175874Y86674D01*
G01X1176674Y83900D02*
Y85874D01*
G01X1176300Y83526D02*
X1176674Y83900D01*
G01X1176300Y75200D02*
Y83526D01*
G01X1176674Y74826D02*
X1176300Y75200D01*
G01X1176674Y72859D02*
Y74826D01*
G01X1175774Y71959D02*
X1176674Y72859D01*
G01X1175774Y67326D02*
Y71959D01*
G01X1176874Y66226D02*
X1175774Y67326D01*
G01X1176874Y54138D02*
Y66226D01*
G01X1175974Y53238D02*
X1176874Y54138D01*
G01X1175974Y48774D02*
Y53238D01*
G01X1176863Y47885D02*
X1175974Y48774D01*
G01X1176863Y35299D02*
Y47885D01*
G01X1175863Y34299D02*
X1176863Y35299D01*
G01X1172845Y48525D02*
X1171456Y49914D01*
G01X1172845Y35512D02*
Y48525D01*
G01X1173457Y34900D02*
X1172845Y35512D01*
G01X1173457Y33500D02*
Y34900D01*
G01X1172694Y91854D02*
Y104991D01*
G01X1173394Y91154D02*
X1172694Y91854D01*
G01X1173394Y86494D02*
Y91154D01*
G01X1172694Y85794D02*
X1173394Y86494D01*
G01X1172694Y84200D02*
Y85794D01*
G01X1173300Y83594D02*
X1172694Y84200D01*
G01X1173300Y75600D02*
Y83594D01*
G01X1172694Y74994D02*
X1173300Y75600D01*
G01X1172694Y73307D02*
Y74994D01*
G01X1173294Y72707D02*
X1172694Y73307D01*
G01X1173294Y66879D02*
Y72707D01*
G01X1172728Y66313D02*
X1173294Y66879D01*
G01X1172728Y56798D02*
Y66313D01*
G01X1169500Y53570D02*
X1172728Y56798D01*
G01X1169500Y51870D02*
Y53570D01*
G01X1171456Y49914D02*
X1169500Y51870D01*
G01X1186063Y83900D02*
Y115600D01*
G01X1186700Y83263D02*
X1186063Y83900D01*
G01X1186700Y75500D02*
Y83263D01*
G01X1186063Y74863D02*
X1186700Y75500D01*
G01X1186233Y157600D02*
X1221892Y121941D01*
G01X1161632Y106969D02*
X1163694Y104907D01*
G01X1161632Y112357D02*
Y106969D01*
G01X1160644Y127356D02*
X1158900Y129100D01*
G01X1160644Y124560D02*
Y127356D01*
G01X1161204Y124000D02*
X1160644Y124560D01*
G01X1163284Y124000D02*
X1161204D01*
G01X1163844Y124560D02*
X1163284Y124000D01*
G01X1163844Y125200D02*
Y124560D01*
G01X1164644Y126000D02*
X1163844Y125200D01*
G01X1166244Y126000D02*
X1164644D01*
G01X1167044Y125200D02*
X1166244Y126000D01*
G01X1167044Y123782D02*
Y125200D01*
G01X1167844Y122982D02*
X1167044Y123782D01*
G01X1169444Y122982D02*
X1167844D01*
G01X1170244Y123782D02*
X1169444Y122982D01*
G01X1170244Y125200D02*
Y123782D01*
G01X1171044Y126000D02*
X1170244Y125200D01*
G01X1172126Y126000D02*
X1171044D01*
G01X1183392Y114734D02*
X1172126Y126000D01*
G01X1183392Y111556D02*
Y114734D01*
G01X1182274Y110438D02*
X1183392Y111556D01*
G01X1182274Y106074D02*
Y110438D01*
G01X1183374Y104974D02*
X1182274Y106074D01*
G01X1188500Y178500D02*
X1248400Y118600D01*
G01X1167925Y107075D02*
X1170094Y104906D01*
G01X1167925Y112357D02*
Y107075D01*
G01X1202892Y117191D02*
X1173083Y147000D01*
G01X1202892Y111456D02*
Y117191D01*
G01X1203540Y110808D02*
X1202892Y111456D01*
G01X1203540Y106004D02*
Y110808D01*
G01X1202974Y105438D02*
X1203540Y106004D01*
G01X1188700Y171599D02*
X1240600Y119699D01*
G01X1187374Y176126D02*
X1243100Y120400D01*
G01X1164428Y106964D02*
X1165900Y105492D01*
G01X1205362Y128839D02*
X1158101Y176100D01*
G01X1206861Y128839D02*
X1205362D01*
G01X1207963Y127737D02*
X1206861Y128839D01*
G01X1207965Y126236D02*
X1207963Y127737D01*
G01X1208984Y125217D02*
X1207965Y126236D01*
G01X1209776Y125217D02*
X1208984D01*
G01X1210933Y126374D02*
X1209776Y125217D01*
G01X1211400Y126375D02*
X1210933Y126374D01*
G01X1211723Y126375D02*
X1211400D01*
G01X1212743Y125355D02*
X1211723Y126375D01*
G01X1212743Y124563D02*
Y125355D01*
G01X1211586Y123406D02*
X1212743Y124563D01*
G01X1211587Y122614D02*
X1211586Y123406D01*
G01X1212606Y121595D02*
X1211587Y122614D01*
G01X1213398Y121595D02*
X1212606D01*
G01X1214555Y122752D02*
X1213398Y121595D01*
G01X1215345Y122753D02*
X1214555Y122752D01*
G01X1216365Y121733D02*
X1215345Y122753D01*
G01X1216365Y120941D02*
Y121733D01*
G01X1215208Y119784D02*
X1216365Y120941D01*
G01X1215209Y118992D02*
X1215208Y119784D01*
G01X1216892Y117309D02*
X1215209Y118992D01*
G01X1216892Y102592D02*
Y117309D01*
G01X1216392Y102092D02*
X1216892Y102592D01*
G01X1210300Y116855D02*
X1173155Y154000D01*
G01X1210300Y103100D02*
Y116855D01*
G01X1209800Y102600D02*
X1210300Y103100D01*
G01X1200028Y116347D02*
X1171275Y145100D01*
G01X1200028Y111228D02*
Y116347D01*
G01X1199574Y110774D02*
X1200028Y111228D01*
G01X1199574Y106274D02*
Y110774D01*
G01X1200274Y105574D02*
X1199574Y106274D01*
G01X1189238Y167962D02*
X1235574Y121626D01*
G01X1161754Y119000D02*
Y120200D01*
G01X1162554Y118200D02*
X1161754Y119000D01*
G01X1164154Y118200D02*
X1162554D01*
G01X1165254Y119300D02*
X1164154Y118200D01*
G01X1175290Y119300D02*
X1165254D01*
G01X1179492Y115098D02*
X1175290Y119300D01*
G01X1179492Y111256D02*
Y115098D01*
G01X1179792Y110956D02*
X1179492Y111256D01*
G01X1179792Y105756D02*
Y110956D01*
G01X1179474Y105438D02*
X1179792Y105756D01*
G01X1214392Y117209D02*
X1174301Y157300D01*
G01X1214392Y103892D02*
Y117209D01*
G01X1213800Y103300D02*
X1214392Y103892D01*
G01X1207800Y115819D02*
X1173319Y150300D01*
G01X1207800Y112364D02*
Y115819D01*
G01X1206074Y110638D02*
X1207800Y112364D01*
G01X1206074Y106374D02*
Y110638D01*
G01X1207608Y104840D02*
X1206074Y106374D01*
G01X1207608Y103708D02*
Y104840D01*
G01X1206900Y103000D02*
X1207608Y103708D01*
G01X1176700Y114354D02*
X1175354Y115700D01*
G01X1176700Y111564D02*
Y114354D01*
G01X1175974Y110838D02*
X1176700Y111564D01*
G01X1175974Y106174D02*
Y110838D01*
G01X1176774Y105374D02*
X1175974Y106174D01*
G01X1172694Y104991D02*
X1170721Y106964D01*
G01X1186063Y115600D02*
X1170563Y131100D01*
G01X1202788Y138013D02*
X1219392Y121409D01*
G01X1202787Y138013D02*
X1202788D01*
G01X1201768Y139032D02*
X1202787Y138013D01*
G01X1200976Y139032D02*
X1201768D01*
G01X1200068Y138124D02*
X1200976Y139032D01*
G01X1199276Y138124D02*
X1200068D01*
G01X1198257Y139143D02*
X1199276Y138124D01*
G01X1198257Y139935D02*
Y139143D01*
G01X1199165Y140843D02*
X1198257Y139935D01*
G01X1199165Y141635D02*
Y140843D01*
G01X1198146Y142654D02*
X1199165Y141635D01*
G01X1197354Y142654D02*
X1198146D01*
G01X1196446Y141746D02*
X1197354Y142654D01*
G01X1195654Y141746D02*
X1196446D01*
G01X1194635Y142765D02*
X1195654Y141746D01*
G01X1194635Y143557D02*
Y142765D01*
G01X1195543Y144465D02*
X1194635Y143557D01*
G01X1195543Y145257D02*
Y144465D01*
G01X1194524Y146276D02*
X1195543Y145257D01*
G01X1193732Y146276D02*
X1194524D01*
G01X1192824Y145368D02*
X1193732Y146276D01*
G01X1192032Y145368D02*
X1192824D01*
G01X1191013Y146387D02*
X1192032Y145368D01*
G01X1191013Y147179D02*
Y146387D01*
G01X1191921Y148087D02*
X1191013Y147179D01*
G01X1191921Y148879D02*
Y148087D01*
G01X1190902Y149898D02*
X1191921Y148879D01*
G01X1190110Y149898D02*
X1190902D01*
G01X1189202Y148990D02*
X1190110Y149898D01*
G01X1188410Y148990D02*
X1189202D01*
G01X1187391Y150009D02*
X1188410Y148990D01*
G01X1187391Y150801D02*
Y150009D01*
G01X1187899Y151309D02*
X1187391Y150801D01*
G01X1187899Y152101D02*
Y151309D01*
G01X1186880Y153120D02*
X1187899Y152101D01*
G01X1186088Y153120D02*
X1186880D01*
G01X1185580Y152612D02*
X1186088Y153120D01*
G01X1184788Y152612D02*
X1185580D01*
G01X1158500Y178900D02*
X1184788Y152612D01*
G01X1182399Y157600D02*
X1186233D01*
G01X1157099Y182900D02*
X1182399Y157600D01*
G01X1184200Y178500D02*
X1188500D01*
G01X1162400Y200300D02*
X1184200Y178500D01*
G01X1184900Y171599D02*
X1188700D01*
G01X1160899Y195600D02*
X1184900Y171599D01*
G01X1183374Y176126D02*
X1187374D01*
G01X1161600Y197900D02*
X1183374Y176126D01*
G01X1185138Y167962D02*
X1189238D01*
G01X1159900Y193200D02*
X1185138Y167962D01*
G01X1160700Y160060D02*
Y167201D01*
G01X1161260Y159500D02*
X1160700Y160060D01*
G01X1163089Y159500D02*
X1161260D01*
G01X1163649Y160060D02*
X1163089Y159500D01*
G01X1163649Y163740D02*
Y160060D01*
G01X1164209Y164300D02*
X1163649Y163740D01*
G01X1165649Y164300D02*
X1164209D01*
G01X1166209Y163740D02*
X1165649Y164300D01*
G01X1166209Y157860D02*
Y163740D01*
G01X1166769Y157300D02*
X1166209Y157860D01*
G01X1174301Y157300D02*
X1166769D01*
G01X1183691Y449903D02*
X1220147Y486359D01*
G01X1167096Y449903D02*
X1183691D01*
G01X1162123Y444930D02*
X1167096Y449903D01*
G01X1162123Y434817D02*
Y444930D01*
G01X1185419Y447835D02*
X1222874Y485290D01*
G01X1171118Y447835D02*
X1185419D01*
G01X1169689Y446406D02*
X1171118Y447835D01*
G01X1169689Y438919D02*
Y446406D01*
G01X1169079Y438309D02*
X1169689Y438919D01*
G01X1167689Y438309D02*
X1169079D01*
G01X1167079Y438919D02*
X1167689Y438309D01*
G01X1167079Y443845D02*
Y438919D01*
G01X1166469Y444455D02*
X1167079Y443845D01*
G01X1165079Y444455D02*
X1166469D01*
G01X1164469Y443845D02*
X1165079Y444455D01*
G01X1164469Y433569D02*
Y443845D01*
G01X1179752Y459094D02*
X1189968Y469310D01*
G01X1175784Y461273D02*
X1198720Y484209D01*
G01X1182020Y452200D02*
X1216813Y486993D01*
G01X1175590Y463760D02*
X1198162Y486332D01*
G01X1159630Y463760D02*
X1175590D01*
G01X1159020Y464370D02*
X1159630Y463760D01*
G01X1159020Y465804D02*
Y464370D01*
G01X1186036Y435096D02*
X1235541Y484601D01*
G01X1178884Y435096D02*
X1186036D01*
G01X1186930Y432806D02*
X1238074Y483950D01*
G01X1179720Y432806D02*
X1186930D01*
G01X1180955Y454600D02*
X1213414Y487059D01*
G01X1187822Y430682D02*
X1240574Y483434D01*
G01X1180722Y430682D02*
X1187822D01*
G01X1188494Y428447D02*
X1245821Y485774D01*
G01X1181629Y428447D02*
X1188494D01*
G01X1171658Y418476D02*
X1181629Y428447D01*
G01X1171658Y417614D02*
Y418476D01*
G01X1172496Y416776D02*
X1171658Y417614D01*
G01X1172496Y415814D02*
Y416776D01*
G01X1171612Y414930D02*
X1172496Y415814D01*
G01X1170650Y414930D02*
X1171612D01*
G01X1169812Y415768D02*
X1170650Y414930D01*
G01X1168950Y415768D02*
X1169812D01*
G01X1167966Y414784D02*
X1168950Y415768D01*
G01X1167966Y413922D02*
Y414784D01*
G01X1168804Y413084D02*
X1167966Y413922D01*
G01X1168804Y412222D02*
Y413084D01*
G01X1167820Y411238D02*
X1168804Y412222D01*
G01X1166958Y411238D02*
X1167820D01*
G01X1166120Y412076D02*
X1166958Y411238D01*
G01X1165258Y412076D02*
X1166120D01*
G01X1158085Y404903D02*
X1165258Y412076D01*
G01X1200063Y517357D02*
Y529842D01*
G01X1199663Y516957D02*
X1200063Y517357D01*
G01X1199663Y512057D02*
Y516957D01*
G01X1200061Y511659D02*
X1199663Y512057D01*
G01X1200061Y497639D02*
Y511659D01*
G01X1199800Y497378D02*
X1200061Y497639D01*
G01X1199800Y495100D02*
Y497378D01*
G01X1198600Y493900D02*
X1199800Y495100D01*
G01X1198600Y488787D02*
Y493900D01*
G01X1198100Y488287D02*
X1198600Y488787D01*
G01X1197182Y488287D02*
X1198100D01*
G01X1174833Y465938D02*
X1197182Y488287D01*
G01X1162122Y465938D02*
X1174833D01*
G01X1159327Y468733D02*
X1162122Y465938D01*
G01X1161874Y498944D02*
X1161417Y498487D01*
G01X1161874Y507774D02*
Y498944D01*
G01X1163652Y509552D02*
X1161874Y507774D01*
G01X1163652Y511257D02*
Y509552D01*
G01X1162852Y512057D02*
X1163652Y511257D01*
G01X1162852Y516957D02*
Y512057D01*
G01X1163452Y517557D02*
X1162852Y516957D01*
G01X1163452Y519500D02*
Y517557D01*
G01X1163100Y519852D02*
X1163452Y519500D01*
G01X1163100Y527800D02*
Y519852D01*
G01X1186500Y519101D02*
Y527800D01*
G01X1186063Y518664D02*
X1186500Y519101D01*
G01X1186063Y509237D02*
Y518664D01*
G01X1187811Y507489D02*
X1186063Y509237D01*
G01X1187811Y506110D02*
Y507489D01*
G01X1187201Y505500D02*
X1187811Y506110D01*
G01X1186049Y505500D02*
X1187201D01*
G01X1185439Y504890D02*
X1186049Y505500D01*
G01X1185439Y504010D02*
Y504890D01*
G01X1186049Y503400D02*
X1185439Y504010D01*
G01X1187201Y503400D02*
X1186049D01*
G01X1187811Y502790D02*
X1187201Y503400D01*
G01X1187811Y501312D02*
Y502790D01*
G01X1186063Y499564D02*
X1187811Y501312D01*
G01X1186063Y489844D02*
Y499564D01*
G01X1174059Y477840D02*
X1186063Y489844D01*
G01X1170185Y477840D02*
X1174059D01*
G01X1169575Y478450D02*
X1170185Y477840D01*
G01X1169575Y479688D02*
Y478450D01*
G01X1168965Y480298D02*
X1169575Y479688D01*
G01X1167575Y480298D02*
X1168965D01*
G01X1166965Y479688D02*
X1167575Y480298D01*
G01X1166965Y478450D02*
Y479688D01*
G01X1166355Y477840D02*
X1166965Y478450D01*
G01X1164965Y477840D02*
X1166355D01*
G01X1164355Y478450D02*
X1164965Y477840D01*
G01X1164355Y479688D02*
Y478450D01*
G01X1163745Y480298D02*
X1164355Y479688D01*
G01X1161564Y480298D02*
X1163745D01*
G01X1160954Y479688D02*
X1161564Y480298D01*
G01X1160954Y478478D02*
Y479688D01*
G01X1160344Y477868D02*
X1160954Y478478D01*
G01X1158954Y477868D02*
X1160344D01*
G01X1158344Y478478D02*
X1158954Y477868D01*
G01X1158344Y479688D02*
Y478478D01*
G01X1157734Y480298D02*
X1158344Y479688D01*
G01X1183563Y517657D02*
Y529267D01*
G01X1182348Y516442D02*
X1183563Y517657D01*
G01X1182348Y511922D02*
Y516442D01*
G01X1183271Y510999D02*
X1182348Y511922D01*
G01X1183271Y497539D02*
Y510999D01*
G01X1182329Y496597D02*
X1183271Y497539D01*
G01X1182329Y488876D02*
Y496597D01*
G01X1176657Y483204D02*
X1182329Y488876D01*
G01X1210000Y519587D02*
Y527600D01*
G01X1209713Y519300D02*
X1210000Y519587D01*
G01X1209713Y517357D02*
Y519300D01*
G01X1210263Y516807D02*
X1209713Y517357D01*
G01X1210263Y512257D02*
Y516807D01*
G01X1209663Y511657D02*
X1210263Y512257D01*
G01X1209663Y509237D02*
Y511657D01*
G01X1209900Y509000D02*
X1209663Y509237D01*
G01X1209900Y497600D02*
Y509000D01*
G01X1210300Y497200D02*
X1209900Y497600D01*
G01X1210300Y489642D02*
Y497200D01*
G01X1200060Y479402D02*
X1210300Y489642D01*
G01X1199198Y479402D02*
X1200060D01*
G01X1198342Y480258D02*
X1199198Y479402D01*
G01X1197480Y480258D02*
X1198342D01*
G01X1196496Y479274D02*
X1197480Y480258D01*
G01X1196496Y478412D02*
Y479274D01*
G01X1197352Y477556D02*
X1196496Y478412D01*
G01X1197352Y476694D02*
Y477556D01*
G01X1196368Y475710D02*
X1197352Y476694D01*
G01X1195506Y475710D02*
X1196368D01*
G01X1194650Y476566D02*
X1195506Y475710D01*
G01X1193788Y476566D02*
X1194650D01*
G01X1192804Y475582D02*
X1193788Y476566D01*
G01X1192804Y474720D02*
Y475582D01*
G01X1193660Y473864D02*
X1192804Y474720D01*
G01X1193660Y473002D02*
Y473864D01*
G01X1192676Y472018D02*
X1193660Y473002D01*
G01X1191814Y472018D02*
X1192676D01*
G01X1190958Y472874D02*
X1191814Y472018D01*
G01X1190096Y472874D02*
X1190958D01*
G01X1189112Y471890D02*
X1190096Y472874D01*
G01X1189112Y471028D02*
Y471890D01*
G01X1189968Y470172D02*
X1189112Y471028D01*
G01X1189968Y469310D02*
Y470172D01*
G01X1173100Y519498D02*
Y527800D01*
G01X1172902Y519300D02*
X1173100Y519498D01*
G01X1172902Y517357D02*
Y519300D01*
G01X1173452Y516807D02*
X1172902Y517357D01*
G01X1173452Y512257D02*
Y516807D01*
G01X1172852Y511657D02*
X1173452Y512257D01*
G01X1172852Y509348D02*
Y511657D01*
G01X1173200Y509000D02*
X1172852Y509348D01*
G01X1173200Y504000D02*
Y509000D01*
G01X1170656Y501456D02*
X1173200Y504000D01*
G01X1170656Y493844D02*
Y501456D01*
G01X1206600Y519913D02*
Y527800D01*
G01X1207500Y519013D02*
X1206600Y519913D01*
G01X1207500Y517700D02*
Y519013D01*
G01X1206363Y516563D02*
X1207500Y517700D01*
G01X1206363Y511657D02*
Y516563D01*
G01X1206863Y511157D02*
X1206363Y511657D01*
G01X1206863Y509400D02*
Y511157D01*
G01X1206100Y508637D02*
X1206863Y509400D01*
G01X1206100Y501100D02*
Y508637D01*
G01X1206863Y500337D02*
X1206100Y501100D01*
G01X1206863Y497841D02*
Y500337D01*
G01X1206500Y497478D02*
X1206863Y497841D01*
G01X1206500Y491826D02*
Y497478D01*
G01X1206874Y491452D02*
X1206500Y491826D01*
G01X1206874Y489932D02*
Y491452D01*
G01X1201151Y484209D02*
X1206874Y489932D01*
G01X1198720Y484209D02*
X1201151D01*
G01X1216700Y519626D02*
Y527500D01*
G01X1216274Y519200D02*
X1216700Y519626D01*
G01X1216274Y517457D02*
Y519200D01*
G01X1216600Y517131D02*
X1216274Y517457D01*
G01X1216600Y511823D02*
Y517131D01*
G01X1216274Y511497D02*
X1216600Y511823D01*
G01X1216274Y509052D02*
Y511497D01*
G01X1216813Y508513D02*
X1216274Y509052D01*
G01X1216813Y486993D02*
Y508513D01*
G01X1176763Y517357D02*
Y529438D01*
G01X1175863Y516457D02*
X1176763Y517357D01*
G01X1175863Y511797D02*
Y516457D01*
G01X1176763Y510897D02*
X1175863Y511797D01*
G01X1176763Y509400D02*
Y510897D01*
G01X1175951Y508588D02*
X1176763Y509400D01*
G01X1175951Y503051D02*
Y508588D01*
G01X1172400Y499500D02*
X1175951Y503051D01*
G01X1172400Y490499D02*
Y499500D01*
G01X1170201Y488300D02*
X1172400Y490499D01*
G01X1169800Y519752D02*
Y527800D01*
G01X1170352Y519200D02*
X1169800Y519752D01*
G01X1170352Y517857D02*
Y519200D01*
G01X1169552Y517057D02*
X1170352Y517857D01*
G01X1169552Y511657D02*
Y517057D01*
G01X1170052Y511157D02*
X1169552Y511657D01*
G01X1170052Y509153D02*
Y511157D01*
G01X1167510Y506611D02*
X1170052Y509153D01*
G01X1167510Y498487D02*
Y506611D01*
G01X1203300Y519637D02*
Y527600D01*
G01X1203063Y519400D02*
X1203300Y519637D01*
G01X1203063Y517357D02*
Y519400D01*
G01X1203863Y516557D02*
X1203063Y517357D01*
G01X1203863Y512157D02*
Y516557D01*
G01X1202963Y511257D02*
X1203863Y512157D01*
G01X1202963Y509500D02*
Y511257D01*
G01X1203529Y508934D02*
X1202963Y509500D01*
G01X1203529Y500729D02*
Y508934D01*
G01X1202700Y499900D02*
X1203529Y500729D01*
G01X1202700Y489474D02*
Y499900D01*
G01X1199558Y486332D02*
X1202700Y489474D01*
G01X1198162Y486332D02*
X1199558D01*
G01X1158438Y466386D02*
X1159020Y465804D01*
G01X1157048Y466386D02*
X1158438D01*
G01X1164474Y493855D02*
X1164363Y493744D01*
G01X1164474Y507570D02*
Y493855D01*
G01X1166152Y509248D02*
X1164474Y507570D01*
G01X1166152Y511257D02*
Y509248D01*
G01X1167052Y512157D02*
X1166152Y511257D01*
G01X1167052Y516557D02*
Y512157D01*
G01X1165952Y517657D02*
X1167052Y516557D01*
G01X1165952Y519200D02*
Y517657D01*
G01X1166500Y519748D02*
X1165952Y519200D01*
G01X1166500Y527700D02*
Y519748D01*
G01X1180873Y525717D02*
Y526941D01*
G01X1180263Y525107D02*
X1180873Y525717D01*
G01X1179585Y525107D02*
X1180263D01*
G01X1178975Y524497D02*
X1179585Y525107D01*
G01X1178975Y522517D02*
Y524497D01*
G01X1179585Y521907D02*
X1178975Y522517D01*
G01X1180263Y521907D02*
X1179585D01*
G01X1180873Y521297D02*
X1180263Y521907D01*
G01X1180873Y520122D02*
Y521297D01*
G01X1179463Y518712D02*
X1180873Y520122D01*
G01X1179463Y517457D02*
Y518712D01*
G01X1179713Y517207D02*
X1179463Y517457D01*
G01X1179713Y511747D02*
Y517207D01*
G01X1179463Y511497D02*
X1179713Y511747D01*
G01X1179463Y509337D02*
Y511497D01*
G01X1180720Y508080D02*
X1179463Y509337D01*
G01X1180720Y506900D02*
Y508080D01*
G01X1179998Y506178D02*
X1180720Y506900D01*
G01X1178902Y506178D02*
X1179998D01*
G01X1178264Y505540D02*
X1178902Y506178D01*
G01X1178264Y495536D02*
Y505540D01*
G01X1179600Y494200D02*
X1178264Y495536D01*
G01X1179600Y489882D02*
Y494200D01*
G01X1177450Y487732D02*
X1179600Y489882D01*
G01X1177450Y486913D02*
Y487732D01*
G01X1176049Y485512D02*
X1177450Y486913D01*
G01X1175144Y485512D02*
X1176049D01*
G01X1173039Y487617D02*
X1175144Y485512D01*
G01X1172218Y487617D02*
X1173039D01*
G01X1170821Y486220D02*
X1172218Y487617D01*
G01X1213414Y517197D02*
Y529586D01*
G01X1213023Y516806D02*
X1213414Y517197D01*
G01X1213023Y511448D02*
Y516806D01*
G01X1213414Y511057D02*
X1213023Y511448D01*
G01X1213414Y487059D02*
Y511057D01*
G01X1200116Y586704D02*
X1197909Y588911D01*
G01X1200116Y573895D02*
Y586704D01*
G01X1199614Y573393D02*
X1200116Y573895D01*
G01X1199614Y568046D02*
Y573393D01*
G01X1200263Y567397D02*
X1199614Y568046D01*
G01X1200263Y554963D02*
Y567397D01*
G01X1199698Y554398D02*
X1200263Y554963D01*
G01X1199698Y549402D02*
Y554398D01*
G01X1200117Y548983D02*
X1199698Y549402D01*
G01X1200117Y536216D02*
Y548983D01*
G01X1199663Y535762D02*
X1200117Y536216D01*
G01X1199663Y530242D02*
Y535762D01*
G01X1200063Y529842D02*
X1199663Y530242D01*
G01X1163452Y528152D02*
X1163100Y527800D01*
G01X1163452Y529597D02*
Y528152D01*
G01X1162379Y530670D02*
X1163452Y529597D01*
G01X1162379Y535169D02*
Y530670D01*
G01X1163652Y536442D02*
X1162379Y535169D01*
G01X1163652Y537600D02*
Y536442D01*
G01X1163100Y538152D02*
X1163652Y537600D01*
G01X1163100Y546600D02*
Y538152D01*
G01X1163652Y547152D02*
X1163100Y546600D01*
G01X1163652Y548557D02*
Y547152D01*
G01X1160752Y551457D02*
X1163652Y548557D01*
G01X1160752Y555292D02*
Y551457D01*
G01X1161417Y555957D02*
X1160752Y555292D01*
G01X1186063Y586443D02*
X1184142Y588364D01*
G01X1186063Y565737D02*
Y586443D01*
G01X1186500Y565300D02*
X1186063Y565737D01*
G01X1186500Y557101D02*
Y565300D01*
G01X1186063Y556664D02*
X1186500Y557101D01*
G01X1186063Y546537D02*
Y556664D01*
G01X1186500Y546100D02*
X1186063Y546537D01*
G01X1186500Y538137D02*
Y546100D01*
G01X1186063Y537700D02*
X1186500Y538137D01*
G01X1186063Y528237D02*
Y537700D01*
G01X1186500Y527800D02*
X1186063Y528237D01*
G01X1183242Y586628D02*
X1180756Y589114D01*
G01X1183242Y574142D02*
Y586628D01*
G01X1182263Y573163D02*
X1183242Y574142D01*
G01X1182263Y568367D02*
Y573163D01*
G01X1183243Y567387D02*
X1182263Y568367D01*
G01X1183243Y555137D02*
Y567387D01*
G01X1182213Y554107D02*
X1183243Y555137D01*
G01X1182213Y549857D02*
Y554107D01*
G01X1183214Y548856D02*
X1182213Y549857D01*
G01X1183214Y536215D02*
Y548856D01*
G01X1182349Y535350D02*
X1183214Y536215D01*
G01X1182349Y530481D02*
Y535350D01*
G01X1183563Y529267D02*
X1182349Y530481D01*
G01X1209563Y587470D02*
X1208267Y588766D01*
G01X1209563Y574038D02*
Y587470D01*
G01X1210563Y573038D02*
X1209563Y574038D01*
G01X1210563Y568497D02*
Y573038D01*
G01X1209713Y567647D02*
X1210563Y568497D01*
G01X1209713Y565687D02*
Y567647D01*
G01X1210000Y565400D02*
X1209713Y565687D01*
G01X1210000Y557287D02*
Y565400D01*
G01X1209713Y557000D02*
X1210000Y557287D01*
G01X1209713Y555157D02*
Y557000D01*
G01X1210263Y554607D02*
X1209713Y555157D01*
G01X1210263Y550057D02*
Y554607D01*
G01X1209663Y549457D02*
X1210263Y550057D01*
G01X1209663Y546637D02*
Y549457D01*
G01X1209900Y546400D02*
X1209663Y546637D01*
G01X1209900Y537837D02*
Y546400D01*
G01X1209663Y537600D02*
X1209900Y537837D01*
G01X1209663Y536238D02*
Y537600D01*
G01X1210363Y535538D02*
X1209663Y536238D01*
G01X1210363Y530466D02*
Y535538D01*
G01X1209713Y529816D02*
X1210363Y530466D01*
G01X1209713Y527887D02*
Y529816D01*
G01X1210000Y527600D02*
X1209713Y527887D01*
G01X1171456Y550966D02*
Y550914D01*
G01X1172752Y549670D02*
X1171456Y550966D01*
G01X1172752Y546248D02*
Y549670D01*
G01X1173100Y545900D02*
X1172752Y546248D01*
G01X1173100Y537948D02*
Y545900D01*
G01X1172752Y537600D02*
X1173100Y537948D01*
G01X1172752Y536348D02*
Y537600D01*
G01X1173752Y535348D02*
X1172752Y536348D01*
G01X1173752Y530697D02*
Y535348D01*
G01X1172902Y529847D02*
X1173752Y530697D01*
G01X1172902Y527998D02*
Y529847D01*
G01X1173100Y527800D02*
X1172902Y527998D01*
G01X1206963Y586507D02*
X1203563Y589907D01*
G01X1206963Y574042D02*
Y586507D01*
G01X1206063Y573142D02*
X1206963Y574042D01*
G01X1206063Y568397D02*
Y573142D01*
G01X1207163Y567297D02*
X1206063Y568397D01*
G01X1207163Y566063D02*
Y567297D01*
G01X1206596Y565496D02*
X1207163Y566063D01*
G01X1206596Y557467D02*
Y565496D01*
G01X1207163Y556900D02*
X1206596Y557467D01*
G01X1207163Y555657D02*
Y556900D01*
G01X1206363Y554857D02*
X1207163Y555657D01*
G01X1206363Y549457D02*
Y554857D01*
G01X1206863Y548957D02*
X1206363Y549457D01*
G01X1206863Y546963D02*
Y548957D01*
G01X1206600Y546700D02*
X1206863Y546963D01*
G01X1206600Y538163D02*
Y546700D01*
G01X1207100Y537663D02*
X1206600Y538163D01*
G01X1207100Y536499D02*
Y537663D01*
G01X1206263Y535662D02*
X1207100Y536499D01*
G01X1206263Y530366D02*
Y535662D01*
G01X1207148Y529481D02*
X1206263Y530366D01*
G01X1207148Y528348D02*
Y529481D01*
G01X1206600Y527800D02*
X1207148Y528348D01*
G01X1216174Y587200D02*
X1214660Y588714D01*
G01X1216174Y584126D02*
Y587200D01*
G01X1216600Y583700D02*
X1216174Y584126D01*
G01X1216600Y575626D02*
Y583700D01*
G01X1216174Y575200D02*
X1216600Y575626D01*
G01X1216174Y573256D02*
Y575200D01*
G01X1216774Y572656D02*
X1216174Y573256D01*
G01X1216774Y568497D02*
Y572656D01*
G01X1216274Y567997D02*
X1216774Y568497D01*
G01X1216274Y565926D02*
Y567997D01*
G01X1216600Y565600D02*
X1216274Y565926D01*
G01X1216600Y557326D02*
Y565600D01*
G01X1216274Y557000D02*
X1216600Y557326D01*
G01X1216274Y555257D02*
Y557000D01*
G01X1216700Y554831D02*
X1216274Y555257D01*
G01X1216700Y548983D02*
Y554831D01*
G01X1216174Y548457D02*
X1216700Y548983D01*
G01X1216174Y546626D02*
Y548457D01*
G01X1216700Y546100D02*
X1216174Y546626D01*
G01X1216700Y538026D02*
Y546100D01*
G01X1216174Y537500D02*
X1216700Y538026D01*
G01X1216174Y535542D02*
Y537500D01*
G01X1216524Y535192D02*
X1216174Y535542D01*
G01X1216524Y530242D02*
Y535192D01*
G01X1216274Y529992D02*
X1216524Y530242D01*
G01X1216274Y527926D02*
Y529992D01*
G01X1216700Y527500D02*
X1216274Y527926D01*
G01X1174400Y587700D02*
X1173563Y588537D01*
G01X1175600Y587700D02*
X1174400D01*
G01X1176713Y586587D02*
X1175600Y587700D01*
G01X1176713Y573942D02*
Y586587D01*
G01X1175400Y572629D02*
X1176713Y573942D01*
G01X1175400Y568600D02*
Y572629D01*
G01X1176763Y567237D02*
X1175400Y568600D01*
G01X1176763Y565863D02*
Y567237D01*
G01X1176500Y565600D02*
X1176763Y565863D01*
G01X1176500Y557699D02*
Y565600D01*
G01X1177336Y556863D02*
X1176500Y557699D01*
G01X1177336Y555730D02*
Y556863D01*
G01X1175400Y553794D02*
X1177336Y555730D01*
G01X1175400Y550400D02*
Y553794D01*
G01X1176734Y549066D02*
X1175400Y550400D01*
G01X1176734Y536113D02*
Y549066D01*
G01X1175863Y535242D02*
X1176734Y536113D01*
G01X1175863Y530338D02*
Y535242D01*
G01X1176763Y529438D02*
X1175863Y530338D01*
G01X1166752Y554599D02*
X1168110Y555957D01*
G01X1166752Y552107D02*
Y554599D01*
G01X1170152Y548707D02*
X1166752Y552107D01*
G01X1170152Y546552D02*
Y548707D01*
G01X1169800Y546200D02*
X1170152Y546552D01*
G01X1169800Y538052D02*
Y546200D01*
G01X1170152Y537700D02*
X1169800Y538052D01*
G01X1170152Y536242D02*
Y537700D01*
G01X1169252Y535342D02*
X1170152Y536242D01*
G01X1169252Y530597D02*
Y535342D01*
G01X1170352Y529497D02*
X1169252Y530597D01*
G01X1170352Y528352D02*
Y529497D01*
G01X1169800Y527800D02*
X1170352Y528352D01*
G01X1202920Y587368D02*
X1201574Y588714D01*
G01X1202963Y587368D02*
X1202920D01*
G01X1202963Y574137D02*
Y587368D01*
G01X1203629Y573471D02*
X1202963Y574137D01*
G01X1203629Y568163D02*
Y573471D01*
G01X1203063Y567597D02*
X1203629Y568163D01*
G01X1203063Y565937D02*
Y567597D01*
G01X1203300Y565700D02*
X1203063Y565937D01*
G01X1203300Y557637D02*
Y565700D01*
G01X1202763Y557100D02*
X1203300Y557637D01*
G01X1202763Y555457D02*
Y557100D01*
G01X1203863Y554357D02*
X1202763Y555457D01*
G01X1203863Y549957D02*
Y554357D01*
G01X1202963Y549057D02*
X1203863Y549957D01*
G01X1202963Y546937D02*
Y549057D01*
G01X1203300Y546600D02*
X1202963Y546937D01*
G01X1203300Y538037D02*
Y546600D01*
G01X1202963Y537700D02*
X1203300Y538037D01*
G01X1202963Y536538D02*
Y537700D01*
G01X1203763Y535738D02*
X1202963Y536538D01*
G01X1203763Y530542D02*
Y535738D01*
G01X1203063Y529842D02*
X1203763Y530542D01*
G01X1203063Y527837D02*
Y529842D01*
G01X1203300Y527600D02*
X1203063Y527837D01*
G01X1166252Y527948D02*
X1166500Y527700D01*
G01X1166252Y529797D02*
Y527948D01*
G01X1166818Y530363D02*
X1166252Y529797D01*
G01X1166818Y535581D02*
Y530363D01*
G01X1166152Y536247D02*
X1166818Y535581D01*
G01X1166152Y537800D02*
Y536247D01*
G01X1166400Y538048D02*
X1166152Y537800D01*
G01X1166400Y546200D02*
Y538048D01*
G01X1166152Y546448D02*
X1166400Y546200D01*
G01X1166152Y549568D02*
Y546448D01*
G01X1166109Y549568D02*
X1166152D01*
G01X1164763Y550914D02*
X1166109Y549568D01*
G01X1179363Y587200D02*
X1177849Y588714D01*
G01X1179363Y584737D02*
Y587200D01*
G01X1180300Y583800D02*
X1179363Y584737D01*
G01X1180300Y576237D02*
Y583800D01*
G01X1179363Y575300D02*
X1180300Y576237D01*
G01X1179363Y573256D02*
Y575300D01*
G01X1179963Y572656D02*
X1179363Y573256D01*
G01X1179963Y568497D02*
Y572656D01*
G01X1179463Y567997D02*
X1179963Y568497D01*
G01X1179463Y566237D02*
Y567997D01*
G01X1179800Y565900D02*
X1179463Y566237D01*
G01X1179800Y557437D02*
Y565900D01*
G01X1179463Y557100D02*
X1179800Y557437D01*
G01X1179463Y555257D02*
Y557100D01*
G01X1179713Y555007D02*
X1179463Y555257D01*
G01X1179713Y548807D02*
Y555007D01*
G01X1179363Y548457D02*
X1179713Y548807D01*
G01X1179363Y535542D02*
Y548457D01*
G01X1179713Y535192D02*
X1179363Y535542D01*
G01X1179713Y530242D02*
Y535192D01*
G01X1179463Y529992D02*
X1179713Y530242D01*
G01X1179463Y528351D02*
Y529992D01*
G01X1180873Y526941D02*
X1179463Y528351D01*
G01X1213524Y586457D02*
X1210374Y589607D01*
G01X1213524Y573942D02*
Y586457D01*
G01X1212526Y572944D02*
X1213524Y573942D01*
G01X1212526Y568373D02*
Y572944D01*
G01X1213574Y567325D02*
X1212526Y568373D01*
G01X1213574Y555157D02*
Y567325D01*
G01X1212995Y554578D02*
X1213574Y555157D01*
G01X1212995Y549236D02*
Y554578D01*
G01X1213330Y548901D02*
X1212995Y549236D01*
G01X1213330Y535898D02*
Y548901D01*
G01X1212827Y535395D02*
X1213330Y535898D01*
G01X1212827Y530173D02*
Y535395D01*
G01X1213414Y529586D02*
X1212827Y530173D01*
G01X1197909Y593438D02*
X1198228Y593757D01*
G01X1197909Y588911D02*
Y593438D01*
G01X1196523Y605649D02*
X1201574Y610700D01*
G01X1196523Y595462D02*
Y605649D01*
G01X1198228Y593757D02*
X1196523Y595462D01*
G01X1166405D02*
X1168110Y593757D01*
G01X1166405Y605649D02*
Y595462D01*
G01X1171456Y610700D02*
X1166405Y605649D01*
G01X1216602Y607115D02*
X1219787Y610300D01*
G01X1216602Y595462D02*
Y607115D01*
G01X1218307Y593757D02*
X1216602Y595462D01*
G01X1216874Y592324D02*
X1218307Y593757D01*
G01X1216874Y589807D02*
Y592324D01*
G01X1220091Y586590D02*
X1216874Y589807D01*
G01X1182476Y604499D02*
X1181496D01*
G01X1183075Y603900D02*
X1182476Y604499D01*
G01X1183075Y602700D02*
Y603900D01*
G01X1182131Y601756D02*
X1183075Y602700D01*
G01X1182131Y600544D02*
Y601756D01*
G01X1182975Y599700D02*
X1182131Y600544D01*
G01X1182975Y598000D02*
Y599700D01*
G01X1182131Y597156D02*
X1182975Y598000D01*
G01X1182131Y595736D02*
Y597156D01*
G01X1183275Y594592D02*
X1182131Y595736D01*
G01X1183275Y592999D02*
Y594592D01*
G01X1182368Y592092D02*
X1183275Y592999D01*
G01X1182368Y590400D02*
Y592092D01*
G01X1184054Y588714D02*
X1182368Y590400D01*
G01X1184142Y588714D02*
X1184054D01*
G01X1184142Y588364D02*
Y588714D01*
G01X1182976Y610300D02*
X1184142D01*
G01X1179791Y607115D02*
X1182976Y610300D01*
G01X1179791Y595462D02*
Y607115D01*
G01X1181496Y593757D02*
X1179791Y595462D01*
G01X1180756Y593017D02*
X1181496Y593757D01*
G01X1180756Y589114D02*
Y593017D01*
G01X1219287Y604499D02*
X1218307D01*
G01X1205993D02*
X1204921D01*
G01X1206693Y603799D02*
X1205993Y604499D01*
G01X1206693Y602525D02*
Y603799D01*
G01X1205556Y601388D02*
X1206693Y602525D01*
G01X1205556Y600312D02*
Y601388D01*
G01X1206568Y599300D02*
X1205556Y600312D01*
G01X1206568Y598100D02*
Y599300D01*
G01X1205556Y597088D02*
X1206568Y598100D01*
G01X1205556Y596012D02*
Y597088D01*
G01X1206668Y594900D02*
X1205556Y596012D01*
G01X1206668Y592267D02*
Y594900D01*
G01X1206493Y592092D02*
X1206668Y592267D01*
G01X1206493Y590400D02*
Y592092D01*
G01X1208179Y588714D02*
X1206493Y590400D01*
G01X1208267Y588714D02*
X1208179D01*
G01X1208267Y588766D02*
Y588714D01*
G01X1203216Y605649D02*
X1208267Y610700D01*
G01X1203216Y595462D02*
Y605649D01*
G01X1204921Y593757D02*
X1203216Y595462D01*
G01X1203563Y592399D02*
X1204921Y593757D01*
G01X1203563Y589907D02*
Y592399D01*
G01X1212686Y604499D02*
X1211614D01*
G01X1213286Y603899D02*
X1212686Y604499D01*
G01X1213286Y603001D02*
Y603899D01*
G01X1212249Y601964D02*
X1213286Y603001D01*
G01X1212249Y600736D02*
Y601964D01*
G01X1213186Y599799D02*
X1212249Y600736D01*
G01X1213186Y598401D02*
Y599799D01*
G01X1212249Y597464D02*
X1213186Y598401D01*
G01X1212249Y596136D02*
Y597464D01*
G01X1213386Y594999D02*
X1212249Y596136D01*
G01X1213386Y593100D02*
Y594999D01*
G01X1212886Y592600D02*
X1213386Y593100D01*
G01X1212886Y590400D02*
Y592600D01*
G01X1214572Y588714D02*
X1212886Y590400D01*
G01X1214660Y588714D02*
X1214572D01*
G01X1176775Y610300D02*
X1177763D01*
G01X1173720Y607245D02*
X1176775Y610300D01*
G01X1173720Y606057D02*
Y607245D01*
G01X1173098Y605435D02*
X1173720Y606057D01*
G01X1173098Y595462D02*
Y605435D01*
G01X1174803Y593757D02*
X1173098Y595462D01*
G01X1173563Y592517D02*
X1174803Y593757D01*
G01X1173563Y588537D02*
Y592517D01*
G01X1164675Y588714D02*
X1164763D01*
G01X1162989Y590400D02*
X1164675Y588714D01*
G01X1162989Y592092D02*
Y590400D01*
G01X1163164Y592267D02*
X1162989Y592092D01*
G01X1163164Y594900D02*
Y592267D01*
G01X1162052Y596012D02*
X1163164Y594900D01*
G01X1162052Y597088D02*
Y596012D01*
G01X1163064Y598100D02*
X1162052Y597088D01*
G01X1163064Y599300D02*
Y598100D01*
G01X1162052Y600312D02*
X1163064Y599300D01*
G01X1162052Y601388D02*
Y600312D01*
G01X1163189Y602525D02*
X1162052Y601388D01*
G01X1163189Y603799D02*
Y602525D01*
G01X1162489Y604499D02*
X1163189Y603799D01*
G01X1161417Y604499D02*
X1162489D01*
G01X1199300D02*
X1198228D01*
G01X1200000Y603799D02*
X1199300Y604499D01*
G01X1200000Y602525D02*
Y603799D01*
G01X1198863Y601388D02*
X1200000Y602525D01*
G01X1198863Y600312D02*
Y601388D01*
G01X1199875Y599300D02*
X1198863Y600312D01*
G01X1199875Y598100D02*
Y599300D01*
G01X1198863Y597088D02*
X1199875Y598100D01*
G01X1198863Y596012D02*
Y597088D01*
G01X1199975Y594900D02*
X1198863Y596012D01*
G01X1199975Y592267D02*
Y594900D01*
G01X1199800Y592092D02*
X1199975Y592267D01*
G01X1199800Y590400D02*
Y592092D01*
G01X1201486Y588714D02*
X1199800Y590400D01*
G01X1201574Y588714D02*
X1201486D01*
G01X1171368D02*
X1171456D01*
G01X1169682Y590400D02*
X1171368Y588714D01*
G01X1169682Y592092D02*
Y590400D01*
G01X1169857Y592267D02*
X1169682Y592092D01*
G01X1169857Y594900D02*
Y592267D01*
G01X1168745Y596012D02*
X1169857Y594900D01*
G01X1168745Y597088D02*
Y596012D01*
G01X1169757Y598100D02*
X1168745Y597088D01*
G01X1169757Y599300D02*
Y598100D01*
G01X1168745Y600312D02*
X1169757Y599300D01*
G01X1168745Y601388D02*
Y600312D01*
G01X1169882Y602525D02*
X1168745Y601388D01*
G01X1169882Y603799D02*
Y602525D01*
G01X1169182Y604499D02*
X1169882Y603799D01*
G01X1168110Y604499D02*
X1169182D01*
G01X1175875D02*
X1174803D01*
G01X1176475Y603899D02*
X1175875Y604499D01*
G01X1176475Y603001D02*
Y603899D01*
G01X1175438Y601964D02*
X1176475Y603001D01*
G01X1175438Y600736D02*
Y601964D01*
G01X1176375Y599799D02*
X1175438Y600736D01*
G01X1176375Y598401D02*
Y599799D01*
G01X1175438Y597464D02*
X1176375Y598401D01*
G01X1175438Y596136D02*
Y597464D01*
G01X1176575Y594999D02*
X1175438Y596136D01*
G01X1176575Y593100D02*
Y594999D01*
G01X1176075Y592600D02*
X1176575Y593100D01*
G01X1176075Y590400D02*
Y592600D01*
G01X1177761Y588714D02*
X1176075Y590400D01*
G01X1177849Y588714D02*
X1177761D01*
G01X1213586Y610300D02*
X1214574D01*
G01X1210531Y607245D02*
X1213586Y610300D01*
G01X1210531Y606057D02*
Y607245D01*
G01X1209909Y605435D02*
X1210531Y606057D01*
G01X1209909Y595462D02*
Y605435D01*
G01X1211614Y593757D02*
X1209909Y595462D01*
G01X1210374Y592517D02*
X1211614Y593757D01*
G01X1210374Y589607D02*
Y592517D01*
G01X1159712Y595462D02*
X1161417Y593757D01*
G01X1159712Y605649D02*
Y595462D01*
G01X1164763Y610700D02*
X1159712Y605649D01*
G01X1221586Y-5900D02*
X1220186D01*
G01X1223042Y-4444D02*
X1221586Y-5900D01*
G01X1223042Y-3100D02*
Y-4444D01*
G01X1222426Y-2484D02*
X1223042Y-3100D01*
G01X1222426Y10641D02*
Y-2484D01*
G01X1220953Y12114D02*
X1222426Y10641D01*
G01X1218880Y14187D02*
X1220953Y12114D01*
G01X1218880Y15180D02*
Y14187D01*
G01X1220374Y16674D02*
X1218880Y15180D01*
G01X1220374Y23173D02*
Y16674D01*
G01X1222874Y25673D02*
X1220374Y23173D01*
G01X1222874Y37200D02*
Y25673D01*
G01X1242979Y-8654D02*
X1241732Y-9901D01*
G01X1242979Y-7400D02*
Y-8654D01*
G01X1244279Y-6100D02*
X1242979Y-7400D01*
G01X1245279Y-6100D02*
X1244279D01*
G01X1247079Y-4300D02*
X1245279Y-6100D01*
G01X1247079Y-2900D02*
Y-4300D01*
G01X1246467Y-2288D02*
X1247079Y-2900D01*
G01X1246467Y10725D02*
Y-2288D01*
G01X1245078Y12114D02*
X1246467Y10725D01*
G01X1243174Y14018D02*
X1245078Y12114D01*
G01X1243174Y15614D02*
Y14018D01*
G01X1246524Y18964D02*
X1243174Y15614D01*
G01X1246524Y28699D02*
Y18964D01*
G01X1247074Y29249D02*
X1246524Y28699D01*
G01X1247074Y34627D02*
Y29249D01*
G01X1236286Y-8654D02*
X1235039Y-9901D01*
G01X1236286Y-7400D02*
Y-8654D01*
G01X1237586Y-6100D02*
X1236286Y-7400D01*
G01X1238586Y-6100D02*
X1237586D01*
G01X1240386Y-4300D02*
X1238586Y-6100D01*
G01X1240386Y-2900D02*
Y-4300D01*
G01X1239774Y-2288D02*
X1240386Y-2900D01*
G01X1239774Y10725D02*
Y-2288D01*
G01X1238385Y12114D02*
X1239774Y10725D01*
G01X1236481Y14018D02*
X1238385Y12114D01*
G01X1236481Y15614D02*
Y14018D01*
G01X1239831Y18964D02*
X1236481Y15614D01*
G01X1239831Y28699D02*
Y18964D01*
G01X1240381Y29249D02*
X1239831Y28699D01*
G01X1240381Y34627D02*
Y29249D01*
G01X1243511Y-2133D02*
X1245078Y-3700D01*
G01X1243511Y-932D02*
Y-2133D01*
G01X1242153Y426D02*
X1243511Y-932D01*
G01X1242153Y1799D02*
Y426D01*
G01X1243353Y2999D02*
X1242153Y1799D01*
G01X1243353Y4125D02*
Y2999D01*
G01X1242153Y5325D02*
X1243353Y4125D01*
G01X1242153Y6900D02*
Y5325D01*
G01X1243953Y8700D02*
X1242153Y6900D01*
G01X1243953Y9758D02*
Y8700D01*
G01X1240611Y13100D02*
X1243953Y9758D01*
G01X1240611Y16036D02*
Y13100D01*
G01X1241732Y17157D02*
X1240611Y16036D01*
G01X1243974Y19399D02*
X1241732Y17157D01*
G01X1243974Y28199D02*
Y19399D01*
G01X1243174Y28999D02*
X1243974Y28199D01*
G01X1243174Y34675D02*
Y28999D01*
G01X1236911Y-2226D02*
X1238385Y-3700D01*
G01X1236911Y-1132D02*
Y-2226D01*
G01X1235478Y301D02*
X1236911Y-1132D01*
G01X1235478Y1524D02*
Y301D01*
G01X1236978Y3024D02*
X1235478Y1524D01*
G01X1236978Y4376D02*
Y3024D01*
G01X1235478Y5876D02*
X1236978Y4376D01*
G01X1235478Y6999D02*
Y5876D01*
G01X1237153Y8674D02*
X1235478Y6999D01*
G01X1237153Y10059D02*
Y8674D01*
G01X1234111Y13101D02*
X1237153Y10059D01*
G01X1234111Y16229D02*
Y13101D01*
G01X1235039Y17157D02*
X1234111Y16229D01*
G01X1237074Y19192D02*
X1235039Y17157D01*
G01X1237074Y28499D02*
Y19192D01*
G01X1236474Y29099D02*
X1237074Y28499D01*
G01X1236474Y34601D02*
Y29099D01*
G01X1220086Y-3233D02*
X1220953Y-4100D01*
G01X1220086Y-932D02*
Y-3233D01*
G01X1219803Y4250D02*
Y3350D01*
G01X1220086Y10200D02*
Y8232D01*
G01X1220200Y28418D02*
Y26799D01*
G01X1219024Y29594D02*
X1220200Y28418D01*
G01X1219024Y34183D02*
Y29594D01*
G01X1223600Y37926D02*
X1222874Y37200D01*
G01X1223600Y45300D02*
Y37926D01*
G01X1222874Y46026D02*
X1223600Y45300D01*
G01X1222874Y74700D02*
Y46026D01*
G01X1223800Y75626D02*
X1222874Y74700D01*
G01X1223800Y83101D02*
Y75626D01*
G01X1222874Y84027D02*
X1223800Y83101D01*
G01X1222874Y102126D02*
Y84027D01*
G01X1246474Y35227D02*
X1247074Y34627D01*
G01X1246474Y36900D02*
Y35227D01*
G01X1247300Y37726D02*
X1246474Y36900D01*
G01X1247300Y45400D02*
Y37726D01*
G01X1246474Y46226D02*
X1247300Y45400D01*
G01X1246474Y47938D02*
Y46226D01*
G01X1247174Y48638D02*
X1246474Y47938D01*
G01X1247174Y53214D02*
Y48638D01*
G01X1246524Y53864D02*
X1247174Y53214D01*
G01X1246524Y66499D02*
Y53864D01*
G01X1247074Y67049D02*
X1246524Y66499D01*
G01X1247074Y72527D02*
Y67049D01*
G01X1246474Y73127D02*
X1247074Y72527D01*
G01X1246474Y74874D02*
Y73127D01*
G01X1247000Y75400D02*
X1246474Y74874D01*
G01X1247000Y83574D02*
Y75400D01*
G01X1246474Y84100D02*
X1247000Y83574D01*
G01X1246474Y85914D02*
Y84100D01*
G01X1247174Y86614D02*
X1246474Y85914D01*
G01X1247174Y91274D02*
Y86614D01*
G01X1246574Y91874D02*
X1247174Y91274D01*
G01X1246574Y93674D02*
Y91874D01*
G01X1248400Y95500D02*
X1246574Y93674D01*
G01X1239781Y35227D02*
X1240381Y34627D01*
G01X1239781Y36900D02*
Y35227D01*
G01X1240607Y37726D02*
X1239781Y36900D01*
G01X1240607Y45400D02*
Y37726D01*
G01X1239781Y46226D02*
X1240607Y45400D01*
G01X1239781Y47938D02*
Y46226D01*
G01X1240481Y48638D02*
X1239781Y47938D01*
G01X1240481Y53214D02*
Y48638D01*
G01X1239831Y53864D02*
X1240481Y53214D01*
G01X1239831Y66499D02*
Y53864D01*
G01X1240381Y67049D02*
X1239831Y66499D01*
G01X1240381Y72527D02*
Y67049D01*
G01X1239781Y73127D02*
X1240381Y72527D01*
G01X1239781Y74874D02*
Y73127D01*
G01X1240307Y75400D02*
X1239781Y74874D01*
G01X1240307Y83574D02*
Y75400D01*
G01X1239781Y84100D02*
X1240307Y83574D01*
G01X1239781Y85914D02*
Y84100D01*
G01X1240481Y86614D02*
X1239781Y85914D01*
G01X1240481Y91274D02*
Y86614D01*
G01X1239881Y91874D02*
X1240481Y91274D01*
G01X1239881Y93674D02*
Y91874D01*
G01X1240600Y94393D02*
X1239881Y93674D01*
G01X1240600Y119699D02*
Y94393D01*
G01X1243674Y35175D02*
X1243174Y34675D01*
G01X1243674Y37100D02*
Y35175D01*
G01X1243200Y37574D02*
X1243674Y37100D01*
G01X1243200Y45700D02*
Y37574D01*
G01X1243674Y46174D02*
X1243200Y45700D01*
G01X1243674Y47774D02*
Y46174D01*
G01X1243074Y48374D02*
X1243674Y47774D01*
G01X1243074Y53314D02*
Y48374D01*
G01X1244024Y54264D02*
X1243074Y53314D01*
G01X1244024Y66225D02*
Y54264D01*
G01X1243174Y67075D02*
X1244024Y66225D01*
G01X1243174Y72675D02*
Y67075D01*
G01X1243674Y73175D02*
X1243174Y72675D01*
G01X1243674Y74626D02*
Y73175D01*
G01X1243200Y75100D02*
X1243674Y74626D01*
G01X1243200Y83626D02*
Y75100D01*
G01X1243674Y84100D02*
X1243200Y83626D01*
G01X1243674Y85814D02*
Y84100D01*
G01X1243074Y86414D02*
X1243674Y85814D01*
G01X1243074Y91238D02*
Y86414D01*
G01X1244074Y92238D02*
X1243074Y91238D01*
G01X1244074Y94574D02*
Y92238D01*
G01X1243100Y95548D02*
X1244074Y94574D01*
G01X1237274Y35401D02*
X1236474Y34601D01*
G01X1237274Y36826D02*
Y35401D01*
G01X1236500Y37600D02*
X1237274Y36826D01*
G01X1236500Y45626D02*
Y37600D01*
G01X1237274Y46400D02*
X1236500Y45626D01*
G01X1237274Y47914D02*
Y46400D01*
G01X1236474Y48714D02*
X1237274Y47914D01*
G01X1236474Y53414D02*
Y48714D01*
G01X1236874Y53814D02*
X1236474Y53414D01*
G01X1236874Y66575D02*
Y53814D01*
G01X1236474Y66975D02*
X1236874Y66575D01*
G01X1236474Y72575D02*
Y66975D01*
G01X1237274Y73375D02*
X1236474Y72575D01*
G01X1237274Y74926D02*
Y73375D01*
G01X1236700Y75500D02*
X1237274Y74926D01*
G01X1236700Y83526D02*
Y75500D01*
G01X1237274Y84100D02*
X1236700Y83526D01*
G01X1237274Y85714D02*
Y84100D01*
G01X1236474Y86514D02*
X1237274Y85714D01*
G01X1236474Y91214D02*
Y86514D01*
G01X1236874Y91614D02*
X1236474Y91214D01*
G01X1236874Y100827D02*
Y91614D01*
G01X1220200Y35359D02*
X1219024Y34183D01*
G01X1220200Y36900D02*
Y35359D01*
G01X1218900Y38200D02*
X1220200Y36900D01*
G01X1218900Y39000D02*
Y38200D01*
G01X1219800Y39900D02*
X1218900Y39000D01*
G01X1219800Y41734D02*
Y39900D01*
G01X1219100Y42434D02*
X1219800Y41734D01*
G01X1219100Y44734D02*
Y42434D01*
G01X1220200Y45834D02*
X1219100Y44734D01*
G01X1220200Y47738D02*
Y45834D01*
G01X1219024Y48914D02*
X1220200Y47738D01*
G01X1219024Y52788D02*
Y48914D01*
G01X1219248Y53012D02*
X1219024Y52788D01*
G01X1219248Y53321D02*
Y53012D01*
G01X1220200Y54273D02*
X1219248Y53321D01*
G01X1220200Y66218D02*
Y54273D01*
G01X1219024Y67394D02*
X1220200Y66218D01*
G01X1219024Y72123D02*
Y67394D01*
G01X1220200Y73299D02*
X1219024Y72123D01*
G01X1220200Y74700D02*
Y73299D01*
G01X1219400Y75500D02*
X1220200Y74700D01*
G01X1219400Y83299D02*
Y75500D01*
G01X1220200Y84099D02*
X1219400Y83299D01*
G01X1220200Y85248D02*
Y84099D01*
G01X1219100Y86348D02*
X1220200Y85248D01*
G01X1219100Y91100D02*
Y86348D01*
G01X1220107Y92107D02*
X1219100Y91100D01*
G01X1220107Y101492D02*
Y92107D01*
G01X1221892Y103108D02*
X1222874Y102126D01*
G01X1221892Y121941D02*
Y103108D01*
G01X1248400Y118600D02*
Y95500D01*
G01X1243100Y97205D02*
Y95548D01*
G01X1243660Y97765D02*
X1243100Y97205D01*
G01X1245040Y97765D02*
X1243660D01*
G01X1245600Y98325D02*
X1245040Y97765D01*
G01X1245600Y99765D02*
Y98325D01*
G01X1245040Y100325D02*
X1245600Y99765D01*
G01X1243660Y100325D02*
X1245040D01*
G01X1243100Y100885D02*
X1243660Y100325D01*
G01X1243100Y102325D02*
Y100885D01*
G01X1243660Y102885D02*
X1243100Y102325D01*
G01X1245040Y102885D02*
X1243660D01*
G01X1245600Y103445D02*
X1245040Y102885D01*
G01X1245600Y104885D02*
Y103445D01*
G01X1245040Y105445D02*
X1245600Y104885D01*
G01X1243660Y105445D02*
X1245040D01*
G01X1243100Y106005D02*
X1243660Y105445D01*
G01X1243100Y107445D02*
Y106005D01*
G01X1243660Y108005D02*
X1243100Y107445D01*
G01X1245040Y108005D02*
X1243660D01*
G01X1245600Y108565D02*
X1245040Y108005D01*
G01X1245600Y110005D02*
Y108565D01*
G01X1245040Y110565D02*
X1245600Y110005D01*
G01X1243660Y110565D02*
X1245040D01*
G01X1243100Y111125D02*
X1243660Y110565D01*
G01X1243100Y120400D02*
Y111125D01*
G01X1235574Y102127D02*
X1236874Y100827D01*
G01X1235574Y104657D02*
Y102127D01*
G01X1236134Y105217D02*
X1235574Y104657D01*
G01X1238040Y105217D02*
X1236134D01*
G01X1238600Y105777D02*
X1238040Y105217D01*
G01X1238600Y107217D02*
Y105777D01*
G01X1238040Y107777D02*
X1238600Y107217D01*
G01X1236134Y107777D02*
X1238040D01*
G01X1235574Y108337D02*
X1236134Y107777D01*
G01X1235574Y109777D02*
Y108337D01*
G01X1236134Y110337D02*
X1235574Y109777D01*
G01X1238040Y110337D02*
X1236134D01*
G01X1238600Y110897D02*
X1238040Y110337D01*
G01X1238600Y112337D02*
Y110897D01*
G01X1238040Y112897D02*
X1238600Y112337D01*
G01X1236134Y112897D02*
X1238040D01*
G01X1235574Y113457D02*
X1236134Y112897D01*
G01X1235574Y114897D02*
Y113457D01*
G01X1236134Y115457D02*
X1235574Y114897D01*
G01X1238040Y115457D02*
X1236134D01*
G01X1238600Y116017D02*
X1238040Y115457D01*
G01X1238600Y117457D02*
Y116017D01*
G01X1238040Y118017D02*
X1238600Y117457D01*
G01X1236134Y118017D02*
X1238040D01*
G01X1235574Y118577D02*
X1236134Y118017D01*
G01X1235574Y121626D02*
Y118577D01*
G01X1219392Y102207D02*
X1220107Y101492D01*
G01X1219392Y121409D02*
Y102207D01*
G01X1220035Y517318D02*
Y529606D01*
G01X1219024Y516307D02*
X1220035Y517318D01*
G01X1219024Y512057D02*
Y516307D01*
G01X1220147Y510934D02*
X1219024Y512057D01*
G01X1220147Y486359D02*
Y510934D01*
G01X1223300Y519526D02*
Y528100D01*
G01X1222874Y519100D02*
X1223300Y519526D01*
G01X1222874Y509326D02*
Y519100D01*
G01X1223400Y508800D02*
X1222874Y509326D01*
G01X1223400Y501000D02*
Y508800D01*
G01X1222874Y500474D02*
X1223400Y501000D01*
G01X1222874Y485290D02*
Y500474D01*
G01X1236700Y519774D02*
Y527700D01*
G01X1236874Y519600D02*
X1236700Y519774D01*
G01X1236874Y517357D02*
Y519600D01*
G01X1236474Y516957D02*
X1236874Y517357D01*
G01X1236474Y512057D02*
Y516957D01*
G01X1237274Y511257D02*
X1236474Y512057D01*
G01X1237274Y509674D02*
Y511257D01*
G01X1235541Y507941D02*
X1237274Y509674D01*
G01X1235541Y484601D02*
Y507941D01*
G01X1240100Y519526D02*
Y527700D01*
G01X1239874Y519300D02*
X1240100Y519526D01*
G01X1239874Y517357D02*
Y519300D01*
G01X1240674Y516557D02*
X1239874Y517357D01*
G01X1240674Y512157D02*
Y516557D01*
G01X1239774Y511257D02*
X1240674Y512157D01*
G01X1239774Y509200D02*
Y511257D01*
G01X1240766Y508208D02*
X1239774Y509200D01*
G01X1240766Y507004D02*
Y508208D01*
G01X1240156Y506394D02*
X1240766Y507004D01*
G01X1238272Y506394D02*
X1240156D01*
G01X1237606Y505728D02*
X1238272Y506394D01*
G01X1237606Y503748D02*
Y505728D01*
G01X1238160Y503194D02*
X1237606Y503748D01*
G01X1240743Y503194D02*
X1238160D01*
G01X1241353Y502584D02*
X1240743Y503194D01*
G01X1241353Y500604D02*
Y502584D01*
G01X1240743Y499994D02*
X1241353Y500604D01*
G01X1238133Y499994D02*
X1240743D01*
G01X1237523Y499384D02*
X1238133Y499994D01*
G01X1237523Y497404D02*
Y499384D01*
G01X1238133Y496794D02*
X1237523Y497404D01*
G01X1240156Y496794D02*
X1238133D01*
G01X1240766Y496184D02*
X1240156Y496794D01*
G01X1240766Y494893D02*
Y496184D01*
G01X1238074Y492201D02*
X1240766Y494893D01*
G01X1238074Y483950D02*
Y492201D01*
G01X1244063Y517562D02*
Y529377D01*
G01X1242900Y516399D02*
X1244063Y517562D01*
G01X1242900Y511931D02*
Y516399D01*
G01X1243674Y511157D02*
X1242900Y511931D01*
G01X1243674Y494174D02*
Y511157D01*
G01X1240574Y491074D02*
X1243674Y494174D01*
G01X1240574Y483434D02*
Y491074D01*
G01X1246524Y517357D02*
Y529816D01*
G01X1247074Y516807D02*
X1246524Y517357D01*
G01X1247074Y511973D02*
Y516807D01*
G01X1246474Y511373D02*
X1247074Y511973D01*
G01X1246474Y509326D02*
Y511373D01*
G01X1245821Y508673D02*
X1246474Y509326D01*
G01X1245821Y491101D02*
Y508673D01*
G01X1245320Y490600D02*
X1245821Y491101D01*
G01X1243500Y490600D02*
X1245320D01*
G01X1242700Y489800D02*
X1243500Y490600D01*
G01X1242700Y488200D02*
Y489800D01*
G01X1243200Y487700D02*
X1242700Y488200D01*
G01X1245421Y487700D02*
X1243200D01*
G01X1245821Y487300D02*
X1245421Y487700D01*
G01X1245821Y485774D02*
Y487300D01*
G01X1220091Y574090D02*
Y586590D01*
G01X1219197Y573196D02*
X1220091Y574090D01*
G01X1219197Y568244D02*
Y573196D01*
G01X1220063Y567378D02*
X1219197Y568244D01*
G01X1220063Y555146D02*
Y567378D01*
G01X1219024Y554107D02*
X1220063Y555146D01*
G01X1219024Y549857D02*
Y554107D01*
G01X1220091Y548790D02*
X1219024Y549857D01*
G01X1220091Y536291D02*
Y548790D01*
G01X1219141Y535341D02*
X1220091Y536291D01*
G01X1219141Y530500D02*
Y535341D01*
G01X1220035Y529606D02*
X1219141Y530500D01*
G01X1222874Y586443D02*
X1220953Y588364D01*
G01X1222874Y584426D02*
Y586443D01*
G01X1223300Y584000D02*
X1222874Y584426D01*
G01X1223300Y575926D02*
Y584000D01*
G01X1222874Y575500D02*
X1223300Y575926D01*
G01X1222874Y566026D02*
Y575500D01*
G01X1223300Y565600D02*
X1222874Y566026D01*
G01X1223300Y557000D02*
Y565600D01*
G01X1222874Y556574D02*
X1223300Y557000D01*
G01X1222874Y546726D02*
Y556574D01*
G01X1223400Y546200D02*
X1222874Y546726D01*
G01X1223400Y538226D02*
Y546200D01*
G01X1222874Y537700D02*
X1223400Y538226D01*
G01X1222874Y528526D02*
Y537700D01*
G01X1223300Y528100D02*
X1222874Y528526D01*
G01X1237649Y585982D02*
X1234374Y589257D01*
G01X1237649Y584849D02*
Y585982D01*
G01X1236700Y583900D02*
X1237649Y584849D01*
G01X1236700Y575974D02*
Y583900D01*
G01X1237274Y575400D02*
X1236700Y575974D01*
G01X1237274Y574474D02*
Y575400D01*
G01X1236001Y573201D02*
X1237274Y574474D01*
G01X1236001Y568470D02*
Y573201D01*
G01X1237219Y567252D02*
X1236001Y568470D01*
G01X1237219Y566119D02*
Y567252D01*
G01X1236700Y565600D02*
X1237219Y566119D01*
G01X1236700Y557174D02*
Y565600D01*
G01X1237421Y556453D02*
X1236700Y557174D01*
G01X1237421Y555320D02*
Y556453D01*
G01X1236200Y554099D02*
X1237421Y555320D01*
G01X1236200Y550131D02*
Y554099D01*
G01X1237274Y549057D02*
X1236200Y550131D01*
G01X1237274Y546874D02*
Y549057D01*
G01X1236700Y546300D02*
X1237274Y546874D01*
G01X1236700Y538600D02*
Y546300D01*
G01X1237274Y538026D02*
X1236700Y538600D01*
G01X1237274Y536474D02*
Y538026D01*
G01X1236474Y535674D02*
X1237274Y536474D01*
G01X1236474Y530242D02*
Y535674D01*
G01X1236874Y529842D02*
X1236474Y530242D01*
G01X1236874Y527874D02*
Y529842D01*
G01X1236700Y527700D02*
X1236874Y527874D01*
G01X1239731Y587368D02*
X1238385Y588714D01*
G01X1239774Y587368D02*
X1239731D01*
G01X1239774Y584326D02*
Y587368D01*
G01X1240100Y584000D02*
X1239774Y584326D01*
G01X1240100Y575826D02*
Y584000D01*
G01X1239774Y575500D02*
X1240100Y575826D01*
G01X1239774Y574127D02*
Y575500D01*
G01X1240440Y573461D02*
X1239774Y574127D01*
G01X1240440Y568163D02*
Y573461D01*
G01X1239874Y567597D02*
X1240440Y568163D01*
G01X1239874Y565626D02*
Y567597D01*
G01X1240100Y565400D02*
X1239874Y565626D01*
G01X1240100Y557926D02*
Y565400D01*
G01X1239400Y557226D02*
X1240100Y557926D01*
G01X1239400Y555199D02*
Y557226D01*
G01X1240674Y553925D02*
X1239400Y555199D01*
G01X1240674Y549957D02*
Y553925D01*
G01X1239400Y548683D02*
X1240674Y549957D01*
G01X1239400Y547000D02*
Y548683D01*
G01X1240100Y546300D02*
X1239400Y547000D01*
G01X1240100Y539000D02*
Y546300D01*
G01X1239461Y538361D02*
X1240100Y539000D01*
G01X1239461Y536436D02*
Y538361D01*
G01X1240574Y535323D02*
X1239461Y536436D01*
G01X1240574Y530542D02*
Y535323D01*
G01X1239874Y529842D02*
X1240574Y530542D01*
G01X1239874Y527926D02*
Y529842D01*
G01X1240100Y527700D02*
X1239874Y527926D01*
G01X1243642Y586639D02*
X1241296Y588985D01*
G01X1243642Y573910D02*
Y586639D01*
G01X1242748Y573016D02*
X1243642Y573910D01*
G01X1242748Y568523D02*
Y573016D01*
G01X1243809Y567462D02*
X1242748Y568523D01*
G01X1243809Y555492D02*
Y567462D01*
G01X1242861Y554544D02*
X1243809Y555492D01*
G01X1242861Y549770D02*
Y554544D01*
G01X1243895Y548736D02*
X1242861Y549770D01*
G01X1243895Y536329D02*
Y548736D01*
G01X1242750Y535184D02*
X1243895Y536329D01*
G01X1242750Y530690D02*
Y535184D01*
G01X1244063Y529377D02*
X1242750Y530690D01*
G01X1246374Y587470D02*
X1245078Y588766D01*
G01X1246374Y574226D02*
Y587470D01*
G01X1247374Y573226D02*
X1246374Y574226D01*
G01X1247374Y568497D02*
Y573226D01*
G01X1246524Y567647D02*
X1247374Y568497D01*
G01X1246524Y555157D02*
Y567647D01*
G01X1247074Y554607D02*
X1246524Y555157D01*
G01X1247074Y550057D02*
Y554607D01*
G01X1246474Y549457D02*
X1247074Y550057D01*
G01X1246474Y536226D02*
Y549457D01*
G01X1247174Y535526D02*
X1246474Y536226D01*
G01X1247174Y530466D02*
Y535526D01*
G01X1246524Y529816D02*
X1247174Y530466D01*
G01X1219787Y610300D02*
X1220953D01*
G01X1219886Y603900D02*
X1219287Y604499D01*
G01X1219886Y602700D02*
Y603900D01*
G01X1218942Y601756D02*
X1219886Y602700D01*
G01X1218942Y600544D02*
Y601756D01*
G01X1219786Y599700D02*
X1218942Y600544D01*
G01X1219786Y598000D02*
Y599700D01*
G01X1218942Y597156D02*
X1219786Y598000D01*
G01X1218942Y595736D02*
Y597156D01*
G01X1220086Y594592D02*
X1218942Y595736D01*
G01X1220086Y592999D02*
Y594592D01*
G01X1219179Y592092D02*
X1220086Y592999D01*
G01X1219179Y590400D02*
Y592092D01*
G01X1220865Y588714D02*
X1219179Y590400D01*
G01X1220953Y588714D02*
X1220865D01*
G01X1220953Y588364D02*
Y588714D01*
G01X1233334Y605649D02*
X1238385Y610700D01*
G01X1233334Y595462D02*
Y605649D01*
G01X1235039Y593757D02*
X1233334Y595462D01*
G01X1234374Y593092D02*
X1235039Y593757D01*
G01X1234374Y589257D02*
Y593092D01*
G01X1236111Y604499D02*
X1235039D01*
G01X1236811Y603799D02*
X1236111Y604499D01*
G01X1236811Y602525D02*
Y603799D01*
G01X1235674Y601388D02*
X1236811Y602525D01*
G01X1235674Y600312D02*
Y601388D01*
G01X1236686Y599300D02*
X1235674Y600312D01*
G01X1236686Y598100D02*
Y599300D01*
G01X1235674Y597088D02*
X1236686Y598100D01*
G01X1235674Y596012D02*
Y597088D01*
G01X1236786Y594900D02*
X1235674Y596012D01*
G01X1236786Y592267D02*
Y594900D01*
G01X1236611Y592092D02*
X1236786Y592267D01*
G01X1236611Y590400D02*
Y592092D01*
G01X1238297Y588714D02*
X1236611Y590400D01*
G01X1238385Y588714D02*
X1238297D01*
G01X1241296Y593321D02*
X1241732Y593757D01*
G01X1241296Y588985D02*
Y593321D01*
G01X1240027Y605649D02*
X1245078Y610700D01*
G01X1240027Y595462D02*
Y605649D01*
G01X1241732Y593757D02*
X1240027Y595462D01*
G01X1242804Y604499D02*
X1241732D01*
G01X1243504Y603799D02*
X1242804Y604499D01*
G01X1243504Y602525D02*
Y603799D01*
G01X1242367Y601388D02*
X1243504Y602525D01*
G01X1242367Y600312D02*
Y601388D01*
G01X1243379Y599300D02*
X1242367Y600312D01*
G01X1243379Y598100D02*
Y599300D01*
G01X1242367Y597088D02*
X1243379Y598100D01*
G01X1242367Y596012D02*
Y597088D01*
G01X1243479Y594900D02*
X1242367Y596012D01*
G01X1243479Y592267D02*
Y594900D01*
G01X1243304Y592092D02*
X1243479Y592267D01*
G01X1243304Y590400D02*
Y592092D01*
G01X1244990Y588714D02*
X1243304Y590400D01*
G01X1245078Y588714D02*
X1244990D01*
G01X1245078Y588766D02*
Y588714D01*
M02*
